(kicad_pcb
	(version 20241229)
	(generator "pcbnew")
	(generator_version "9.0")
	(general
		(thickness 1.711)
		(legacy_teardrops no)
	)
	(paper "A4")
	(title_block
		(title "Antmicro Baseboard for Jetson AGX Thor")
		(date "2026-02-18")
		(rev "1.1.0")
		(company "Antmicro Ltd")
		(comment 1 "www.antmicro.com")
	)
	(layers
		(0 "F.Cu" signal)
		(4 "In1.Cu" signal)
		(6 "In2.Cu" signal)
		(8 "In3.Cu" signal)
		(10 "In4.Cu" jumper)
		(12 "In5.Cu" signal)
		(14 "In6.Cu" signal)
		(16 "In7.Cu" signal)
		(18 "In8.Cu" signal)
		(2 "B.Cu" signal)
		(9 "F.Adhes" user "F.Adhesive")
		(11 "B.Adhes" user "B.Adhesive")
		(13 "F.Paste" user)
		(15 "B.Paste" user)
		(5 "F.SilkS" user "F.Silkscreen")
		(7 "B.SilkS" user "B.Silkscreen")
		(1 "F.Mask" user)
		(3 "B.Mask" user)
		(17 "Dwgs.User" user "User.Drawings")
		(19 "Cmts.User" user "User.Comments")
		(21 "Eco1.User" user "User.Eco1")
		(23 "Eco2.User" user "User.Eco2")
		(25 "Edge.Cuts" user)
		(27 "Margin" user)
		(31 "F.CrtYd" user "F.Courtyard")
		(29 "B.CrtYd" user "B.Courtyard")
		(35 "F.Fab" user)
		(33 "B.Fab" user)
	)
	(setup
		(stackup
			(layer "F.SilkS"
				(type "Top Silk Screen")
				(color "White")
			)
			(layer "F.Paste"
				(type "Top Solder Paste")
			)
			(layer "F.Mask"
				(type "Top Solder Mask")
				(color "Black")
				(thickness 0.01)
			)
			(layer "F.Cu"
				(type "copper")
				(thickness 0.035)
			)
			(layer "dielectric 1"
				(type "prepreg")
				(thickness 0.12)
				(material "PR2116")
				(epsilon_r 4.1)
				(loss_tangent 0.02)
			)
			(layer "In1.Cu"
				(type "copper")
				(thickness 0.018)
			)
			(layer "dielectric 2"
				(type "core")
				(thickness 0.2)
				(material "FR4")
				(epsilon_r 4.3)
				(loss_tangent 0.02)
			)
			(layer "In2.Cu"
				(type "copper")
				(thickness 0.018)
			)
			(layer "dielectric 3"
				(type "prepreg")
				(thickness 0.07)
				(material "PR1080")
				(epsilon_r 3.96)
				(loss_tangent 0.02) addsublayer
				(thickness 0.07)
				(material "PR1080")
				(epsilon_r 3.96)
				(loss_tangent 0)
			)
			(layer "In3.Cu"
				(type "copper")
				(thickness 0.018)
			)
			(layer "dielectric 4"
				(type "core")
				(thickness 0.2)
				(material "FR4")
				(epsilon_r 4.3)
				(loss_tangent 0.02)
			)
			(layer "In4.Cu"
				(type "copper")
				(thickness 0.018)
			)
			(layer "dielectric 5"
				(type "prepreg")
				(thickness 0.07)
				(material "PR1080")
				(epsilon_r 3.96)
				(loss_tangent 0.02) addsublayer
				(thickness 0.07)
				(material "PR1080")
				(epsilon_r 3.96)
				(loss_tangent 0)
			)
			(layer "In5.Cu"
				(type "copper")
				(thickness 0.018)
			)
			(layer "dielectric 6"
				(type "core")
				(thickness 0.2)
				(material "FR4")
				(epsilon_r 4.3)
				(loss_tangent 0.02)
			)
			(layer "In6.Cu"
				(type "copper")
				(thickness 0.035)
			)
			(layer "dielectric 7"
				(type "prepreg")
				(thickness 0.07)
				(material "PR1080")
				(epsilon_r 3.96)
				(loss_tangent 0.02) addsublayer
				(thickness 0.07)
				(material "PR1080")
				(epsilon_r 3.96)
				(loss_tangent 0)
			)
			(layer "In7.Cu"
				(type "copper")
				(thickness 0.018)
			)
			(layer "dielectric 8"
				(type "core")
				(thickness 0.2)
				(material "FR4")
				(epsilon_r 4.3)
				(loss_tangent 0.02)
			)
			(layer "In8.Cu"
				(type "copper")
				(thickness 0.018)
			)
			(layer "dielectric 9"
				(type "prepreg")
				(thickness 0.12)
				(material "PR2116")
				(epsilon_r 4.1)
				(loss_tangent 0.02)
			)
			(layer "B.Cu"
				(type "copper")
				(thickness 0.035)
			)
			(layer "B.Mask"
				(type "Bottom Solder Mask")
				(color "Black")
				(thickness 0.01)
			)
			(layer "B.Paste"
				(type "Bottom Solder Paste")
			)
			(layer "B.SilkS"
				(type "Bottom Silk Screen")
				(color "White")
			)
			(copper_finish "ENIG")
			(dielectric_constraints no)
		)
		(pad_to_mask_clearance 0)
		(allow_soldermask_bridges_in_footprints no)
		(tenting front back)
		(pcbplotparams
			(layerselection 0x00000000_00000000_55555555_5755f5ff)
			(plot_on_all_layers_selection 0x00000000_00000000_00000000_00000000)
			(disableapertmacros no)
			(usegerberextensions no)
			(usegerberattributes yes)
			(usegerberadvancedattributes yes)
			(creategerberjobfile yes)
			(dashed_line_dash_ratio 12.000000)
			(dashed_line_gap_ratio 3.000000)
			(svgprecision 4)
			(plotframeref no)
			(mode 1)
			(useauxorigin no)
			(hpglpennumber 1)
			(hpglpenspeed 20)
			(hpglpendiameter 15.000000)
			(pdf_front_fp_property_popups yes)
			(pdf_back_fp_property_popups yes)
			(pdf_metadata yes)
			(pdf_single_document no)
			(dxfpolygonmode yes)
			(dxfimperialunits yes)
			(dxfusepcbnewfont yes)
			(psnegative no)
			(psa4output no)
			(plot_black_and_white yes)
			(sketchpadsonfab no)
			(plotpadnumbers no)
			(hidednponfab no)
			(sketchdnponfab yes)
			(crossoutdnponfab yes)
			(subtractmaskfromsilk no)
			(outputformat 1)
			(mirror no)
			(drillshape 1)
			(scaleselection 1)
			(outputdirectory "")
		)
	)
	(net 0 "")
	(net 1 "GND")
	(net 2 "+3V3")
	(net 3 "VCC_IN")
	(net 4 "+3V3_AON")
	(net 5 "+5V")
	(net 6 "/CSI/CSIA_3V3")
	(net 7 "/CSI/CSIA_5V")
	(net 8 "/CSI/CSIB_3V3")
	(net 9 "/CSI/CSIB_5V")
	(net 10 "Net-(BT1-+)")
	(net 11 "+1V8")
	(net 12 "SYS_VIN_HV")
	(net 13 "VCC")
	(net 14 "/M.2/3V3_M2")
	(net 15 "/M.2/PCIe_{C1x1}.TX0+")
	(net 16 "/M.2/PCIe_{C1x1}.TX0-")
	(net 17 "/DCDC/1V8_OUT")
	(net 18 "/DCDC/5V_VDD")
	(net 19 "/DCDC/3V3_VDD")
	(net 20 "/DCDC/12V_VDD")
	(net 21 "/SFP/SFI_CONN_TX_P")
	(net 22 "/SFP/SFI_CONN_TX_N")
	(net 23 "/DCDC/5V_VDRV")
	(net 24 "/DCDC/3V3_VDRV")
	(net 25 "/DCDC/5V_BOOT")
	(net 26 "/DCDC/5V_PHASE")
	(net 27 "/SFP/SFI_CONN_RX_P")
	(net 28 "/DCDC/3V3_BOOT")
	(net 29 "/DCDC/3V3_PHASE")
	(net 30 "/SFP/SFI_CONN_RX_N")
	(net 31 "/Power/3V3_LDO")
	(net 32 "Net-(D1-C)")
	(net 33 "Net-(D32-C)")
	(net 34 "/M.2/~{LED_1}")
	(net 35 "/M.2/~{LED_2}")
	(net 36 "Net-(D35-A)")
	(net 37 "Net-(D35-C)")
	(net 38 "Net-(D36-A)")
	(net 39 "Net-(D36-C)")
	(net 40 "/USB Hub/USBC4_TX_{1}+")
	(net 41 "/USB Hub/USBC4_TX_{2}+")
	(net 42 "/Peripherals/I2C_{CONN}.SCL")
	(net 43 "/Peripherals/I2C_{CONN}.SDA")
	(net 44 "/USB Hub/USBC4_TX_{1}-")
	(net 45 "/USB Hub/USBC3_TX_{1}+")
	(net 46 "Net-(D63-A)")
	(net 47 "/CSI/CAM_CTRL.VSYNC_CAM3")
	(net 48 "/SoM_IO/I2C1_SCL_1V8")
	(net 49 "/Expansion connector/SPI3.MOSI")
	(net 50 "/Expansion connector/CAN1.DIN")
	(net 51 "/Expansion connector/UART2.RX")
	(net 52 "/CSI/CAM0.CSI3_D0+")
	(net 53 "/CSI/CAM3.CSI6_CLK+")
	(net 54 "/CSI/CAM1.CSI0_D1+")
	(net 55 "/SoM_IO2/USB1.D+")
	(net 56 "/Expansion connector/UART5.RTS")
	(net 57 "/SFP/MOD_ABS")
	(net 58 "unconnected-(J1F-CSI5_CLK_P-PadC44)")
	(net 59 "/CSI/CAM3.CSI7_D0-")
	(net 60 "/SoM_IO/I2C3_SCL_1V8")
	(net 61 "/Expansion connector/UART2.TX")
	(net 62 "/CSI/CAM3.CSI6_D1-")
	(net 63 "/CSI/CAM0.CSI3_D0-")
	(net 64 "/CSI/CAM0.CSI2_D0-")
	(net 65 "/Expansion connector/SPI1.MOSI")
	(net 66 "/CSI/CAM1.CSI0_CLK-")
	(net 67 "/CSI/CAM_CTRL.VSYNC_CAM2")
	(net 68 "/CSI/CAM0.CSI2_CLK-")
	(net 69 "/Expansion connector/SPI1.MISO")
	(net 70 "/CSI/CAM3.CSI6_D1+")
	(net 71 "/USB Hub/USBC3_VBUS")
	(net 72 "/SoM_IO/I2S_{M.2}.SDOUT")
	(net 73 "unconnected-(J1F-CSI7_CLK_N-PadB46)")
	(net 74 "/CSI/CAM_CTRL.CSIA_PEN")
	(net 75 "/Expansion connector/SPI3.MISO")
	(net 76 "/SoM_IO/I2S_{M.2}.SDIN")
	(net 77 "/CSI/CAM1.CSI1_D0+")
	(net 78 "/USB Hub/USBC4_CONN_TX1_P")
	(net 79 "/CSI/CAM2.CSI5_D1-")
	(net 80 "/USB Hub/USBC4_CONN_TX2_P")
	(net 81 "/Expansion connector/CAN1.DOUT")
	(net 82 "/Expansion connector/UART2.RTS")
	(net 83 "unconnected-(J1F-CSI1_CLK_N-PadH42)")
	(net 84 "/CSI/CAM2.CSI4_CLK-")
	(net 85 "/SoM_Power/~{SOM_POWER_BTN}")
	(net 86 "/CSI/CAM3.CSI7_D1-")
	(net 87 "/CSI/CAM2.CSI4_D1+")
	(net 88 "/CSI/CAM0.CSI2_D0+")
	(net 89 "/CSI/CAM0.CSI2_D1+")
	(net 90 "/Peripherals/I2C_CONN_PEN")
	(net 91 "/USB Hub/USBC4_CONN_TX1_N")
	(net 92 "unconnected-(J1F-CSI7_CLK_P-PadB45)")
	(net 93 "/CSI/CAM1.CSI1_D1+")
	(net 94 "/M.2/PCIe_{C1x1}.RX0-")
	(net 95 "/USB Hub/USBC3_CONN_TX1_N")
	(net 96 "/SoM_IO/I2C1_SDA_1V8")
	(net 97 "/Peripherals/FAN_PWM")
	(net 98 "/CSI/CAM_CTRL.CSIA_FLG")
	(net 99 "unconnected-(J1A-MID1-PadH40)")
	(net 100 "/Peripherals/FAN_TACH")
	(net 101 "/SFP/SFI.RX+")
	(net 102 "/CSI/CAM3.CSI7_D1+")
	(net 103 "/USB Hub/USBC3_CONN_TX2_N")
	(net 104 "/M.2/~{PEWAKE}")
	(net 105 "/Expansion connector/CAN0.DIN")
	(net 106 "/SFP/SFI.TX+")
	(net 107 "/SoM_IO/I2S_{M.2}.CLK")
	(net 108 "/SoM_IO/UART1.RX")
	(net 109 "/Expansion connector/SPI2.MISO")
	(net 110 "/USB Hub/USBC4_CONN_TX2_N")
	(net 111 "/Expansion connector/I2S3.FS")
	(net 112 "/SoM_IO/I2C5_SDA_1V8")
	(net 113 "/CSI/CAM1.CSI0_D0-")
	(net 114 "/Expansion connector/I2S3.SDIN")
	(net 115 "/USB Hub/USBC4_VBUS")
	(net 116 "/CSI/CAM3.CSI6_CLK-")
	(net 117 "/CSI/CAM_CTRL.CSIB_FLG")
	(net 118 "/Expansion connector/UART5.TX")
	(net 119 "unconnected-(J1A-MID0-PadK40)")
	(net 120 "/Expansion connector/I2S2.CLK")
	(net 121 "/Expansion connector/UART5.CTS")
	(net 122 "/CSI/CAM2.CSI4_D0-")
	(net 123 "/CSI/CAM_CTRL.CSIB_PEN")
	(net 124 "/CSI/CAM3.CSI7_D0+")
	(net 125 "/CSI/CAM2.CSI5_D0+")
	(net 126 "/SoM_IO/UART1.RTS")
	(net 127 "unconnected-(J1F-CSI5_CLK_N-PadC45)")
	(net 128 "/CSI/CAM2.CSI5_D0-")
	(net 129 "unconnected-(J1F-CSI3_CLK_P-PadF46)")
	(net 130 "/M.2/PCIe_{C1x1}.RX0+")
	(net 131 "/CSI/CAM_CTRL.VSYNC_CAM1")
	(net 132 "/SFP/SFI.TX-")
	(net 133 "/SoM_IO/I2C5_SCL_1V8")
	(net 134 "/CSI/CAM1.CSI1_D0-")
	(net 135 "/CSI/CAM3.CSI6_D0-")
	(net 136 "/CSI/CAM1.CSI0_CLK+")
	(net 137 "/M.2/PCIe_{C1x1}.~{CLKREQ}")
	(net 138 "/SoM_IO/UART1.TX")
	(net 139 "/SoM_IO/I2C2_SCL_1V8")
	(net 140 "/SoM_IO2/USB1.D-")
	(net 141 "/Expansion connector/I2S3.SDOUT")
	(net 142 "/Expansion connector/CAN0.DOUT")
	(net 143 "/CSI/CAM1.CSI1_D1-")
	(net 144 "/CSI/CAM2.CSI4_D0+")
	(net 145 "/SoM_IO/I2C3_SDA_1V8")
	(net 146 "/Expansion connector/I2S2.FS")
	(net 147 "/SFP/SFI.RX-")
	(net 148 "/Expansion connector/+3V3_AUX")
	(net 149 "/Peripherals/TPM_IRQ")
	(net 150 "/SoM_IO/I2S_{M.2}.FS")
	(net 151 "/Expansion connector/UART5.RX")
	(net 152 "/CSI/CAM3.CSI6_D0+")
	(net 153 "/CSI/CAM1.CSI0_D1-")
	(net 154 "/CSI/CAM0.CSI3_D1-")
	(net 155 "/CSI/CAM_CTRL.VSYNC_CAM0")
	(net 156 "/Expansion connector/+VCC_FMC")
	(net 157 "/CSI/CAM1.CSI0_D0+")
	(net 158 "/Expansion connector/UART2.CTS")
	(net 159 "unconnected-(J1F-CSI1_CLK_P-PadH43)")
	(net 160 "/CSI/CAM2.CSI4_CLK+")
	(net 161 "/CSI/CAM0.CSI3_D1+")
	(net 162 "/CSI/CAM2.CSI4_D1-")
	(net 163 "/CSI/CAM2.CSI5_D1+")
	(net 164 "/USB Hub/USBC3_CONN_TX1_P")
	(net 165 "/Expansion connector/I2S3.CLK")
	(net 166 "unconnected-(J1F-CSI3_CLK_N-PadF45)")
	(net 167 "/SoM_IO/I2C2_SDA_1V8")
	(net 168 "/Expansion connector/I2S2.SDIN")
	(net 169 "/SoM_IO2/SFI_REFCLK+")
	(net 170 "/CSI/CAM0.CSI2_D1-")
	(net 171 "/SoM_IO2/SFI_REFCLK-")
	(net 172 "/Expansion connector/I2S2.SDOUT")
	(net 173 "/Expansion connector/SPI2.MOSI")
	(net 174 "/USB Hub/USBC3_CONN_TX2_P")
	(net 175 "unconnected-(J5-SBU_{1}-PadA8)")
	(net 176 "/USB Debug, PD/USBC0_VBUS")
	(net 177 "unconnected-(J5-SBU_{2}-PadB8)")
	(net 178 "unconnected-(J6-SBU_{2}-PadB8)")
	(net 179 "unconnected-(J6-SBU_{1}-PadA8)")
	(net 180 "unconnected-(J10-Pad16)")
	(net 181 "unconnected-(J10-Pad13)")
	(net 182 "unconnected-(J10-Pad46)")
	(net 183 "unconnected-(J10-Pad14)")
	(net 184 "unconnected-(J10-Pad17)")
	(net 185 "unconnected-(J10-Pad31)")
	(net 186 "/CSI/VSYNC_CAM0_3V3")
	(net 187 "unconnected-(J10-Pad37)")
	(net 188 "unconnected-(J10-Pad36)")
	(net 189 "unconnected-(J10-Pad38)")
	(net 190 "unconnected-(J10-Pad35)")
	(net 191 "unconnected-(J10-Pad33)")
	(net 192 "unconnected-(J10-Pad45)")
	(net 193 "unconnected-(J10-Pad43)")
	(net 194 "/CSI/VSYNC_CAM1_3V3")
	(net 195 "unconnected-(J10-Pad44)")
	(net 196 "unconnected-(J11-Pad16)")
	(net 197 "unconnected-(J11-Pad38)")
	(net 198 "unconnected-(J11-Pad33)")
	(net 199 "unconnected-(J11-Pad14)")
	(net 200 "unconnected-(J11-Pad35)")
	(net 201 "/CSI/VSYNC_CAM2_3V3")
	(net 202 "unconnected-(J11-Pad31)")
	(net 203 "unconnected-(J11-Pad13)")
	(net 204 "unconnected-(J11-Pad37)")
	(net 205 "unconnected-(J11-Pad44)")
	(net 206 "unconnected-(J11-Pad46)")
	(net 207 "unconnected-(J11-Pad43)")
	(net 208 "unconnected-(J11-Pad17)")
	(net 209 "unconnected-(J11-Pad36)")
	(net 210 "/CSI/VSYNC_CAM3_3V3")
	(net 211 "unconnected-(J11-Pad45)")
	(net 212 "/USB Hub/USBC3_TX_{2}+")
	(net 213 "+5V_SOM")
	(net 214 "/USB Hub/USBC4_TX_{2}-")
	(net 215 "/Recovery USB/USBC2_CONN_TX1_N")
	(net 216 "unconnected-(J13-NC-Pad22)")
	(net 217 "/M.2/M2_M_SMB_DATA")
	(net 218 "unconnected-(J13-NC-Pad24)")
	(net 219 "unconnected-(J13-NC-Pad36)")
	(net 220 "unconnected-(J13-NC-Pad58)")
	(net 221 "unconnected-(J13-NC-Pad69)")
	(net 222 "unconnected-(J13-NC-Pad28)")
	(net 223 "unconnected-(J13-NC-Pad8)")
	(net 224 "/M.2/M2_M_SUSCLK")
	(net 225 "unconnected-(J13-NC-Pad48)")
	(net 226 "unconnected-(J13-NC-Pad6)")
	(net 227 "unconnected-(J13-NC-Pad34)")
	(net 228 "unconnected-(J13-NC-Pad30)")
	(net 229 "unconnected-(J13-NC-Pad32)")
	(net 230 "unconnected-(J13-NC-Pad26)")
	(net 231 "unconnected-(J13-NC-Pad67)")
	(net 232 "unconnected-(J13-NC-Pad20)")
	(net 233 "unconnected-(J13-NC-Pad38)")
	(net 234 "/Recovery USB/USBC2_TX1_N")
	(net 235 "/M.2/M2_M_SMB_CLK")
	(net 236 "/M.2/~{M2_M_ALERT}")
	(net 237 "/Recovery USB/USBC2_TX2_N")
	(net 238 "unconnected-(J13-NC-Pad46)")
	(net 239 "unconnected-(J13-NC-Pad56)")
	(net 240 "unconnected-(J14-SDIO_~{WAKE}-Pad21)")
	(net 241 "/Recovery USB/USBC2_CONN_TX2_N")
	(net 242 "/Recovery USB/USBC2_TX1_P")
	(net 243 "/SoM_IO/UART1.CTS")
	(net 244 "/M.2/M2_E_W_DIS_1")
	(net 245 "/Recovery USB/USBC2_CONN_TX1_P")
	(net 246 "/SoM_Power/~{VDDIN_PWR_BAD}")
	(net 247 "/M.2/M2_E_W_DIS_2")
	(net 248 "unconnected-(J14-COEX3-Pad44)")
	(net 249 "/CSI/CAM0.CSI2_CLK+")
	(net 250 "unconnected-(J14-UART_RXD-Pad22)")
	(net 251 "unconnected-(J14-RFU-Pad64)")
	(net 252 "unconnected-(J14-COEX_RXD-Pad48)")
	(net 253 "/DCDC/5V_OUT")
	(net 254 "unconnected-(J14-SDIO_CMD-Pad11)")
	(net 255 "unconnected-(J14-PCM_CLK-Pad8)")
	(net 256 "unconnected-(J14-I2C_DATA-Pad58)")
	(net 257 "/M.2/~{M2_E_ALERT}")
	(net 258 "unconnected-(J14-SDIO_D3-Pad19)")
	(net 259 "/M.2/WIFI_BT_USB_D_N")
	(net 260 "/Recovery USB/USBC2_TX2_P")
	(net 261 "unconnected-(J14-COEX_TXD-Pad46)")
	(net 262 "unconnected-(J14-SDIO_D1-Pad15)")
	(net 263 "unconnected-(J14-UART_TXD-Pad32)")
	(net 264 "unconnected-(J14-I2C_CLK-Pad60)")
	(net 265 "unconnected-(J14-UIM_POWER_SNK-Pad68)")
	(net 266 "unconnected-(J14-SDIO_D2-Pad17)")
	(net 267 "unconnected-(J14-UART_RTS-Pad36)")
	(net 268 "unconnected-(J14-SDIO_D0-Pad13)")
	(net 269 "/SoM_IO2/TC_VCC")
	(net 270 "/Recovery USB/USBC2_CONN_TX2_P")
	(net 271 "FLASH_PWR")
	(net 272 "/M.2/WIFI_BT_USB_D_P")
	(net 273 "unconnected-(J14-UART_CTS-Pad34)")
	(net 274 "unconnected-(J14-PCM_OUT-Pad14)")
	(net 275 "unconnected-(J14-SDIO_~{RESET}-Pad23)")
	(net 276 "unconnected-(J14-UIM_SWP-Pad66)")
	(net 277 "unconnected-(J14-SDIO_CLK-Pad9)")
	(net 278 "unconnected-(J14-UIM_POWER_SRC-Pad70)")
	(net 279 "/Peripherals/FAN_TACH_5V")
	(net 280 "/DCDC/1V15_OUT")
	(net 281 "/Peripherals/FAN_PWM_5V")
	(net 282 "+1V15")
	(net 283 "/USB Hub/USBC3_TX_{1}-")
	(net 284 "unconnected-(J18-PadJ09)")
	(net 285 "/USB Hub/USBC3_TX_{2}-")
	(net 286 "unconnected-(J18-PadK23)")
	(net 287 "/Recovery USB/USBC2_VBUS")
	(net 288 "unconnected-(J18-PadE09)")
	(net 289 "/Expansion connector/+12V_FMC")
	(net 290 "unconnected-(J18-PadE25)")
	(net 291 "unconnected-(J18-PadK22)")
	(net 292 "/Expansion connector/SPI1.~{CS0}")
	(net 293 "/USB Debug, PD/PDC_LDO_1V8")
	(net 294 "/USB Debug, PD/PDC_LDO_3V3")
	(net 295 "/Expansion connector/+V_{ADJ}")
	(net 296 "unconnected-(J18-PadJ22)")
	(net 297 "/Expansion connector/+3V3_FMC")
	(net 298 "unconnected-(J18-PadJ21)")
	(net 299 "/SoM_IO2/USBSS1.RX+")
	(net 300 "unconnected-(J18-PadG36)")
	(net 301 "unconnected-(J18-PadK28)")
	(net 302 "/USB DP Alt mode/USBSS1_RX_C_P")
	(net 303 "unconnected-(J18-PadL21)")
	(net 304 "unconnected-(J18-PadC06)")
	(net 305 "/Expansion connector/SPI3.SCK")
	(net 306 "unconnected-(J18-PadK35)")
	(net 307 "/Expansion connector/+5V_FMC")
	(net 308 "unconnected-(J18-PadG37)")
	(net 309 "unconnected-(J18-PadD05)")
	(net 310 "/USB DP Alt mode/USBSS1_TX_C_P")
	(net 311 "/SoM_IO2/USBSS1.TX+")
	(net 312 "unconnected-(J18-PadE33)")
	(net 313 "unconnected-(J18-PadB28)")
	(net 314 "unconnected-(J1D-FSI_GPIO29-PadJ11)")
	(net 315 "unconnected-(J18-PadK19)")
	(net 316 "unconnected-(J18-PadF08)")
	(net 317 "/SoM_IO/I2C0_SCL_1V8")
	(net 318 "unconnected-(J18-PadJ30)")
	(net 319 "/Expansion connector/FMC_PRSNT_M2C_L")
	(net 320 "unconnected-(J1D-FSI_GPIO28-PadK10)")
	(net 321 "/Expansion connector/GPIO.MCLK03")
	(net 322 "/USB DP Alt mode/USBSS1_RX_C_N")
	(net 323 "unconnected-(J18-PadK17)")
	(net 324 "/SoM_IO2/USBSS1.RX-")
	(net 325 "unconnected-(J18-PadY06)")
	(net 326 "unconnected-(J18-PadG34)")
	(net 327 "unconnected-(J18-PadL20)")
	(net 328 "unconnected-(J18-PadK38)")
	(net 329 "/SoM_IO2/USBSS1.TX-")
	(net 330 "/Expansion connector/FMC_PG_M2C")
	(net 331 "/SoM_IO/I2C0_SDA_1V8")
	(net 332 "unconnected-(J18-PadJ13)")
	(net 333 "/USB DP Alt mode/USBSS1_TX_C_N")
	(net 334 "/USB Debug, PD/FTDI_3V3")
	(net 335 "unconnected-(J18-PadK31)")
	(net 336 "unconnected-(J18-PadK37)")
	(net 337 "unconnected-(J18-PadF23)")
	(net 338 "unconnected-(J18-PadK16)")
	(net 339 "Net-(U34-~{RESET})")
	(net 340 "unconnected-(J18-PadB29)")
	(net 341 "/Expansion connector/FMC_PRESENT")
	(net 342 "/Expansion connector/FMC_PG_C2M")
	(net 343 "unconnected-(J18-PadJ24)")
	(net 344 "/USB DP Alt mode/USBC1_TX1_P")
	(net 345 "/USB DP Alt mode/USBC1_CONN_TX1_P")
	(net 346 "unconnected-(J18-PadE13)")
	(net 347 "/USB DP Alt mode/USBC1_CONN_TX2_P")
	(net 348 "unconnected-(J18-PadM06)")
	(net 349 "unconnected-(J18-PadA35)")
	(net 350 "unconnected-(J18-PadY02)")
	(net 351 "unconnected-(J18-PadJ25)")
	(net 352 "unconnected-(J18-PadJ07)")
	(net 353 "unconnected-(J18-PadJ02)")
	(net 354 "/USB DP Alt mode/USBC1_TX2_P")
	(net 355 "unconnected-(J18-PadK13)")
	(net 356 "/Expansion connector/GPIO.USER_BTN1")
	(net 357 "unconnected-(J18-PadC03)")
	(net 358 "unconnected-(J18-PadE36)")
	(net 359 "unconnected-(J18-PadY03)")
	(net 360 "Net-(J18-PadK40)")
	(net 361 "/USB DP Alt mode/USBC1_CONN_TX1_N")
	(net 362 "/Expansion connector/GPIO.MCLK01")
	(net 363 "unconnected-(J18-PadF16)")
	(net 364 "/Expansion connector/SPI1.~{CS1}")
	(net 365 "unconnected-(J18-PadJ12)")
	(net 366 "unconnected-(J18-PadK04)")
	(net 367 "unconnected-(J18-PadJ28)")
	(net 368 "/Expansion connector/GPIO.21")
	(net 369 "unconnected-(J18-PadK29)")
	(net 370 "/USB DP Alt mode/USBC1_TX1_N")
	(net 371 "/Expansion connector/GPIO.USER_LED1")
	(net 372 "/USB DP Alt mode/USBC1_TX2_N")
	(net 373 "unconnected-(J18-PadK34)")
	(net 374 "/USB DP Alt mode/USBC1_CONN_TX2_N")
	(net 375 "unconnected-(J18-PadA26)")
	(net 376 "/USB DP Alt mode/USBC1_VBUS")
	(net 377 "unconnected-(J18-PadJ18)")
	(net 378 "unconnected-(J18-PadJ34)")
	(net 379 "/SFP/SH")
	(net 380 "unconnected-(J18-PadJ10)")
	(net 381 "unconnected-(J18-PadE16)")
	(net 382 "/M.2/PCIe_{C5x4}.TX0+")
	(net 383 "unconnected-(J18-PadD31)")
	(net 384 "unconnected-(J18-PadD34)")
	(net 385 "unconnected-(J18-PadE12)")
	(net 386 "/M.2/M2_M_PET0_P")
	(net 387 "unconnected-(J18-PadK08)")
	(net 388 "unconnected-(J18-PadJ31)")
	(net 389 "unconnected-(J18-PadL16)")
	(net 390 "unconnected-(J18-PadG33)")
	(net 391 "/M.2/M2_M_PET1_P")
	(net 392 "/M.2/PCIe_{C5x4}.TX1+")
	(net 393 "/Expansion connector/SPI2.SCK")
	(net 394 "unconnected-(J18-PadK25)")
	(net 395 "unconnected-(J18-PadJ15)")
	(net 396 "unconnected-(J18-PadJ16)")
	(net 397 "unconnected-(J18-PadB33)")
	(net 398 "unconnected-(J18-PadY07)")
	(net 399 "/M.2/M2_M_PET2_P")
	(net 400 "/M.2/PCIe_{C5x4}.TX2+")
	(net 401 "unconnected-(J18-PadJ03)")
	(net 402 "unconnected-(J18-PadF11)")
	(net 403 "unconnected-(J18-PadF34)")
	(net 404 "unconnected-(J18-PadF38)")
	(net 405 "/Expansion connector/SPI3.~{CS1}")
	(net 406 "unconnected-(J18-PadK11)")
	(net 407 "/Expansion connector/I2C0.SCL")
	(net 408 "/M.2/M2_M_PET3_P")
	(net 409 "/Expansion connector/SPI2.~{CS0}")
	(net 410 "/M.2/PCIe_{C5x4}.TX3+")
	(net 411 "/M.2/PCIe_{C5x4}.TX0-")
	(net 412 "unconnected-(J18-PadC07)")
	(net 413 "unconnected-(J18-PadF10)")
	(net 414 "unconnected-(J18-PadM07)")
	(net 415 "/M.2/M2_M_PET0_N")
	(net 416 "/Expansion connector/GPIO.MCLK02")
	(net 417 "/M.2/M2_M_PET1_N")
	(net 418 "/M.2/PCIe_{C5x4}.TX1-")
	(net 419 "unconnected-(J18-PadL05)")
	(net 420 "unconnected-(J18-PadJ27)")
	(net 421 "/Expansion connector/SPI1.SCK")
	(net 422 "unconnected-(J18-PadB37)")
	(net 423 "/M.2/M2_M_PET2_N")
	(net 424 "unconnected-(J18-PadF37)")
	(net 425 "unconnected-(J18-PadZ08)")
	(net 426 "unconnected-(J18-PadK05)")
	(net 427 "unconnected-(J18-PadF14)")
	(net 428 "unconnected-(J18-PadC02)")
	(net 429 "unconnected-(J18-PadK14)")
	(net 430 "unconnected-(J18-PadK32)")
	(net 431 "Net-(J18-PadH01)")
	(net 432 "unconnected-(J18-PadH04)")
	(net 433 "unconnected-(J18-PadL17)")
	(net 434 "unconnected-(J18-PadD04)")
	(net 435 "/M.2/PCIe_{C5x4}.TX2-")
	(net 436 "/M.2/M2_M_PET3_N")
	(net 437 "unconnected-(J18-PadE21)")
	(net 438 "/Expansion connector/SPI3.~{CS0}")
	(net 439 "/M.2/PCIe_{C5x4}.TX3-")
	(net 440 "/M.2/M2_E_PET0_P")
	(net 441 "unconnected-(J18-PadF04)")
	(net 442 "unconnected-(J18-PadK26)")
	(net 443 "unconnected-(J18-PadB32)")
	(net 444 "/M.2/M2_E_PET0_N")
	(net 445 "unconnected-(J18-PadF13)")
	(net 446 "unconnected-(J18-PadE24)")
	(net 447 "unconnected-(J18-PadE37)")
	(net 448 "/Expansion connector/GPIO.USER_BTN0")
	(net 449 "unconnected-(J18-PadD30)")
	(net 450 "Net-(J18-PadJ39)")
	(net 451 "unconnected-(J18-PadK07)")
	(net 452 "/Expansion connector/PET0_C3_P")
	(net 453 "unconnected-(J18-PadM02)")
	(net 454 "unconnected-(J18-PadF20)")
	(net 455 "unconnected-(J18-PadF07)")
	(net 456 "unconnected-(J18-PadF35)")
	(net 457 "unconnected-(J18-PadE28)")
	(net 458 "unconnected-(J18-PadJ33)")
	(net 459 "/Expansion connector/PCIe_{C3x2}.TX0+")
	(net 460 "unconnected-(J18-PadJ36)")
	(net 461 "unconnected-(J18-PadJ19)")
	(net 462 "unconnected-(J18-PadL04)")
	(net 463 "unconnected-(J18-PadK20)")
	(net 464 "/Expansion connector/GPIO.20")
	(net 465 "unconnected-(J18-PadF28)")
	(net 466 "unconnected-(J18-PadJ06)")
	(net 467 "/Expansion connector/PCIe_{C3x2}.TX1+")
	(net 468 "unconnected-(J18-PadZ04)")
	(net 469 "unconnected-(J18-PadZ05)")
	(net 470 "unconnected-(J18-PadJ37)")
	(net 471 "/Expansion connector/PER0_C2_N")
	(net 472 "/Expansion connector/ADDR1")
	(net 473 "unconnected-(J18-PadB36)")
	(net 474 "unconnected-(J18-PadF17)")
	(net 475 "/Expansion connector/PET1_C3_P")
	(net 476 "/Expansion connector/PET0_C2_P")
	(net 477 "unconnected-(J18-PadE34)")
	(net 478 "/Expansion connector/PCIe_{C2x1}.TX0+")
	(net 479 "/Expansion connector/PET0_C2_N")
	(net 480 "unconnected-(J18-PadA30)")
	(net 481 "unconnected-(J18-PadF05)")
	(net 482 "unconnected-(J18-PadA22)")
	(net 483 "unconnected-(J18-PadA23)")
	(net 484 "unconnected-(J18-PadD33)")
	(net 485 "unconnected-(J18-PadM03)")
	(net 486 "unconnected-(J18-PadK10)")
	(net 487 "/Expansion connector/GPIO.USER_LED0")
	(net 488 "/USB Debug, PD/USBC0_D_N")
	(net 489 "/USB Debug, PD/USBC0_D_P")
	(net 490 "Net-(D12-A)")
	(net 491 "+5V_AON")
	(net 492 "/SoM_IO2/USB2.D+")
	(net 493 "/SoM_IO2/USB2.D-")
	(net 494 "/SoM_IO/UART3_DEBUG_RX_1V8")
	(net 495 "/SoM_Power/~{FORCE_RECOVERY}")
	(net 496 "/SoM_IO/UART3_DEBUG_TX_1V8")
	(net 497 "unconnected-(J1E-HDMI_CEC-PadJ50)")
	(net 498 "/USB Hub/USBC4_RX_{2}+")
	(net 499 "/USB Hub/USBC4_D-")
	(net 500 "/USB Hub/USBC4_RX_{2}-")
	(net 501 "/USB Hub/USBC4_RX_{1}-")
	(net 502 "/USB Hub/USBC4_CC_{2}")
	(net 503 "/USB Hub/USBC4_CC_{1}")
	(net 504 "/USB Hub/USBC4_RX_{1}+")
	(net 505 "/USB Hub/USBC4_D+")
	(net 506 "/USB Hub/USBC3_D+")
	(net 507 "/USB Hub/USBC3_RX_{1}-")
	(net 508 "/USB Hub/USBC3_D-")
	(net 509 "/USB Hub/USBC3_CC_{2}")
	(net 510 "/USB Hub/USBC3_CC_{1}")
	(net 511 "/USB Hub/USBC3_RX_{2}-")
	(net 512 "/USB Hub/USBC3_RX_{2}+")
	(net 513 "/USB Hub/USBC3_RX_{1}+")
	(net 514 "/USB Debug, PD/USBC0_CC1")
	(net 515 "/USB Debug, PD/USBC0_CC2")
	(net 516 "/Expansion connector/PCIe_{C2x1}.TX0-")
	(net 517 "/Expansion connector/PCIe_{C3x2}.TX0-")
	(net 518 "/Expansion connector/PET0_C3_N")
	(net 519 "/Expansion connector/PCIe_{C3x2}.TX1-")
	(net 520 "/Expansion connector/PET1_C3_N")
	(net 521 "Net-(U72-CT)")
	(net 522 "/Power/USBPD1_HV")
	(net 523 "/SoM_IO2/DP0.TX0_C+")
	(net 524 "Net-(Q22-D)")
	(net 525 "/Power/USBPD2_HV")
	(net 526 "Net-(D3-A)")
	(net 527 "/USB Hub/~{RESET}")
	(net 528 "Net-(D4-A)")
	(net 529 "Net-(D10-A)")
	(net 530 "Net-(D14-C)")
	(net 531 "Net-(D16-A)")
	(net 532 "/USB Debug, PD/SCK")
	(net 533 "Net-(D18-A)")
	(net 534 "Net-(D19-A)")
	(net 535 "Net-(D20-A)")
	(net 536 "/USB Debug, PD/FTDI_LED_TX")
	(net 537 "/USB Debug, PD/FTDI_LED_RX")
	(net 538 "Net-(D21-A)")
	(net 539 "Net-(D26-A)")
	(net 540 "Net-(D27-A)")
	(net 541 "Net-(D28-A)")
	(net 542 "Net-(D29-A)")
	(net 543 "Net-(D30-C)")
	(net 544 "Net-(D32-A)")
	(net 545 "Net-(D33-A)")
	(net 546 "Net-(D34-A)")
	(net 547 "Net-(D41-A)")
	(net 548 "Net-(D44-A)")
	(net 549 "Net-(D52-A)")
	(net 550 "Net-(D52-C)")
	(net 551 "unconnected-(J1H-I2S3_DIN-PadJ59)")
	(net 552 "/M.2/PCIe_{C5x4}.RX2-")
	(net 553 "/SoM_IO2/DP0.TX3-")
	(net 554 "/Expansion connector/PCIe_{C2x1}.~{RST}")
	(net 555 "unconnected-(J1D-MCLK04-PadH55)")
	(net 556 "unconnected-(J1H-I2S3_FS-PadC60)")
	(net 557 "/SoM_IO2/DP0.TX3+")
	(net 558 "unconnected-(J1G-FSI_GPIO20-PadB9)")
	(net 559 "unconnected-(J1B-UPHY_RX13_P-PadB29)")
	(net 560 "unconnected-(J1H-GPIO40-PadC5)")
	(net 561 "/Expansion connector/I2C0.SDA")
	(net 562 "unconnected-(J18-PadZ24)")
	(net 563 "Net-(J1A-UFS0_REF_CLK)")
	(net 564 "/M.2/PCIe_{C5x4}.RX3-")
	(net 565 "/Expansion connector/PCIe_{C3x2}.~{CLKREQ}")
	(net 566 "Net-(J1A-VM_SLEEP_N)")
	(net 567 "/DCDC/3V3_OUT")
	(net 568 "unconnected-(J1G-FSI_GPIO24-PadE30)")
	(net 569 "/Expansion connector/PCIe_{C3x2}.~{RST}")
	(net 570 "/Expansion connector/DP1.TX2+")
	(net 571 "Net-(J18-PadL32)")
	(net 572 "/Expansion connector/DP2.AUX+")
	(net 573 "unconnected-(J1B-UPHY_RX14_P-PadC31)")
	(net 574 "/Expansion connector/DP3.HPD")
	(net 575 "/SoM_IO2/DP0.TX0_C-")
	(net 576 "unconnected-(J18-PadZ25)")
	(net 577 "unconnected-(J18-PadF19)")
	(net 578 "/DCDC/12V_VDRV")
	(net 579 "unconnected-(J1G-FSI_GPIO00-PadF40)")
	(net 580 "/SoM_IO/USBC1_FLG_1V8")
	(net 581 "unconnected-(J1B-UPHY_TX15_N-PadJ31)")
	(net 582 "unconnected-(J1B-UPHY_TX15_P-PadJ30)")
	(net 583 "/SoM_IO2/DP0.TX0+")
	(net 584 "/M.2/PCIe_{C5x4}.CLK+")
	(net 585 "/DCDC/12V_BOOT")
	(net 586 "unconnected-(J1B-UPHY_TX16_N-PadK16)")
	(net 587 "unconnected-(J1H-I2S3_DOUT-PadK59)")
	(net 588 "unconnected-(J1C-PEX_C4_CLKREQ_N-PadC8)")
	(net 589 "/M.2/PCIe_{C1x1}.CLK+")
	(net 590 "unconnected-(J18-PadA27)")
	(net 591 "/Expansion connector/DP2.TX0+")
	(net 592 "/M.2/PCIe_{C5x4}.CLK-")
	(net 593 "/Expansion connector/DP3.TX2+")
	(net 594 "unconnected-(J18-PadF26)")
	(net 595 "unconnected-(J1C-GPIO22-PadF54)")
	(net 596 "/SoM_IO2/DP0.TX1_C+")
	(net 597 "/SoM_IO2/DP0.TX1_C-")
	(net 598 "/Recovery USB/USBSS0.RX+")
	(net 599 "unconnected-(J18-PadA34)")
	(net 600 "/Expansion connector/CAN2.DOUT")
	(net 601 "Net-(J1A-VM_INT_N)")
	(net 602 "unconnected-(J1B-UPHY_TX13_P-PadK29)")
	(net 603 "/Expansion connector/DP1.TX0-")
	(net 604 "unconnected-(J1B-UPHY_TX14_N-PadG30)")
	(net 605 "/SoM_Power/~{MODULE_SHDN}")
	(net 606 "/SoM_IO2/NVJTAG_SEL")
	(net 607 "/SoM_IO2/DP0.AUX-")
	(net 608 "unconnected-(J1B-UPHY_RX5_N-PadD21)")
	(net 609 "/SoM_Power/~{MOD_SLEEP}")
	(net 610 "/SoM_Power/~{PWR_BTN}")
	(net 611 "unconnected-(J18-PadF32)")
	(net 612 "/SoM_IO2/DP0.TX1+")
	(net 613 "unconnected-(J1G-FSI_GPIO02-PadB40)")
	(net 614 "unconnected-(J1C-UPHY_REFCLK0_N-PadF17)")
	(net 615 "/SoM_IO2/DP0.TX2_C+")
	(net 616 "unconnected-(J1I-UART4_TX-PadL5)")
	(net 617 "/SoM_IO2/DP0.TX2_C-")
	(net 618 "/Recovery USB/USBSS0.TX+")
	(net 619 "unconnected-(J18-PadZ09)")
	(net 620 "/M.2/PCIe_{C5x4}.RX1-")
	(net 621 "Net-(J1A-THERM_ALERT_N)")
	(net 622 "/Recovery USB/USBSS0.RX-")
	(net 623 "/SoM_IO2/USBSS2.RX-")
	(net 624 "unconnected-(J1D-I2C9_DAT-PadJ55)")
	(net 625 "/SoM_IO/SFP_LEDY_1V8")
	(net 626 "unconnected-(J1D-I2C9_CLK-PadA55)")
	(net 627 "/SoM_IO2/JTAG_TRST_N")
	(net 628 "unconnected-(J18-PadF25)")
	(net 629 "unconnected-(J1G-FSI_GPIO27-PadK7)")
	(net 630 "/Recovery USB/USBSS0.TX-")
	(net 631 "/Expansion connector/DP2.TX3-")
	(net 632 "unconnected-(J1G-FSI_GPIO22-PadK9)")
	(net 633 "Net-(D57-C)")
	(net 634 "+12V")
	(net 635 "/SoM_IO2/DP0.AUX+")
	(net 636 "unconnected-(J1G-FSI_GPIO11-PadD36)")
	(net 637 "/Expansion connector/PCIe_{C2x1}.RX0-")
	(net 638 "unconnected-(J1B-UPHY_RX5_P-PadD20)")
	(net 639 "Net-(D31-A)")
	(net 640 "/Expansion connector/DP2.TX3+")
	(net 641 "unconnected-(J1D-I2C10_CLK-PadA47)")
	(net 642 "/M.2/USB3.D-")
	(net 643 "/SoM_IO/SFP_LEDG_1V8")
	(net 644 "Net-(D43-C)")
	(net 645 "Net-(D43-A)")
	(net 646 "unconnected-(J1C-UPHY_REFCLK1_P-PadF24)")
	(net 647 "unconnected-(J1G-FSI_GPIO16-PadB48)")
	(net 648 "/Expansion connector/DP3.TX3+")
	(net 649 "unconnected-(J1H-I2S7_DOUT-PadL9)")
	(net 650 "unconnected-(J18-PadA39)")
	(net 651 "unconnected-(J1B-UPHY_RX16_P-PadB16)")
	(net 652 "/SoM_IO2/NVDBG_SEL")
	(net 653 "/M.2/USB3.D+")
	(net 654 "unconnected-(J1H-I2S7_DIN-PadL48)")
	(net 655 "unconnected-(J18-PadD29)")
	(net 656 "/Expansion connector/DP2.AUX-")
	(net 657 "/Expansion connector/DP3.AUX-")
	(net 658 "unconnected-(J18-PadF22)")
	(net 659 "Net-(J18-PadB01)")
	(net 660 "unconnected-(J1I-GPIO69-PadK51)")
	(net 661 "/Expansion connector/DP3.TX3-")
	(net 662 "/SoM_IO2/USBSS2.TX-")
	(net 663 "/SoM_IO2/DP0.TX0-")
	(net 664 "unconnected-(J1D-VM_I2C_SCK-PadL44)")
	(net 665 "/Expansion connector/DP3.TX0-")
	(net 666 "/SoM_IO2/DP0.TX2-")
	(net 667 "unconnected-(J1B-UPHY_RX13_N-PadB28)")
	(net 668 "/SoM_IO2/PCIe_{C2x1}R_CLK-")
	(net 669 "/M.2/PCIe_{C5x4}.RX0-")
	(net 670 "unconnected-(J1I-SGMII0_MDIO-PadE7)")
	(net 671 "unconnected-(J1D-I2C10_DAT-PadA48)")
	(net 672 "unconnected-(J1B-UPHY_TX5_N-PadH21)")
	(net 673 "Net-(J1A-THERM_SHDN_REQ_N)")
	(net 674 "/M.2/PCIe_{C5x4}.RX1+")
	(net 675 "/Expansion connector/DP3.TX1-")
	(net 676 "/M.2/PCIe_{C1x1}.CLK-")
	(net 677 "/Expansion connector/ADDR0")
	(net 678 "Net-(J1A-VCOMP_ALERT_N)")
	(net 679 "/M.2/PCIe_{C1x1}.~{RST}")
	(net 680 "/Expansion connector/DP3.TX2-")
	(net 681 "/M.2/PCIe_{C5x4}.RX3+")
	(net 682 "/Expansion connector/DP1.TX3-")
	(net 683 "/SoM_Power/~{SOM_PRSNT}")
	(net 684 "/SoM_IO2/USBSS2.TX+")
	(net 685 "unconnected-(J18-PadA38)")
	(net 686 "unconnected-(J1H-GPIO12-PadE10)")
	(net 687 "unconnected-(J1I-UART4_RX-PadH6)")
	(net 688 "/SoM_IO2/JTAG_TDO")
	(net 689 "/SoM_IO/USBC2_PEN_1V8")
	(net 690 "/Expansion connector/CAN2.DIN")
	(net 691 "/Expansion connector/DP3.TX0+")
	(net 692 "/SoM_IO/~{USBC2_INT}_1V8")
	(net 693 "unconnected-(J1B-UPHY_TX14_P-PadG31)")
	(net 694 "/Expansion connector/PCIe_{C2x1}.~{CLKREQ}")
	(net 695 "unconnected-(J1B-UPHY_RX15_N-PadA31)")
	(net 696 "unconnected-(J1B-UPHY_TX13_N-PadK28)")
	(net 697 "unconnected-(J1B-UPHY_RX14_N-PadC30)")
	(net 698 "/Recovery USB/USB0.D-")
	(net 699 "/Expansion connector/PCIe_{C3x2}.CLK+")
	(net 700 "Net-(J1A-MV_LSW_MON)")
	(net 701 "/Expansion connector/CAN3.DIN")
	(net 702 "/SoM_Power/~{SYS_RESET}")
	(net 703 "unconnected-(J1I-FSI_GPIO31-PadF8)")
	(net 704 "Net-(J1A-GPIO30)")
	(net 705 "unconnected-(J1H-I2S7_SCLK-PadL50)")
	(net 706 "/SoM_IO2/JTAG_TMS")
	(net 707 "/Expansion connector/DP1.TX0+")
	(net 708 "unconnected-(J18-PadF31)")
	(net 709 "Net-(J18-PadL33)")
	(net 710 "unconnected-(J1I-FSI_GPIO15-PadE34)")
	(net 711 "unconnected-(J1G-FSI_GPIO23-PadE31)")
	(net 712 "unconnected-(J1H-I2S7_LRCK-PadL49)")
	(net 713 "/Expansion connector/DP1.TX1-")
	(net 714 "unconnected-(J1C-PEX_C4_RST_N-PadH10)")
	(net 715 "/SoM_IO2/JTAG_TDI")
	(net 716 "unconnected-(J1I-FSI_GPIO12-PadF37)")
	(net 717 "Net-(J18-PadL01)")
	(net 718 "unconnected-(J1G-FSI_GPIO17-PadB49)")
	(net 719 "unconnected-(J18-PadA31)")
	(net 720 "/SoM_IO2/PCIe_{C2x1}R_CLK+")
	(net 721 "unconnected-(J1I-FSI_GPIO30-PadB6)")
	(net 722 "/Expansion connector/PCIe_{C3x2}.RX1-")
	(net 723 "unconnected-(J1I-GPIO24-PadJ51)")
	(net 724 "unconnected-(J1G-FSI_GPIO01-PadD40)")
	(net 725 "/M.2/PCIe_{C5x4}.RX0+")
	(net 726 "/Expansion connector/DP2.TX1+")
	(net 727 "unconnected-(J1G-FSI_GPIO26-PadB5)")
	(net 728 "/Expansion connector/PER0_C2_P")
	(net 729 "/Expansion connector/DP1.AUX+")
	(net 730 "unconnected-(J1B-UPHY_RX16_N-PadB17)")
	(net 731 "/M.2/PCIe_{C5x4}.RX2+")
	(net 732 "/Expansion connector/PCIe_{C3x2}.CLK-")
	(net 733 "/Expansion connector/DP1.TX2-")
	(net 734 "unconnected-(J1D-VM_I2C_DAT-PadL45)")
	(net 735 "unconnected-(J1I-FSI_GPIO18-PadE51)")
	(net 736 "/Expansion connector/DP3.TX1+")
	(net 737 "/Expansion connector/DP2.TX0-")
	(net 738 "/Expansion connector/DP1.AUX-")
	(net 739 "Net-(J1A-GPIO56)")
	(net 740 "unconnected-(J1I-FSI_GPIO35-PadE8)")
	(net 741 "Net-(J1A-PERIPHERAL_RESET_N)")
	(net 742 "/Expansion connector/DP2.TX2-")
	(net 743 "/SoM_IO2/JTAG_TCK")
	(net 744 "/Expansion connector/DP2.TX1-")
	(net 745 "unconnected-(J18-PadF29)")
	(net 746 "/SoM_IO2/DP0.TX3_C+")
	(net 747 "unconnected-(J1C-GPIO23-PadG55)")
	(net 748 "unconnected-(J1I-GPIO19-PadK56)")
	(net 749 "unconnected-(J1I-FSI_GPIO13-PadF36)")
	(net 750 "unconnected-(J1I-GPIO33-PadC54)")
	(net 751 "/M.2/PCIe_{C5x4}.~{CLKREQ}")
	(net 752 "/Expansion connector/PCIe_{C3x2}.RX0-")
	(net 753 "Net-(J18-PadK01)")
	(net 754 "unconnected-(J1B-UPHY_TX16_P-PadK17)")
	(net 755 "unconnected-(J1G-FSI_GPIO21-PadJ10)")
	(net 756 "/Expansion connector/DP2.TX2+")
	(net 757 "unconnected-(J1I-UART4_RTS-PadL4)")
	(net 758 "Net-(J1A-GPIO31)")
	(net 759 "unconnected-(J1H-GPIO29-PadA7)")
	(net 760 "Net-(J1A-MODULE_POWER_GOOD)")
	(net 761 "Net-(J18-PadH02)")
	(net 762 "Net-(J1A-SYSTEM_OC_N)")
	(net 763 "unconnected-(J1D-MCLK05-PadL57)")
	(net 764 "unconnected-(J1H-GPIO11-PadB8)")
	(net 765 "unconnected-(J1I-UART4_CTS-PadL6)")
	(net 766 "/Recovery USB/USB0.D+")
	(net 767 "unconnected-(J1G-FSI_GPIO25-PadD9)")
	(net 768 "unconnected-(J1B-UPHY_TX5_P-PadH20)")
	(net 769 "unconnected-(J1G-FSI_GPIO04-PadK36)")
	(net 770 "/SoM_IO2/USBSS2.RX+")
	(net 771 "/Expansion connector/DP1.TX1+")
	(net 772 "unconnected-(J1B-UPHY_RX15_P-PadA30)")
	(net 773 "unconnected-(J1H-I2S3_SCLK-PadC59)")
	(net 774 "unconnected-(J1G-FSI_GPIO06-PadJ39)")
	(net 775 "/M.2/PCIe_{C5x4}.~{RST}")
	(net 776 "/Expansion connector/DP3.AUX+")
	(net 777 "Net-(J18-PadB40)")
	(net 778 "unconnected-(J1C-UPHY_REFCLK1_N-PadF25)")
	(net 779 "unconnected-(J1G-FSI_GPIO05-PadJ38)")
	(net 780 "/SoM_IO/~{PDC_I2C1_IRQ}_1V8")
	(net 781 "/Expansion connector/DP1.HPD")
	(net 782 "/Expansion connector/PCIe_{C3x2}.RX1+")
	(net 783 "/Expansion connector/CAN3.DOUT")
	(net 784 "unconnected-(J18-PadB24)")
	(net 785 "unconnected-(J1I-FSI_GPIO14-PadE35)")
	(net 786 "/SoM_IO2/DP0.TX2+")
	(net 787 "unconnected-(J1I-PWM01-PadK57)")
	(net 788 "/SoM_IO2/DP0.HPD")
	(net 789 "/Expansion connector/DP2.HPD")
	(net 790 "/Expansion connector/PCIe_{C2x1}.RX0+")
	(net 791 "unconnected-(J1C-UPHY_REFCLK0_P-PadF16)")
	(net 792 "/SoM_IO2/DP0.TX1-")
	(net 793 "/SoM_Power/~{SLEEP_REQ}")
	(net 794 "/Expansion connector/DP1.TX3+")
	(net 795 "Net-(J1A-POWER_INT_N)")
	(net 796 "Net-(J1A-UFS0_RST_N)")
	(net 797 "/Expansion connector/PCIe_{C3x2}.RX0+")
	(net 798 "unconnected-(J1I-FSI_GPIO19-PadE50)")
	(net 799 "/SoM_IO2/DP0.TX3_C-")
	(net 800 "/Recovery USB/USBC2_RX1_N")
	(net 801 "/Recovery USB/USBC2_CC2")
	(net 802 "/Recovery USB/USBC2_RX1_P")
	(net 803 "unconnected-(J3-SBU_{1}-PadA8)")
	(net 804 "/Recovery USB/USBC2_RX2_P")
	(net 805 "unconnected-(J3-SBU_{2}-PadB8)")
	(net 806 "/Recovery USB/USBC2_CC1")
	(net 807 "/Recovery USB/USBC2_RX2_N")
	(net 808 "unconnected-(J4-Pad10)")
	(net 809 "unconnected-(J4-Pad7)")
	(net 810 "/USB Debug, PD/MISO")
	(net 811 "/USB Debug, PD/MOSI")
	(net 812 "/USB Debug, PD/~{CS}")
	(net 813 "unconnected-(J7-SBU_{1}-PadA8)")
	(net 814 "unconnected-(J7-SBU_{2}-PadB8)")
	(net 815 "/USB DP Alt mode/USBC1_SBU_P")
	(net 816 "/USB DP Alt mode/USBC1_CC2")
	(net 817 "/USB DP Alt mode/USBC1_CC1")
	(net 818 "/USB DP Alt mode/USBC1_RX2_P")
	(net 819 "/USB DP Alt mode/USBC1_RX1_N")
	(net 820 "/USB DP Alt mode/USBC1_RX2_N")
	(net 821 "/USB DP Alt mode/USBC1_SBU_N")
	(net 822 "/USB DP Alt mode/USBC1_RX1_P")
	(net 823 "/SFP/SCL_SFP")
	(net 824 "/SFP/SDA_SFP")
	(net 825 "/M.2/~{CLKREQ_M}")
	(net 826 "/M.2/~{PEWAKE_M}")
	(net 827 "/M.2/~{PERST_M}")
	(net 828 "unconnected-(J14-PER1_P-Pad65)")
	(net 829 "unconnected-(J14-PER1_N-Pad67)")
	(net 830 "unconnected-(J14-PET1_P-Pad59)")
	(net 831 "/M.2/~{PERST_E}")
	(net 832 "/M.2/M2_E_SUSCLK")
	(net 833 "/M.2/~{PEWAKE_E}")
	(net 834 "/M.2/~{CLKREQ_E}")
	(net 835 "unconnected-(J14-PET1_N-Pad61)")
	(net 836 "unconnected-(J14-REFCLK1_P-Pad71)")
	(net 837 "unconnected-(J14-REFCLK1_N-Pad73)")
	(net 838 "/Peripherals/I2C_CONN1_3V3")
	(net 839 "/Peripherals/I2C_CONN2_3V3")
	(net 840 "unconnected-(J18-PadE22)")
	(net 841 "unconnected-(J18-PadB25)")
	(net 842 "/Expansion connector/I2C7.SDA")
	(net 843 "/Expansion connector/PCIe_{C2x1}.CLK+")
	(net 844 "unconnected-(J18-PadE10)")
	(net 845 "unconnected-(J18-PadE27)")
	(net 846 "unconnected-(J18-PadH34)")
	(net 847 "unconnected-(J18-PadE30)")
	(net 848 "unconnected-(J18-PadE19)")
	(net 849 "/Expansion connector/GPIO.18")
	(net 850 "/I2C_{SYS}.SDA")
	(net 851 "/Expansion connector/PCIe_{C2x1}.CLK-")
	(net 852 "unconnected-(J18-PadH05)")
	(net 853 "/I2C_{SYS}.SCL")
	(net 854 "unconnected-(J18-PadE07)")
	(net 855 "unconnected-(J18-PadE31)")
	(net 856 "/Expansion connector/I2C8.SDA")
	(net 857 "/Expansion connector/I2C8.SCL")
	(net 858 "unconnected-(J18-PadE06)")
	(net 859 "unconnected-(J18-PadH38)")
	(net 860 "unconnected-(J18-PadE03)")
	(net 861 "/Expansion connector/GPIO.27")
	(net 862 "unconnected-(J18-PadE18)")
	(net 863 "unconnected-(J18-PadE15)")
	(net 864 "unconnected-(J18-PadH37)")
	(net 865 "unconnected-(J18-PadE02)")
	(net 866 "/Expansion connector/I2C7.SCL")
	(net 867 "unconnected-(J20-Pad7)")
	(net 868 "/SoM_IO2/TC_JTAG_TDI")
	(net 869 "/SoM_IO2/TC_JTAG_TMS")
	(net 870 "/SoM_IO2/TC_JTAG_TRST_N")
	(net 871 "/SoM_IO2/TC_JTAG_TCK")
	(net 872 "/SoM_IO2/TC_JTAG_TDO")
	(net 873 "unconnected-(J1I-FSI_GPIO32-PadA4)")
	(net 874 "unconnected-(J1C-GPIO25-PadK49)")
	(net 875 "Net-(J1A-FSI_GPIO03)")
	(net 876 "unconnected-(J1I-GPIO70-PadK52)")
	(net 877 "unconnected-(J1I-FSI_GPIO34-PadA5)")
	(net 878 "/SoM_IO/M2_E_W_DIS_2_1V8")
	(net 879 "/DCDC/12V_PHASE")
	(net 880 "/DCDC/12V_OUT")
	(net 881 "/USB Debug, PD/FTDI_CBUS_EN")
	(net 882 "unconnected-(J1I-SGMII0_MDC-PadE6)")
	(net 883 "Net-(Q10-G)")
	(net 884 "Net-(Q8-D)")
	(net 885 "Net-(Q10-D)")
	(net 886 "Net-(Q11-D)")
	(net 887 "Net-(Q17-D)")
	(net 888 "Net-(Q18-D)")
	(net 889 "/Recovery USB/USBC2_ID")
	(net 890 "Net-(Q19-D)")
	(net 891 "Net-(D40-C)")
	(net 892 "Net-(Q22-G)")
	(net 893 "Net-(Y1-EN)")
	(net 894 "/SoM_IO2/SFI_CLK+")
	(net 895 "/SoM_IO2/SFI_CLK-")
	(net 896 "/DCDC/16V_VDD")
	(net 897 "/SoM_IO2/C2_CLK+")
	(net 898 "/SoM_IO2/C2_REFCLK+")
	(net 899 "unconnected-(J1C-GPIO26-PadH51)")
	(net 900 "/DCDC/16V_VDRV")
	(net 901 "/DCDC/16V_BOOT")
	(net 902 "/DCDC/16V_PHASE")
	(net 903 "/DCDC/16V_OUT")
	(net 904 "+20V")
	(net 905 "/DCDC/20V_VDD")
	(net 906 "/SoM_IO/M2_E_W_DIS_1_1V8")
	(net 907 "Net-(J1A-GPIO39)")
	(net 908 "unconnected-(J1I-GPIO03-PadD54)")
	(net 909 "/USB Hub/USBC3_ISET")
	(net 910 "/USB Hub/PRT_CTL3")
	(net 911 "/USB Hub/PRT_CTL2")
	(net 912 "/USB Hub/PRT_CTL4")
	(net 913 "/USB Hub/CFG_STRAP1")
	(net 914 "/USB Hub/PRT_CTL1")
	(net 915 "/USB Hub/CFG_STRAP2")
	(net 916 "/USB Hub/TEST3")
	(net 917 "/USB Hub/TEST2")
	(net 918 "unconnected-(J1I-FSI_GPIO33-PadD6)")
	(net 919 "Net-(U21-RBIAS)")
	(net 920 "/USB Hub/TEST1")
	(net 921 "/USB Hub/HUB_SPI_D2")
	(net 922 "/USB Hub/HUB_SPI_D1")
	(net 923 "/USB Debug, PD/SPI_{HUB_DEBUG}.MISO")
	(net 924 "/USB Hub/HUB_SPI_D3")
	(net 925 "/USB Hub/HUB_SPI_D0")
	(net 926 "/USB Debug, PD/SPI_{HUB_DEBUG}.MOSI")
	(net 927 "/USB Hub/HUB_SPI_CLK")
	(net 928 "/USB Debug, PD/SPI_{HUB_DEBUG}.SCK")
	(net 929 "/USB Debug, PD/SPI_{HUB_DEBUG}.~{CS0}")
	(net 930 "/USB Hub/HUB_SPI_CE_N")
	(net 931 "/USB Hub/CFG_STRAP3")
	(net 932 "/USB Hub/USBC4_VBUS_MON")
	(net 933 "/USB Debug, PD/PDC_RESET")
	(net 934 "/USB Debug, PD/PDC_ADCIN1")
	(net 935 "/USB Debug, PD/PDC_ADCIN2")
	(net 936 "/USB Debug, PD/PDC_MISO")
	(net 937 "Net-(J10-Pad41)")
	(net 938 "Net-(J10-Pad42)")
	(net 939 "/USB Debug, PD/~{PDC_CS}")
	(net 940 "/USB Debug, PD/PDC_MOSI")
	(net 941 "/USB Debug, PD/PDC_SCLK")
	(net 942 "/USB DP Alt mode/USBC1_FLIP")
	(net 943 "/USB DP Alt mode/USBC1_CTL0")
	(net 944 "/USB DP Alt mode/USBC1_CTL1")
	(net 945 "/USB Debug, PD/DEBUG_SCL")
	(net 946 "/USB Debug, PD/DEBUG_SDA")
	(net 947 "/USB Debug, PD/PDC_I2C2_SCL")
	(net 948 "/USB DP Alt mode/USBC_HPD")
	(net 949 "/USB Debug, PD/PDC_HPD2")
	(net 950 "/USB Debug, PD/PDC_I2C2_SDA")
	(net 951 "/USB Debug, PD/PDC_GPIO14")
	(net 952 "/USB Debug, PD/PDC_GPIO15")
	(net 953 "/USB Debug, PD/PDC_I2C1_IRQn")
	(net 954 "/SoM_IO/~{PDC_I2C1_IRQ}")
	(net 955 "/USB Debug, PD/FTDI_CBUS3{slash}SCL")
	(net 956 "/USB Debug, PD/FTDI_CBUS0{slash}SDA")
	(net 957 "/USB DP Alt mode/HPDIN")
	(net 958 "Net-(U34-TXD)")
	(net 959 "/SoM_IO/UART3_DEBUG.TX")
	(net 960 "/SoM_IO/UART3_DEBUG.RX")
	(net 961 "Net-(U34-RXD)")
	(net 962 "/SoM_IO/USBC1_FLG")
	(net 963 "/USB DP Alt mode/USBC1_I2C_EN")
	(net 964 "/USB DP Alt mode/USBC1_SSEQ0")
	(net 965 "/USB DP Alt mode/USBC1_SSEQ1")
	(net 966 "/USB DP Alt mode/USBC1_DPEQ0")
	(net 967 "/USB DP Alt mode/USBC1_DPEQ1")
	(net 968 "/USB DP Alt mode/USBC1_EQ0")
	(net 969 "/USB DP Alt mode/USBC1_EQ1")
	(net 970 "/USB DP Alt mode/USBC1_5V_PEN")
	(net 971 "Net-(U35-EN)")
	(net 972 "Net-(U35-ISET)")
	(net 973 "/USB Debug, PD/USB_FTDI_P")
	(net 974 "/USB Debug, PD/USB_FTDI_N")
	(net 975 "/USB Debug, PD/USBC0_5V_PEN")
	(net 976 "/USB Debug, PD/USBC0_FLG")
	(net 977 "Net-(U40-EN)")
	(net 978 "/USB Debug, PD/USBC0_ISET")
	(net 979 "/CSI/CSIA_I2C_VCC")
	(net 980 "/CSI/I2C_MUX_A0")
	(net 981 "/CSI/I2C_{CAM}.SDA")
	(net 982 "/CSI/I2C_MUX_SDA")
	(net 983 "/CSI/I2C_{CAM}.SCL")
	(net 984 "/CSI/I2C_MUX_SCL")
	(net 985 "/CSI/SCL_CAM0")
	(net 986 "/CSI/SDA_CAM1")
	(net 987 "/CSI/SDA_CAM0")
	(net 988 "/CSI/SCL_CAM1")
	(net 989 "/CSI/I2C_MUX_RESET")
	(net 990 "/CSI/CSIB_I2C_VCC")
	(net 991 "/CSI/SDA_CAM3")
	(net 992 "/CSI/SCL_CAM3")
	(net 993 "/CSI/SDA_CAM2")
	(net 994 "/CSI/SCL_CAM2")
	(net 995 "/CSI/CSIA_5V_ISET")
	(net 996 "/CSI/CSIA_3V3_ISET")
	(net 997 "/CSI/CSIB_5V_ISET")
	(net 998 "/CSI/CSIB_3V3_ISET")
	(net 999 "/SFP/I2C_{SFP}.SDA")
	(net 1000 "/SFP/I2C_{SFP}.SCL")
	(net 1001 "/SoM_IO2/C2_CLK-")
	(net 1002 "/SoM_IO2/C2_REFCLK-")
	(net 1003 "/SFP/SFP_LEDY")
	(net 1004 "/SFP/SFP_LEDG")
	(net 1005 "/M.2/SUSCLK")
	(net 1006 "unconnected-(J14-PCM_IN-Pad12)")
	(net 1007 "unconnected-(J14-PCM_SYNC-Pad10)")
	(net 1008 "Net-(D40-A)")
	(net 1009 "Net-(U53-ISET)")
	(net 1010 "Net-(U55-ISET)")
	(net 1011 "/Recovery USB/USBC2_ADDR")
	(net 1012 "/Recovery USB/USBC2_PORT")
	(net 1013 "/Recovery USB/USBC2_DIR")
	(net 1014 "/Recovery USB/USBC2_FAULT_N")
	(net 1015 "/USB Hub/USBC4_ISET")
	(net 1016 "/USB Hub/USBC3_VBUS_MON")
	(net 1017 "/Recovery USB/USBC2_PEN")
	(net 1018 "/Recovery USB/USBC2_VBUS_DET")
	(net 1019 "Net-(D57-A)")
	(net 1020 "/Recovery USB/USBC2_ISET")
	(net 1021 "/Recovery USB/~{USBC2_EN_MUX}")
	(net 1022 "/Recovery USB/~{USBC2_EN_CC}")
	(net 1023 "/Recovery USB/USBC2_I_MODE")
	(net 1024 "/Recovery USB/USBC2_I2C_SDA")
	(net 1025 "/Recovery USB/USBC2_I2C_SCL")
	(net 1026 "/Recovery USB/~{USBC2_INT}")
	(net 1027 "Net-(U70-~{CLR})")
	(net 1028 "Net-(U59-B3Y)")
	(net 1029 "Net-(U59-B2Y)")
	(net 1030 "Net-(U59-B1Y)")
	(net 1031 "Net-(U59-B4)")
	(net 1032 "/SoM_Power/~{FORCE_SHDN}")
	(net 1033 "Net-(U70-OUT)")
	(net 1034 "/DCDC/1V15_SW")
	(net 1035 "Net-(U70-~{INT})")
	(net 1036 "Net-(R307-Pad2)")
	(net 1037 "Net-(U72-~{MR})")
	(net 1038 "unconnected-(SW2-Pad1)")
	(net 1039 "/USB Debug, PD/PDC_I2C3_SCL")
	(net 1040 "/USB Debug, PD/PDC_I2C3_SDA")
	(net 1041 "/USB Debug, PD/~{PDC_I2C3_IRQ}")
	(net 1042 "/USB Debug, PD/PDC_I2C2_IRQn")
	(net 1043 "/Peripherals/FAN_VDD")
	(net 1044 "Net-(U33-CAD_SNK{slash}RSVD1)")
	(net 1045 "/CSI/MUX_I2C_4_SDA")
	(net 1046 "/CSI/MUX_I2C_4_SCL")
	(net 1047 "/CSI/MUX_I2C_5_SDA")
	(net 1048 "/CSI/MUX_I2C_5_SCL")
	(net 1049 "/CSI/MUX_I2C_6_SDA")
	(net 1050 "/CSI/MUX_I2C_6_SCL")
	(net 1051 "/CSI/MUX_I2C_7_SDA")
	(net 1052 "/CSI/MUX_I2C_7_SCL")
	(net 1053 "unconnected-(U12-GL-Pad10)")
	(net 1054 "unconnected-(U12-GL-Pad10)_1")
	(net 1055 "unconnected-(U12-GL-Pad10)_2")
	(net 1056 "unconnected-(U13-P_{GOOD}-Pad14)")
	(net 1057 "unconnected-(U13-GL-Pad10)")
	(net 1058 "unconnected-(U13-GL-Pad10)_1")
	(net 1059 "unconnected-(U13-GL-Pad10)_2")
	(net 1060 "unconnected-(U14-NCI-Pad28)")
	(net 1061 "unconnected-(U14-NCI-Pad11)")
	(net 1062 "unconnected-(U14-NC-Pad21)")
	(net 1063 "unconnected-(U14-NC-Pad24)")
	(net 1064 "unconnected-(U14-GPIO_00-Pad3)")
	(net 1065 "unconnected-(U14-NCI-Pad12)")
	(net 1066 "unconnected-(U14-NCI-Pad10)")
	(net 1067 "unconnected-(U14-NC-Pad19)")
	(net 1068 "unconnected-(U14-GPIO_01-Pad4)")
	(net 1069 "unconnected-(U14-GPIO_02-Pad7)")
	(net 1070 "unconnected-(U14-NCI-Pad31)")
	(net 1071 "unconnected-(U14-NCI-Pad26)")
	(net 1072 "unconnected-(U14-NCI-Pad5)")
	(net 1073 "unconnected-(U14-NCI-Pad25)")
	(net 1074 "unconnected-(U14-NCI-Pad13)")
	(net 1075 "unconnected-(U14-NCI-Pad27)")
	(net 1076 "unconnected-(U14-NCI-Pad15)")
	(net 1077 "unconnected-(U14-NC-Pad6)")
	(net 1078 "Net-(U21-XTALI)")
	(net 1079 "unconnected-(U21-ATEST-Pad96)")
	(net 1080 "unconnected-(U21-USB3DN_TXDM3-Pad84)")
	(net 1081 "/DCDC/20V_VDRV")
	(net 1082 "unconnected-(U21-PF7-Pad48)")
	(net 1083 "unconnected-(U21-PF29-Pad74)")
	(net 1084 "/USB Hub/DP1_VCONN1")
	(net 1085 "/USB Hub/DP2_DISCH")
	(net 1086 "/DCDC/20V_BOOT")
	(net 1087 "unconnected-(U21-XTALO-Pad97)")
	(net 1088 "/SoM_IO2/DP0.AUX_C+")
	(net 1089 "Net-(Q1-D)")
	(net 1090 "unconnected-(U21-PF31-Pad3)")
	(net 1091 "unconnected-(U21-USB3DN_TXDP3-Pad83)")
	(net 1092 "unconnected-(U21-PF9-Pad50)")
	(net 1093 "unconnected-(U21-PF27-Pad76)")
	(net 1094 "unconnected-(U21-PF30-Pad2)")
	(net 1095 "/USB Hub/DP1_VCONN2")
	(net 1096 "Net-(Q9-D)")
	(net 1097 "unconnected-(U21-PF6-Pad47)")
	(net 1098 "unconnected-(U21-PF8-Pad49)")
	(net 1099 "/USB Hub/DP2_VCONN1")
	(net 1100 "/Peripherals/TPM_RST")
	(net 1101 "Net-(Y5-EN)")
	(net 1102 "unconnected-(U21-PF28-Pad77)")
	(net 1103 "/USB Hub/DP1_DISCH")
	(net 1104 "/DCDC/20V_PHASE")
	(net 1105 "/DCDC/20V_OUT")
	(net 1106 "/USB Hub/DP2_VCONN2")
	(net 1107 "unconnected-(U29-PadEP)")
	(net 1108 "Net-(D6-A)")
	(net 1109 "unconnected-(U30A-GPIO12-Pad40)")
	(net 1110 "unconnected-(U30A-GPIO13-Pad41)")
	(net 1111 "Net-(U21-USB2DN_DP3)")
	(net 1112 "/SoM_IO2/DP0.AUX_C-")
	(net 1113 "/M.2/M2_E.W_DIS_1")
	(net 1114 "unconnected-(U34-~{RTS}-Pad16)")
	(net 1115 "unconnected-(U34-~{CTS}-Pad4)")
	(net 1116 "unconnected-(U36-Pad4)")
	(net 1117 "unconnected-(U36-Pad5)")
	(net 1118 "unconnected-(U36-Pad4)_1")
	(net 1119 "unconnected-(U36-Pad5)_1")
	(net 1120 "unconnected-(U43-EP-Pad25)")
	(net 1121 "unconnected-(U53-FLG-Pad3)")
	(net 1122 "unconnected-(U55-FLG-Pad3)")
	(net 1123 "unconnected-(U59-NC-Pad9)")
	(net 1124 "unconnected-(U59-NC-Pad6)")
	(net 1125 "unconnected-(Y1-NC-Pad2)")
	(net 1126 "Net-(U21-USB2DN_DM3)")
	(net 1127 "Net-(D42-A)")
	(net 1128 "/Recovery USB/USBSS_RX_N")
	(net 1129 "/Recovery USB/USBSS_TX_N")
	(net 1130 "/Recovery USB/USBSS_RX_P")
	(net 1131 "/Recovery USB/USBSS_TX_P")
	(net 1132 "/USB Hub/USBSS_TX_P")
	(net 1133 "/USB Hub/USBSS_RX_P")
	(net 1134 "/USB Hub/USBSS_TX_N")
	(net 1135 "/USB Hub/USBSS_RX_N")
	(net 1136 "unconnected-(J18-PadZ21)")
	(net 1137 "unconnected-(J18-PadZ20)")
	(net 1138 "Net-(U21-USB2DN_DP4)")
	(net 1139 "unconnected-(U30C-DRAIN2-Pad52)")
	(net 1140 "unconnected-(U30B-DRAIN1-Pad15)")
	(net 1141 "Net-(U21-USB2DN_DM4)")
	(net 1142 "Net-(U21-USB3DN_RXDP3)")
	(net 1143 "unconnected-(U30B-DRAIN1-Pad15)_1")
	(net 1144 "unconnected-(U30B-DRAIN1-Pad15)_2")
	(net 1145 "unconnected-(U30B-DRAIN1-Pad15)_3")
	(net 1146 "unconnected-(U30B-DRAIN1-Pad15)_4")
	(net 1147 "unconnected-(U30B-DRAIN1-Pad15)_5")
	(net 1148 "unconnected-(U30C-DRAIN2-Pad52)_1")
	(net 1149 "unconnected-(U30C-DRAIN2-Pad52)_2")
	(net 1150 "unconnected-(U30C-DRAIN2-Pad52)_3")
	(net 1151 "unconnected-(U30C-DRAIN2-Pad52)_4")
	(net 1152 "unconnected-(U30C-DRAIN2-Pad52)_5")
	(net 1153 "unconnected-(U30C-DRAIN2-Pad52)_6")
	(net 1154 "unconnected-(U30C-DRAIN2-Pad52)_7")
	(net 1155 "unconnected-(U30B-DRAIN1-Pad15)_6")
	(net 1156 "unconnected-(U30B-DRAIN1-Pad15)_7")
	(net 1157 "unconnected-(U30B-DRAIN1-Pad15)_8")
	(net 1158 "unconnected-(U30B-DRAIN1-Pad15)_9")
	(net 1159 "unconnected-(U30C-DRAIN2-Pad52)_8")
	(net 1160 "unconnected-(U30C-DRAIN2-Pad52)_9")
	(net 1161 "Net-(U50-IN-)")
	(net 1162 "Net-(U60-IN-)")
	(net 1163 "Net-(U21-USB3DN_RXDM3)")
	(net 1164 "/USB Hub/VBUS_MON_UP")
	(net 1165 "/USB Hub/HUB_~{HOLD}")
	(net 1166 "/USB Hub/HUB_~{WP}")
	(net 1167 "/M.2/M2_E.W_DIS_2")
	(net 1168 "Net-(U30A-HPD1)")
	(net 1169 "unconnected-(U8-GL-Pad10)")
	(net 1170 "unconnected-(U8-GL-Pad10)_1")
	(net 1171 "unconnected-(U8-GL-Pad10)_2")
	(net 1172 "unconnected-(U8-P_{GOOD}-Pad14)")
	(net 1173 "unconnected-(U21-PF14-Pad57)")
	(net 1174 "unconnected-(U21-PF18-Pad61)")
	(net 1175 "unconnected-(U21-PF12-Pad54)")
	(net 1176 "unconnected-(U30B-C1_USB_P-Pad50)")
	(net 1177 "unconnected-(U30C-C2_USB_P-Pad54)")
	(net 1178 "unconnected-(U30B-C1_USB_N-Pad53)")
	(net 1179 "unconnected-(U30C-C2_USB_N-Pad55)")
	(net 1180 "unconnected-(Y5-NC-Pad2)")
	(net 1181 "/DCDC/5V_SW")
	(net 1182 "/DCDC/3V3_SW")
	(net 1183 "/DCDC/16V_SW")
	(net 1184 "/DCDC/20V_SW")
	(net 1185 "/DCDC/1V8_SW")
	(net 1186 "/DCDC/12V_SW")
	(net 1187 "Net-(U22-IN-)")
	(net 1188 "unconnected-(U11-GL-Pad10)")
	(net 1189 "unconnected-(U11-GL-Pad10)_1")
	(net 1190 "unconnected-(U11-GL-Pad10)_2")
	(net 1191 "/SoM_IO2/DP1.TX0_C+")
	(net 1192 "unconnected-(J7-TX_{2}+-PadB2)")
	(net 1193 "unconnected-(J7-TX_{1}--PadA3)")
	(net 1194 "unconnected-(J7-TX_{1}+-PadA2)")
	(net 1195 "unconnected-(J7-RX_{2}--PadA10)")
	(net 1196 "unconnected-(J7-RX_{2}+-PadA11)")
	(net 1197 "unconnected-(J7-RX_{1}--PadB10)")
	(net 1198 "unconnected-(J7-TX_{2}--PadB3)")
	(net 1199 "unconnected-(J7-RX_{1}+-PadB11)")
	(net 1200 "Net-(Q5-G)")
	(net 1201 "Net-(Q23-G)")
	(net 1202 "Net-(Q24-G)")
	(net 1203 "Net-(Q25-G)")
	(net 1204 "/DCDC/12V_MODE1")
	(net 1205 "/DCDC/12V_MODE2")
	(net 1206 "/DCDC/12V_FB")
	(net 1207 "/DCDC/16V_MODE1")
	(net 1208 "/DCDC/20V_MODE1")
	(net 1209 "/SoM_IO2/DP1.TX1_C+")
	(net 1210 "/DCDC/20V_MODE2")
	(net 1211 "/DCDC/20V_EN")
	(net 1212 "/DCDC/5V_MODE1")
	(net 1213 "/DCDC/3V3_MODE1")
	(net 1214 "/DCDC/16V_MODE2")
	(net 1215 "/DCDC/5V_MODE2")
	(net 1216 "/DCDC/3V3_MODE2")
	(net 1217 "/DCDC/5V_FB")
	(net 1218 "/DCDC/3V3_FB")
	(net 1219 "/DCDC/16V_FB")
	(net 1220 "/DCDC/20V_FB")
	(net 1221 "Net-(U66-IN-)")
	(net 1222 "/DCDC/1V8_FB")
	(net 1223 "/SoM_IO2/DP1.TX2_C+")
	(net 1224 "unconnected-(U61-STAT-Pad4)")
	(net 1225 "unconnected-(U62-STAT-Pad4)")
	(net 1226 "unconnected-(U63-STAT-Pad4)")
	(net 1227 "unconnected-(U64-STAT-Pad4)")
	(net 1228 "unconnected-(U65-P_{GOOD}-Pad14)")
	(net 1229 "unconnected-(U65-GL-Pad10)")
	(net 1230 "unconnected-(U65-GL-Pad10)_1")
	(net 1231 "unconnected-(U65-GL-Pad10)_2")
	(net 1232 "/DCDC/1V15_FB")
	(net 1233 "Net-(U21-PF19)")
	(net 1234 "Net-(U21-PF26)")
	(net 1235 "Net-(Q30-S)")
	(net 1236 "Net-(D58-A)")
	(net 1237 "Net-(D58-C)")
	(net 1238 "Net-(D59-C)")
	(net 1239 "Net-(D59-A)")
	(net 1240 "Net-(D60-A)")
	(net 1241 "Net-(D60-C)")
	(net 1242 "/SoM_IO/USBC2_ID_1V8")
	(net 1243 "Net-(U23-FLG)")
	(net 1244 "/SoM_IO/USBC2_VBUS_DET_1V8")
	(net 1245 "Net-(R265-Pad1)")
	(net 1246 "/Recovery USB/USBC2_VBUS_DET_MUX")
	(net 1247 "/SoM_IO2/DP1.TX3_C+")
	(net 1248 "/SoM_IO2/DP1.TX0_C-")
	(net 1249 "/SoM_IO2/DP1.TX1_C-")
	(net 1250 "/SoM_IO2/DP1.TX2_C-")
	(net 1251 "/SoM_IO2/DP1.TX3_C-")
	(net 1252 "/SoM_IO2/DP1.AUX_C+")
	(net 1253 "/SoM_IO2/DP1.AUX_C-")
	(net 1254 "/SoM_IO2/DP2.TX0_C+")
	(net 1255 "/SoM_IO2/DP2.TX1_C+")
	(net 1256 "/SoM_IO2/DP2.TX2_C+")
	(net 1257 "/SoM_IO2/DP2.TX3_C+")
	(net 1258 "/SoM_IO2/DP2.TX0_C-")
	(net 1259 "/SoM_IO2/DP2.TX1_C-")
	(net 1260 "/SoM_IO2/DP2.TX2_C-")
	(net 1261 "/SoM_IO2/DP2.TX3_C-")
	(net 1262 "/SoM_IO2/DP2.AUX_C+")
	(net 1263 "/SoM_IO2/DP2.AUX_C-")
	(net 1264 "/SoM_IO2/DP3.TX0_C+")
	(net 1265 "/SoM_IO2/DP3.TX1_C+")
	(net 1266 "/SoM_IO2/DP3.TX2_C+")
	(net 1267 "/SoM_IO2/DP3.TX3_C+")
	(net 1268 "/SoM_IO2/DP3.TX0_C-")
	(net 1269 "/SoM_IO2/DP3.TX1_C-")
	(net 1270 "/SoM_IO2/DP3.TX2_C-")
	(net 1271 "/SoM_IO2/DP3.TX3_C-")
	(net 1272 "/SoM_IO2/DP3.AUX_C+")
	(net 1273 "/SoM_IO2/DP3.AUX_C-")
	(net 1274 "/DCDC/5V_{AON}_VDD")
	(net 1275 "/DCDC/5V_{AON}_VDRV")
	(net 1276 "/DCDC/5V_{AON}_BOOT")
	(net 1277 "/DCDC/5V_{AON}_PHASE")
	(net 1278 "/DCDC/5V_{AON}_OUT")
	(net 1279 "Net-(U76-IN-)")
	(net 1280 "Net-(U76-IN+)")
	(net 1281 "Net-(U50-IN+)")
	(net 1282 "Net-(U60-IN+)")
	(net 1283 "Net-(U22-IN+)")
	(net 1284 "Net-(U66-IN+)")
	(net 1285 "/SoM_Power/VIN_PWR_ON")
	(net 1286 "Net-(D61-A)")
	(net 1287 "/SoM_Power/MODULE_POWER_ON")
	(net 1288 "unconnected-(J1K-GPIO17-PadA62)")
	(net 1289 "unconnected-(J1K-GPIO43-PadA38)")
	(net 1290 "unconnected-(J1K-GPIO42-PadF59)")
	(net 1291 "unconnected-(J1K-GPIO37-PadA39)")
	(net 1292 "/SoM_IO/GPIO_EXP_IRQ_1V8")
	(net 1293 "/DCDC/CARRIER_PWR_ON")
	(net 1294 "unconnected-(J1K-GPIO67-PadJ19)")
	(net 1295 "unconnected-(J1K-GPIO38-PadE59)")
	(net 1296 "/SFP/SFP_MOD_ABS")
	(net 1297 "/DCDC/5V_{AON}_SW")
	(net 1298 "Net-(Q37-G)")
	(net 1299 "Net-(Q28-G)")
	(net 1300 "Net-(Q34-D)")
	(net 1301 "Net-(Q35-D)")
	(net 1302 "Net-(Q37-D)")
	(net 1303 "Net-(Q38-D)")
	(net 1304 "Net-(U74-2Y)")
	(net 1305 "/DCDC/5V_{AON}_EN")
	(net 1306 "/DCDC/5V_{AON}_MODE1")
	(net 1307 "/DCDC/5V_{AON}_MODE2")
	(net 1308 "/DCDC/5V_{AON}_FB")
	(net 1309 "/Peripherals/GPIO_EXP_IRQ")
	(net 1310 "Net-(U71-~{RESET})")
	(net 1311 "Net-(U71-ADDR)")
	(net 1312 "/Peripherals/GPIOEX_P0_3")
	(net 1313 "/Peripherals/GPIOEX_P0_2")
	(net 1314 "/Peripherals/GPIOEX_P0_1")
	(net 1315 "/Peripherals/GPIOEX_P0_0")
	(net 1316 "/Peripherals/GPIOEX_P0_4")
	(net 1317 "/Peripherals/GPIOEX_P0_5")
	(net 1318 "/Peripherals/GPIOEX_P0_6")
	(net 1319 "/Peripherals/GPIOEX_P0_7")
	(net 1320 "unconnected-(U1-NC-Pad9)")
	(net 1321 "unconnected-(U1-NC-Pad6)")
	(net 1322 "unconnected-(U12-P_{GOOD}-Pad14)")
	(net 1323 "unconnected-(U32-NC-Pad4)")
	(net 1324 "unconnected-(U71-EP-Pad17)")
	(net 1325 "unconnected-(U75-GL-Pad10)")
	(net 1326 "unconnected-(U75-GL-Pad10)_1")
	(net 1327 "unconnected-(U75-GL-Pad10)_2")
	(net 1328 "unconnected-(U80-NC-Pad9)")
	(net 1329 "unconnected-(U80-NC-Pad6)")
	(net 1330 "Net-(Q21-D1)")
	(net 1331 "Net-(Q26-D1)")
	(net 1332 "Net-(Q27-D1)")
	(net 1333 "Net-(Q29-D1)")
	(net 1334 "unconnected-(J14-VENDOR_2-Pad40)")
	(net 1335 "unconnected-(J14-VENDOR_3-Pad42)")
	(net 1336 "unconnected-(J14-VENDOR_1-Pad38)")
	(net 1337 "unconnected-(J14-~{UART_WAKE}-Pad20)")
	(net 1338 "unconnected-(U5-B1-Pad20)")
	(net 1339 "unconnected-(U5-A8-Pad9)")
	(net 1340 "unconnected-(U78-B3-Pad18)")
	(net 1341 "unconnected-(J18-PadM10)")
	(net 1342 "unconnected-(J18-PadL13)")
	(net 1343 "unconnected-(J18-PadL09)")
	(net 1344 "unconnected-(J18-PadL28)")
	(net 1345 "unconnected-(J18-PadM18)")
	(net 1346 "unconnected-(J18-PadL25)")
	(net 1347 "unconnected-(J18-PadM19)")
	(net 1348 "unconnected-(J18-PadM34)")
	(net 1349 "unconnected-(J18-PadM22)")
	(net 1350 "unconnected-(J18-PadM15)")
	(net 1351 "unconnected-(J18-PadL24)")
	(net 1352 "unconnected-(J18-PadL29)")
	(net 1353 "unconnected-(J18-PadM31)")
	(net 1354 "unconnected-(J18-PadM35)")
	(net 1355 "unconnected-(J18-PadM38)")
	(net 1356 "unconnected-(J18-PadL12)")
	(net 1357 "unconnected-(J18-PadM39)")
	(net 1358 "unconnected-(J18-PadM23)")
	(net 1359 "unconnected-(J18-PadM14)")
	(net 1360 "unconnected-(J18-PadH35)")
	(net 1361 "unconnected-(J18-PadL08)")
	(net 1362 "unconnected-(J18-PadM11)")
	(net 1363 "unconnected-(J18-PadM30)")
	(net 1364 "unconnected-(J18-PadM27)")
	(net 1365 "unconnected-(J18-PadM26)")
	(net 1366 "/Recovery USB/~{USBC2_INT_R}")
	(net 1367 "Net-(J12-TX_{DISABLE})")
	(net 1368 "Net-(J12-RS0)")
	(net 1369 "Net-(J12-RS1)")
	(net 1370 "Net-(J12-RX_{LOS})")
	(net 1371 "Net-(J12-TX_{FAULT})")
	(net 1372 "Net-(J10-Pad40)")
	(net 1373 "Net-(J10-Pad39)")
	(net 1374 "Net-(J11-Pad39)")
	(net 1375 "Net-(J11-Pad42)")
	(net 1376 "Net-(J11-Pad41)")
	(net 1377 "Net-(J11-Pad40)")
	(net 1378 "Net-(R406-Pad2)")
	(net 1379 "Net-(Q30-D)")
	(net 1380 "Net-(U3-DIV)")
	(net 1381 "Net-(U3-SET)")
	(net 1382 "Net-(R300-Pad2)")
	(net 1383 "VCC_NO_OVP")
	(net 1384 "Net-(Q32-G)")
	(net 1385 "Net-(Q41-G)")
	(net 1386 "Net-(U9-SET)")
	(net 1387 "Net-(D24-A)")
	(net 1388 "Net-(D25-A)")
	(net 1389 "Net-(D47-A)")
	(net 1390 "Net-(D49-A)")
	(net 1391 "Net-(D51-A)")
	(net 1392 "Net-(Q6-D)")
	(net 1393 "Net-(D65-C)")
	(net 1394 "Net-(D65-A)")
	(net 1395 "Net-(D53-A)")
	(net 1396 "Net-(U79-ADJ)")
	(net 1397 "unconnected-(U79-PG-Pad3)")
	(net 1398 "unconnected-(U4-Pad5)")
	(net 1399 "unconnected-(U4-Pad5)_1")
	(footprint "antmicro-footprints:C_0805_2012Metric"
		(layer "F.Cu")
		(at 171.35 69.11 90)
		(descr "Capacitor SMD 0805")
		(tags "capacitor SMD 0805")
		(property "Reference" "C276"
			(at -1.43 -2.720532 90)
			(layer "F.SilkS")
			(effects
				(font
					(size 0.7 0.7)
					(thickness 0.15)
				)
				(justify left bottom)
			)
		)
		(property "Value" "C_22u_25V_0805"
			(at -2.055717 1.963152 90)
			(layer "F.Fab")
			(effects
				(font
					(size 0.7 0.7)
					(thickness 0.15)
				)
				(justify left bottom)
			)
		)
		(property "Datasheet" "https://product.samsungsem.com/mlcc/CL21A226MAYNNN.do"
			(at 0 0 90)
			(layer "F.Fab")
			(hide yes)
			(effects
				(font
					(size 1.27 1.27)
					(thickness 0.15)
				)
			)
		)
		(property "Description" "SMT Multilayer Ceramic Capacitor, 22uF, +/-20%, 25V, X5R, 0805 [2012 Metric]"
			(at 0 0 90)
			(layer "F.Fab")
			(hide yes)
			(effects
				(font
					(size 1.27 1.27)
					(thickness 0.15)
				)
			)
		)
		(property "MPN" "CL21A226MAYNNNE"
			(at 0 0 90)
			(unlocked yes)
			(layer "F.Fab")
			(hide yes)
			(effects
				(font
					(size 1 1)
					(thickness 0.15)
				)
			)
		)
		(property "Manufacturer" "Samsung Electro-Mechanics"
			(at 0 0 90)
			(unlocked yes)
			(layer "F.Fab")
			(hide yes)
			(effects
				(font
					(size 1 1)
					(thickness 0.15)
				)
			)
		)
		(property "License" "Apache-2.0"
			(at 0 0 90)
			(unlocked yes)
			(layer "F.Fab")
			(hide yes)
			(effects
				(font
					(size 1 1)
					(thickness 0.15)
				)
			)
		)
		(property "Author" "Antmicro"
			(at 0 0 90)
			(unlocked yes)
			(layer "F.Fab")
			(hide yes)
			(effects
				(font
					(size 1 1)
					(thickness 0.15)
				)
			)
		)
		(property "Val" "22u"
			(at 0 0 90)
			(unlocked yes)
			(layer "F.Fab")
			(hide yes)
			(effects
				(font
					(size 1 1)
					(thickness 0.15)
				)
			)
		)
		(property "Voltage" "25V"
			(at 0 0 90)
			(unlocked yes)
			(layer "F.Fab")
			(hide yes)
			(effects
				(font
					(size 1 1)
					(thickness 0.15)
				)
			)
		)
		(property "Dielectric" "X5R"
			(at 0 0 90)
			(unlocked yes)
			(layer "F.Fab")
			(hide yes)
			(effects
				(font
					(size 1 1)
					(thickness 0.15)
				)
			)
		)
		(property "Public" "False"
			(at 0 0 90)
			(unlocked yes)
			(layer "F.Fab")
			(hide yes)
			(effects
				(font
					(size 1 1)
					(thickness 0.15)
				)
			)
		)
		(component_classes
			(class "DCDC_20V")
		)
		(sheetname "/DCDC/")
		(sheetfile "dcdc.kicad_sch")
		(attr smd)
		(fp_line
			(start -0.3 -0.7)
			(end 0.3 -0.7)
			(stroke
				(width 0.15)
				(type solid)
			)
			(layer "F.SilkS")
		)
		(fp_line
			(start -0.3 0.7)
			(end 0.3 0.7)
			(stroke
				(width 0.15)
				(type solid)
			)
			(layer "F.SilkS")
		)
		(fp_rect
			(start 1.95 -0.9)
			(end -1.95 0.9)
			(stroke
				(width 0.05)
				(type default)
			)
			(fill no)
			(layer "F.CrtYd")
		)
		(fp_rect
			(start -0.95 -0.675)
			(end 0.95 0.675)
			(stroke
				(width 0.15)
				(type solid)
			)
			(fill no)
			(layer "F.Fab")
		)
		(fp_text user "${REFERENCE}"
			(at -1.9 3.947 90)
			(layer "F.Fab")
			(effects
				(font
					(size 0.7 0.7)
					(thickness 0.15)
				)
				(justify left bottom)
			)
		)
		(fp_text user "License: Apache-2.0"
			(at -1.9 4.947 90)
			(layer "F.Fab")
			(effects
				(font
					(size 0.7 0.7)
					(thickness 0.15)
				)
				(justify left bottom)
			)
		)
		(fp_text user "Author: Antmicro"
			(at -1.9 5.947 90)
			(layer "F.Fab")
			(effects
				(font
					(size 0.7 0.7)
					(thickness 0.15)
				)
				(justify left bottom)
			)
		)
		(pad "1" smd roundrect
			(at -1.1 0 90)
			(size 1.2 1.3)
			(layers "F.Cu" "F.Mask" "F.Paste")
			(roundrect_rratio 0.25)
			(net 1 "GND")
			(pintype "passive")
		)
		(pad "2" smd roundrect
			(at 1.1 0 90)
			(size 1.2 1.3)
			(layers "F.Cu" "F.Mask" "F.Paste")
			(roundrect_rratio 0.25)
			(net 13 "VCC")
			(pintype "passive")
		)
	)
	(footprint "antmicro-footprints:C_0805_2012Metric"
		(layer "F.Cu")
		(at 126.17 57.54)
		(descr "Capacitor SMD 0805")
		(tags "capacitor SMD 0805")
		(property "Reference" "C373"
			(at -8.76 8.85 0)
			(layer "F.SilkS")
			(effects
				(font
					(size 0.7 0.7)
					(thickness 0.15)
				)
				(justify left bottom)
			)
		)
		(property "Value" "C_22u_25V_0805"
			(at -2.055717 1.963153 0)
			(layer "F.Fab")
			(effects
				(font
					(size 0.7 0.7)
					(thickness 0.15)
				)
				(justify left bottom)
			)
		)
		(property "Datasheet" "https://product.samsungsem.com/mlcc/CL21A226MAYNNN.do"
			(at 0 0 0)
			(layer "F.Fab")
			(hide yes)
			(effects
				(font
					(size 1.27 1.27)
					(thickness 0.15)
				)
			)
		)
		(property "Description" "SMT Multilayer Ceramic Capacitor, 22uF, +/-20%, 25V, X5R, 0805 [2012 Metric]"
			(at 0 0 0)
			(layer "F.Fab")
			(hide yes)
			(effects
				(font
					(size 1.27 1.27)
					(thickness 0.15)
				)
			)
		)
		(property "MPN" "CL21A226MAYNNNE"
			(at 0 0 0)
			(unlocked yes)
			(layer "F.Fab")
			(hide yes)
			(effects
				(font
					(size 1 1)
					(thickness 0.15)
				)
			)
		)
		(property "Manufacturer" "Samsung Electro-Mechanics"
			(at 0 0 0)
			(unlocked yes)
			(layer "F.Fab")
			(hide yes)
			(effects
				(font
					(size 1 1)
					(thickness 0.15)
				)
			)
		)
		(property "License" "Apache-2.0"
			(at 0 0 0)
			(unlocked yes)
			(layer "F.Fab")
			(hide yes)
			(effects
				(font
					(size 1 1)
					(thickness 0.15)
				)
			)
		)
		(property "Author" "Antmicro"
			(at 0 0 0)
			(unlocked yes)
			(layer "F.Fab")
			(hide yes)
			(effects
				(font
					(size 1 1)
					(thickness 0.15)
				)
			)
		)
		(property "Val" "22u"
			(at 0 0 0)
			(unlocked yes)
			(layer "F.Fab")
			(hide yes)
			(effects
				(font
					(size 1 1)
					(thickness 0.15)
				)
			)
		)
		(property "Voltage" "25V"
			(at 0 0 0)
			(unlocked yes)
			(layer "F.Fab")
			(hide yes)
			(effects
				(font
					(size 1 1)
					(thickness 0.15)
				)
			)
		)
		(property "Dielectric" "X5R"
			(at 0 0 0)
			(unlocked yes)
			(layer "F.Fab")
			(hide yes)
			(effects
				(font
					(size 1 1)
					(thickness 0.15)
				)
			)
		)
		(property "Public" "False"
			(at 0 0 0)
			(unlocked yes)
			(layer "F.Fab")
			(hide yes)
			(effects
				(font
					(size 1 1)
					(thickness 0.15)
				)
			)
		)
		(sheetname "/DCDC/")
		(sheetfile "dcdc.kicad_sch")
		(attr smd)
		(fp_line
			(start -0.3 -0.7)
			(end 0.3 -0.7)
			(stroke
				(width 0.15)
				(type solid)
			)
			(layer "F.SilkS")
		)
		(fp_line
			(start -0.3 0.7)
			(end 0.3 0.7)
			(stroke
				(width 0.15)
				(type solid)
			)
			(layer "F.SilkS")
		)
		(fp_poly
			(pts
				(xy 1.95 -0.9) (xy 1.95 0.9) (xy -1.95 0.9) (xy -1.95 -0.9)
			)
			(stroke
				(width 0.05)
				(type default)
			)
			(fill no)
			(layer "F.CrtYd")
		)
		(fp_poly
			(pts
				(xy -0.95 -0.675001) (xy -0.95 0.675001) (xy 0.95 0.675001) (xy 0.95 -0.675001)
			)
			(stroke
				(width 0.15)
				(type solid)
			)
			(fill no)
			(layer "F.Fab")
		)
		(fp_text user "${REFERENCE}"
			(at -1.899999 3.947 0)
			(layer "F.Fab")
			(effects
				(font
					(size 0.7 0.7)
					(thickness 0.15)
				)
				(justify left bottom)
			)
		)
		(fp_text user "Author: Antmicro"
			(at -1.9 5.947 0)
			(layer "F.Fab")
			(effects
				(font
					(size 0.7 0.7)
					(thickness 0.15)
				)
				(justify left bottom)
			)
		)
		(fp_text user "License: Apache-2.0"
			(at -1.9 4.947 0)
			(layer "F.Fab")
			(effects
				(font
					(size 0.7 0.7)
					(thickness 0.15)
				)
				(justify left bottom)
			)
		)
		(pad "1" smd roundrect
			(at -1.099999 0)
			(size 1.2 1.3)
			(layers "F.Cu" "F.Mask" "F.Paste")
			(roundrect_rratio 0.25)
			(net 1 "GND")
			(pintype "passive")
		)
		(pad "2" smd roundrect
			(at 1.099999 0)
			(size 1.2 1.3)
			(layers "F.Cu" "F.Mask" "F.Paste")
			(roundrect_rratio 0.25)
			(net 13 "VCC")
			(pintype "passive")
		)
	)
	(footprint "antmicro-footprints:R_0402_1005Metric"
		(layer "F.Cu")
		(at 94 58.5)
		(descr "Resistor SMD 0402")
		(tags "resistor SMD 0402")
		(property "Reference" "R288"
			(at 6.9 1.68 0)
			(layer "F.SilkS")
			(effects
				(font
					(size 0.7 0.7)
					(thickness 0.15)
				)
				(justify left bottom)
			)
		)
		(property "Value" "R_47k_0402"
			(at -1.011843 1.772046 0)
			(layer "F.Fab")
			(effects
				(font
					(size 0.7 0.7)
					(thickness 0.15)
				)
				(justify left bottom)
			)
		)
		(property "Datasheet" "https://www.bourns.com/docs/product-datasheets/cr.pdf"
			(at 0 0 0)
			(layer "F.Fab")
			(hide yes)
			(effects
				(font
					(size 1.27 1.27)
					(thickness 0.15)
				)
			)
		)
		(property "Description" "SMD Chip Resistor, 47 kohm, ± 1%, 62.5 mW, 0402 [1005 Metric], Thick Film, General Purpose"
			(at 0 0 0)
			(layer "F.Fab")
			(hide yes)
			(effects
				(font
					(size 1.27 1.27)
					(thickness 0.15)
				)
			)
		)
		(property "MPN" "CR0402-FX-4702GLF"
			(at 0 0 0)
			(unlocked yes)
			(layer "F.Fab")
			(hide yes)
			(effects
				(font
					(size 1 1)
					(thickness 0.15)
				)
			)
		)
		(property "Manufacturer" "Bourns"
			(at 0 0 0)
			(unlocked yes)
			(layer "F.Fab")
			(hide yes)
			(effects
				(font
					(size 1 1)
					(thickness 0.15)
				)
			)
		)
		(property "License" "Apache-2.0"
			(at 0 0 0)
			(unlocked yes)
			(layer "F.Fab")
			(hide yes)
			(effects
				(font
					(size 1 1)
					(thickness 0.15)
				)
			)
		)
		(property "Author" "Antmicro"
			(at 0 0 0)
			(unlocked yes)
			(layer "F.Fab")
			(hide yes)
			(effects
				(font
					(size 1 1)
					(thickness 0.15)
				)
			)
		)
		(property "Val" "47k"
			(at 0 0 0)
			(unlocked yes)
			(layer "F.Fab")
			(hide yes)
			(effects
				(font
					(size 1 1)
					(thickness 0.15)
				)
			)
		)
		(property "Tolerance" "1%"
			(at 0 0 0)
			(unlocked yes)
			(layer "F.Fab")
			(hide yes)
			(effects
				(font
					(size 1 1)
					(thickness 0.15)
				)
			)
		)
		(sheetname "/SoM_Power/")
		(sheetfile "som_power.kicad_sch")
		(attr smd)
		(fp_poly
			(pts
				(xy -0.925 -0.47) (xy -0.925 0.47) (xy 0.925 0.47) (xy 0.925 -0.47)
			)
			(stroke
				(width 0.05)
				(type default)
			)
			(fill no)
			(layer "F.CrtYd")
		)
		(fp_poly
			(pts
				(xy -0.5 -0.25) (xy -0.5 0.25) (xy 0.5 0.25) (xy 0.5 -0.25)
			)
			(stroke
				(width 0.15)
				(type solid)
			)
			(fill no)
			(layer "F.Fab")
		)
		(fp_text user "Author: Antmicro"
			(at -0.95 4.169 0)
			(layer "F.Fab")
			(effects
				(font
					(size 0.7 0.7)
					(thickness 0.15)
				)
				(justify left bottom)
			)
		)
		(fp_text user "License: Apache-2.0"
			(at -0.949999 5.169 0)
			(layer "F.Fab")
			(effects
				(font
					(size 0.7 0.7)
					(thickness 0.15)
				)
				(justify left bottom)
			)
		)
		(fp_text user "${REFERENCE}"
			(at -0.95 3.168 0)
			(layer "F.Fab")
			(effects
				(font
					(size 0.7 0.7)
					(thickness 0.15)
				)
				(justify left bottom)
			)
		)
		(pad "1" smd roundrect
			(at -0.48 0)
			(size 0.59 0.64)
			(layers "F.Cu" "F.Mask" "F.Paste")
			(roundrect_rratio 0.25)
			(net 610 "/SoM_Power/~{PWR_BTN}")
			(pintype "passive")
		)
		(pad "2" smd roundrect
			(at 0.48 0)
			(size 0.59 0.64)
			(layers "F.Cu" "F.Mask" "F.Paste")
			(roundrect_rratio 0.25)
			(net 491 "+5V_AON")
			(pintype "passive")
		)
	)
	(footprint "antmicro-footprints:C_0805_2012Metric"
		(layer "F.Cu")
		(at 165.88 73.31 -90)
		(descr "Capacitor SMD 0805")
		(tags "capacitor SMD 0805")
		(property "Reference" "C295"
			(at 1.78449 -1.468678 90)
			(layer "F.SilkS")
			(effects
				(font
					(size 0.7 0.7)
					(thickness 0.15)
				)
				(justify right top)
			)
		)
		(property "Value" "C_22u_25V_0805"
			(at -2.055717 1.963152 90)
			(layer "F.Fab")
			(effects
				(font
					(size 0.7 0.7)
					(thickness 0.15)
				)
				(justify right top)
			)
		)
		(property "Datasheet" "https://product.samsungsem.com/mlcc/CL21A226MAYNNN.do"
			(at 0 0 90)
			(layer "F.Fab")
			(hide yes)
			(effects
				(font
					(size 1.27 1.27)
					(thickness 0.15)
				)
			)
		)
		(property "Description" "SMT Multilayer Ceramic Capacitor, 22uF, +/-20%, 25V, X5R, 0805 [2012 Metric]"
			(at 0 0 90)
			(layer "F.Fab")
			(hide yes)
			(effects
				(font
					(size 1.27 1.27)
					(thickness 0.15)
				)
			)
		)
		(property "MPN" "CL21A226MAYNNNE"
			(at 0 0 270)
			(unlocked yes)
			(layer "F.Fab")
			(hide yes)
			(effects
				(font
					(size 1 1)
					(thickness 0.15)
				)
			)
		)
		(property "Manufacturer" "Samsung Electro-Mechanics"
			(at 0 0 270)
			(unlocked yes)
			(layer "F.Fab")
			(hide yes)
			(effects
				(font
					(size 1 1)
					(thickness 0.15)
				)
			)
		)
		(property "License" "Apache-2.0"
			(at 0 0 270)
			(unlocked yes)
			(layer "F.Fab")
			(hide yes)
			(effects
				(font
					(size 1 1)
					(thickness 0.15)
				)
			)
		)
		(property "Author" "Antmicro"
			(at 0 0 270)
			(unlocked yes)
			(layer "F.Fab")
			(hide yes)
			(effects
				(font
					(size 1 1)
					(thickness 0.15)
				)
			)
		)
		(property "Val" "22u"
			(at 0 0 270)
			(unlocked yes)
			(layer "F.Fab")
			(hide yes)
			(effects
				(font
					(size 1 1)
					(thickness 0.15)
				)
			)
		)
		(property "Voltage" "25V"
			(at 0 0 270)
			(unlocked yes)
			(layer "F.Fab")
			(hide yes)
			(effects
				(font
					(size 1 1)
					(thickness 0.15)
				)
			)
		)
		(property "Dielectric" "X5R"
			(at 0 0 270)
			(unlocked yes)
			(layer "F.Fab")
			(hide yes)
			(effects
				(font
					(size 1 1)
					(thickness 0.15)
				)
			)
		)
		(property "Public" "False"
			(at 0 0 270)
			(unlocked yes)
			(layer "F.Fab")
			(hide yes)
			(effects
				(font
					(size 1 1)
					(thickness 0.15)
				)
			)
		)
		(component_classes
			(class "DCDC_20V")
		)
		(sheetname "/DCDC/")
		(sheetfile "dcdc.kicad_sch")
		(attr smd)
		(fp_line
			(start -0.3 0.7)
			(end 0.3 0.7)
			(stroke
				(width 0.15)
				(type solid)
			)
			(layer "F.SilkS")
		)
		(fp_line
			(start -0.3 -0.7)
			(end 0.3 -0.7)
			(stroke
				(width 0.15)
				(type solid)
			)
			(layer "F.SilkS")
		)
		(fp_rect
			(start 1.95 -0.9)
			(end -1.95 0.9)
			(stroke
				(width 0.05)
				(type default)
			)
			(fill no)
			(layer "F.CrtYd")
		)
		(fp_rect
			(start -0.95 -0.675)
			(end 0.95 0.675)
			(stroke
				(width 0.15)
				(type solid)
			)
			(fill no)
			(layer "F.Fab")
		)
		(fp_text user "Author: Antmicro"
			(at -1.9 5.947 90)
			(layer "F.Fab")
			(effects
				(font
					(size 0.7 0.7)
					(thickness 0.15)
				)
				(justify right top)
			)
		)
		(fp_text user "${REFERENCE}"
			(at -1.9 3.947 90)
			(layer "F.Fab")
			(effects
				(font
					(size 0.7 0.7)
					(thickness 0.15)
				)
				(justify right top)
			)
		)
		(fp_text user "License: Apache-2.0"
			(at -1.9 4.947 90)
			(layer "F.Fab")
			(effects
				(font
					(size 0.7 0.7)
					(thickness 0.15)
				)
				(justify right top)
			)
		)
		(pad "1" smd roundrect
			(at -1.1 0 270)
			(size 1.2 1.3)
			(layers "F.Cu" "F.Mask" "F.Paste")
			(roundrect_rratio 0.25)
			(net 1 "GND")
			(pintype "passive")
		)
		(pad "2" smd roundrect
			(at 1.1 0 270)
			(size 1.2 1.3)
			(layers "F.Cu" "F.Mask" "F.Paste")
			(roundrect_rratio 0.25)
			(net 1105 "/DCDC/20V_OUT")
			(pintype "passive")
		)
	)
	(footprint "antmicro-footprints:R_0402_1005Metric"
		(layer "F.Cu")
		(at 91.5 149.63 90)
		(descr "Resistor SMD 0402")
		(tags "resistor SMD 0402")
		(property "Reference" "R193"
			(at -3.77 0.5 90)
			(layer "F.SilkS")
			(effects
				(font
					(size 0.7 0.7)
					(thickness 0.15)
				)
				(justify left bottom)
			)
		)
		(property "Value" "R_49R9_0402"
			(at -1.011843 1.772046 90)
			(layer "F.Fab")
			(effects
				(font
					(size 0.7 0.7)
					(thickness 0.15)
				)
				(justify left bottom)
			)
		)
		(property "Datasheet" "https://www.bourns.com/docs/product-datasheets/cr.pdf"
			(at 0 0 90)
			(layer "F.Fab")
			(hide yes)
			(effects
				(font
					(size 1.27 1.27)
					(thickness 0.15)
				)
			)
		)
		(property "Description" "SMD Chip Resistor, 49.9 ohm, ± 1%, 62.5 mW, 0402 [1005 Metric], Thick Film, General Purpose"
			(at 0 0 90)
			(layer "F.Fab")
			(hide yes)
			(effects
				(font
					(size 1.27 1.27)
					(thickness 0.15)
				)
			)
		)
		(property "MPN" "CR0402-FX-49R9GLF"
			(at 0 0 90)
			(unlocked yes)
			(layer "F.Fab")
			(hide yes)
			(effects
				(font
					(size 1 1)
					(thickness 0.15)
				)
			)
		)
		(property "Manufacturer" "Bourns"
			(at 0 0 90)
			(unlocked yes)
			(layer "F.Fab")
			(hide yes)
			(effects
				(font
					(size 1 1)
					(thickness 0.15)
				)
			)
		)
		(property "License" "Apache-2.0"
			(at 0 0 90)
			(unlocked yes)
			(layer "F.Fab")
			(hide yes)
			(effects
				(font
					(size 1 1)
					(thickness 0.15)
				)
			)
		)
		(property "Author" "Antmicro"
			(at 0 0 90)
			(unlocked yes)
			(layer "F.Fab")
			(hide yes)
			(effects
				(font
					(size 1 1)
					(thickness 0.15)
				)
			)
		)
		(property "Val" "49R9"
			(at 0 0 90)
			(unlocked yes)
			(layer "F.Fab")
			(hide yes)
			(effects
				(font
					(size 1 1)
					(thickness 0.15)
				)
			)
		)
		(property "Tolerance" "1%"
			(at 0 0 90)
			(unlocked yes)
			(layer "F.Fab")
			(hide yes)
			(effects
				(font
					(size 1 1)
					(thickness 0.15)
				)
			)
		)
		(sheetname "/SoM_IO2/")
		(sheetfile "som_io2.kicad_sch")
		(attr smd)
		(fp_poly
			(pts
				(xy -0.925 -0.47) (xy 0.925 -0.47) (xy 0.925 0.47) (xy -0.925 0.47)
			)
			(stroke
				(width 0.05)
				(type default)
			)
			(fill no)
			(layer "F.CrtYd")
		)
		(fp_poly
			(pts
				(xy -0.5 -0.25) (xy 0.5 -0.25) (xy 0.5 0.25) (xy -0.5 0.25)
			)
			(stroke
				(width 0.15)
				(type solid)
			)
			(fill no)
			(layer "F.Fab")
		)
		(fp_text user "License: Apache-2.0"
			(at -0.949999 5.169 90)
			(layer "F.Fab")
			(effects
				(font
					(size 0.7 0.7)
					(thickness 0.15)
				)
				(justify left bottom)
			)
		)
		(fp_text user "Author: Antmicro"
			(at -0.95 4.169 90)
			(layer "F.Fab")
			(effects
				(font
					(size 0.7 0.7)
					(thickness 0.15)
				)
				(justify left bottom)
			)
		)
		(fp_text user "${REFERENCE}"
			(at -0.95 3.168 90)
			(layer "F.Fab")
			(effects
				(font
					(size 0.7 0.7)
					(thickness 0.15)
				)
				(justify left bottom)
			)
		)
		(pad "1" smd roundrect
			(at -0.48 0 90)
			(size 0.59 0.64)
			(layers "F.Cu" "F.Mask" "F.Paste")
			(roundrect_rratio 0.25)
			(net 1 "GND")
			(pintype "passive")
		)
		(pad "2" smd roundrect
			(at 0.48 0 90)
			(size 0.59 0.64)
			(layers "F.Cu" "F.Mask" "F.Paste")
			(roundrect_rratio 0.25)
			(net 898 "/SoM_IO2/C2_REFCLK+")
			(pintype "passive")
		)
	)
	(footprint "antmicro-footprints:C_0402_1005Metric"
		(layer "F.Cu")
		(at 213.544132 84.292 -90)
		(descr "Capacitor SMD 0402")
		(tags "capacitor SMD 0402")
		(property "Reference" "C130"
			(at -3.682 0.324132 90)
			(layer "F.SilkS")
			(effects
				(font
					(size 0.7 0.7)
					(thickness 0.15)
				)
				(justify right top)
			)
		)
		(property "Value" "C_100n_0402"
			(at -1.022927 2.155213 90)
			(layer "F.Fab")
			(effects
				(font
					(size 0.7 0.7)
					(thickness 0.15)
				)
				(justify right top)
			)
		)
		(property "Datasheet" "https://www.murata.com/products/productdetail?partno=GRM155R61H104KE14%23"
			(at 0 0 90)
			(layer "F.Fab")
			(hide yes)
			(effects
				(font
					(size 1.27 1.27)
					(thickness 0.15)
				)
			)
		)
		(property "Description" "SMD Multilayer Ceramic Capacitor, 0.1 µF, 50 V, 0402 [1005 Metric], ± 10%, X5R, GRM Series"
			(at 0 0 90)
			(layer "F.Fab")
			(hide yes)
			(effects
				(font
					(size 1.27 1.27)
					(thickness 0.15)
				)
			)
		)
		(property "Manufacturer" "Murata"
			(at 0 0 270)
			(unlocked yes)
			(layer "F.Fab")
			(hide yes)
			(effects
				(font
					(size 1 1)
					(thickness 0.15)
				)
			)
		)
		(property "MPN" "GRM155R61H104KE14D"
			(at 0 0 270)
			(unlocked yes)
			(layer "F.Fab")
			(hide yes)
			(effects
				(font
					(size 1 1)
					(thickness 0.15)
				)
			)
		)
		(property "Val" "100n"
			(at 0 0 270)
			(unlocked yes)
			(layer "F.Fab")
			(hide yes)
			(effects
				(font
					(size 1 1)
					(thickness 0.15)
				)
			)
		)
		(property "License" "Apache-2.0"
			(at 0 0 270)
			(unlocked yes)
			(layer "F.Fab")
			(hide yes)
			(effects
				(font
					(size 1 1)
					(thickness 0.15)
				)
			)
		)
		(property "Author" "Antmicro"
			(at 0 0 270)
			(unlocked yes)
			(layer "F.Fab")
			(hide yes)
			(effects
				(font
					(size 1 1)
					(thickness 0.15)
				)
			)
		)
		(property "Voltage" "50V"
			(at 0 0 270)
			(unlocked yes)
			(layer "F.Fab")
			(hide yes)
			(effects
				(font
					(size 1 1)
					(thickness 0.15)
				)
			)
		)
		(property "Dielectric" "X5R"
			(at 0 0 270)
			(unlocked yes)
			(layer "F.Fab")
			(hide yes)
			(effects
				(font
					(size 1 1)
					(thickness 0.15)
				)
			)
		)
		(sheetname "/USB DP Alt mode/")
		(sheetfile "usb_dp.kicad_sch")
		(attr smd)
		(fp_rect
			(start -0.925 -0.47)
			(end 0.925 0.47)
			(stroke
				(width 0.05)
				(type default)
			)
			(fill no)
			(layer "F.CrtYd")
		)
		(fp_line
			(start -0.494 0.248)
			(end -0.494 -0.25)
			(stroke
				(width 0.15)
				(type solid)
			)
			(layer "F.Fab")
		)
		(fp_line
			(start 0.504 0.248)
			(end -0.494 0.248)
			(stroke
				(width 0.15)
				(type solid)
			)
			(layer "F.Fab")
		)
		(fp_line
			(start -0.494 -0.25)
			(end 0.504 -0.25)
			(stroke
				(width 0.15)
				(type solid)
			)
			(layer "F.Fab")
		)
		(fp_line
			(start 0.504 -0.25)
			(end 0.504 0.248)
			(stroke
				(width 0.15)
				(type solid)
			)
			(layer "F.Fab")
		)
		(fp_text user "${REFERENCE}"
			(at -0.939 4.599 90)
			(layer "F.Fab")
			(effects
				(font
					(size 0.7 0.7)
					(thickness 0.15)
				)
				(justify right top)
			)
		)
		(fp_text user "Author: Antmicro"
			(at -0.939 3.399 90)
			(layer "F.Fab")
			(effects
				(font
					(size 0.7 0.7)
					(thickness 0.15)
				)
				(justify right top)
			)
		)
		(fp_text user "License: Apache-2.0"
			(at -0.939 5.799 90)
			(layer "F.Fab")
			(effects
				(font
					(size 0.7 0.7)
					(thickness 0.15)
				)
				(justify right top)
			)
		)
		(pad "1" smd roundrect
			(at -0.48 0 270)
			(size 0.59 0.64)
			(layers "F.Cu" "F.Mask" "F.Paste")
			(roundrect_rratio 0.25)
			(net 311 "/SoM_IO2/USBSS1.TX+")
			(pintype "passive")
		)
		(pad "2" smd roundrect
			(at 0.48 0 270)
			(size 0.59 0.64)
			(layers "F.Cu" "F.Mask" "F.Paste")
			(roundrect_rratio 0.25)
			(net 333 "/USB DP Alt mode/USBSS1_TX_C_N")
			(pintype "passive")
		)
	)
	(footprint "antmicro-footprints:C_0402_1005Metric"
		(layer "F.Cu")
		(at 89.1 94.1)
		(descr "Capacitor SMD 0402")
		(tags "capacitor SMD 0402")
		(property "Reference" "C335"
			(at -3.82 0.45 0)
			(layer "F.SilkS")
			(effects
				(font
					(size 0.7 0.7)
					(thickness 0.15)
				)
				(justify left bottom)
			)
		)
		(property "Value" "C_100n_0402"
			(at -1.022927 2.155213 0)
			(layer "F.Fab")
			(effects
				(font
					(size 0.7 0.7)
					(thickness 0.15)
				)
				(justify left bottom)
			)
		)
		(property "Datasheet" "https://www.murata.com/products/productdetail?partno=GRM155R61H104KE14%23"
			(at 0 0 0)
			(layer "F.Fab")
			(hide yes)
			(effects
				(font
					(size 1.27 1.27)
					(thickness 0.15)
				)
			)
		)
		(property "Description" "SMD Multilayer Ceramic Capacitor, 0.1 µF, 50 V, 0402 [1005 Metric], ± 10%, X5R, GRM Series"
			(at 0 0 0)
			(layer "F.Fab")
			(hide yes)
			(effects
				(font
					(size 1.27 1.27)
					(thickness 0.15)
				)
			)
		)
		(property "Manufacturer" "Murata"
			(at 0 0 0)
			(unlocked yes)
			(layer "F.Fab")
			(hide yes)
			(effects
				(font
					(size 1 1)
					(thickness 0.15)
				)
			)
		)
		(property "MPN" "GRM155R61H104KE14D"
			(at 0 0 0)
			(unlocked yes)
			(layer "F.Fab")
			(hide yes)
			(effects
				(font
					(size 1 1)
					(thickness 0.15)
				)
			)
		)
		(property "Val" "100n"
			(at 0 0 0)
			(unlocked yes)
			(layer "F.Fab")
			(hide yes)
			(effects
				(font
					(size 1 1)
					(thickness 0.15)
				)
			)
		)
		(property "License" "Apache-2.0"
			(at 0 0 0)
			(unlocked yes)
			(layer "F.Fab")
			(hide yes)
			(effects
				(font
					(size 1 1)
					(thickness 0.15)
				)
			)
		)
		(property "Author" "Antmicro"
			(at 0 0 0)
			(unlocked yes)
			(layer "F.Fab")
			(hide yes)
			(effects
				(font
					(size 1 1)
					(thickness 0.15)
				)
			)
		)
		(property "Voltage" "50V"
			(at 0 0 0)
			(unlocked yes)
			(layer "F.Fab")
			(hide yes)
			(effects
				(font
					(size 1 1)
					(thickness 0.15)
				)
			)
		)
		(property "Dielectric" "X5R"
			(at 0 0 0)
			(unlocked yes)
			(layer "F.Fab")
			(hide yes)
			(effects
				(font
					(size 1 1)
					(thickness 0.15)
				)
			)
		)
		(sheetname "/SoM_IO2/")
		(sheetfile "som_io2.kicad_sch")
		(attr smd)
		(fp_rect
			(start -0.925 -0.47)
			(end 0.925 0.47)
			(stroke
				(width 0.05)
				(type default)
			)
			(fill no)
			(layer "F.CrtYd")
		)
		(fp_line
			(start -0.494 -0.25)
			(end 0.504 -0.25)
			(stroke
				(width 0.15)
				(type solid)
			)
			(layer "F.Fab")
		)
		(fp_line
			(start -0.494 0.248)
			(end -0.494 -0.25)
			(stroke
				(width 0.15)
				(type solid)
			)
			(layer "F.Fab")
		)
		(fp_line
			(start 0.504 -0.25)
			(end 0.504 0.248)
			(stroke
				(width 0.15)
				(type solid)
			)
			(layer "F.Fab")
		)
		(fp_line
			(start 0.504 0.248)
			(end -0.494 0.248)
			(stroke
				(width 0.15)
				(type solid)
			)
			(layer "F.Fab")
		)
		(fp_text user "Author: Antmicro"
			(at -0.939 3.399 0)
			(layer "F.Fab")
			(effects
				(font
					(size 0.7 0.7)
					(thickness 0.15)
				)
				(justify left bottom)
			)
		)
		(fp_text user "${REFERENCE}"
			(at -0.939 4.599 0)
			(layer "F.Fab")
			(effects
				(font
					(size 0.7 0.7)
					(thickness 0.15)
				)
				(justify left bottom)
			)
		)
		(fp_text user "License: Apache-2.0"
			(at -0.939 5.799 0)
			(layer "F.Fab")
			(effects
				(font
					(size 0.7 0.7)
					(thickness 0.15)
				)
				(justify left bottom)
			)
		)
		(pad "1" smd roundrect
			(at -0.48 0)
			(size 0.59 0.64)
			(layers "F.Cu" "F.Mask" "F.Paste")
			(roundrect_rratio 0.25)
			(net 726 "/Expansion connector/DP2.TX1+")
			(pintype "passive")
		)
		(pad "2" smd roundrect
			(at 0.48 0)
			(size 0.59 0.64)
			(layers "F.Cu" "F.Mask" "F.Paste")
			(roundrect_rratio 0.25)
			(net 1255 "/SoM_IO2/DP2.TX1_C+")
			(pintype "passive")
		)
	)
	(footprint "antmicro-footprints:R_0402_1005Metric"
		(layer "F.Cu")
		(at 63.22 85.93 -90)
		(descr "Resistor SMD 0402")
		(tags "resistor SMD 0402")
		(property "Reference" "R166"
			(at -3.73 0.42 90)
			(layer "F.SilkS")
			(effects
				(font
					(size 0.7 0.7)
					(thickness 0.15)
				)
				(justify right top)
			)
		)
		(property "Value" "R_100k_0402"
			(at -1.011843 1.772047 90)
			(layer "F.Fab")
			(effects
				(font
					(size 0.7 0.7)
					(thickness 0.15)
				)
				(justify right top)
			)
		)
		(property "Datasheet" "https://www.bourns.com/docs/product-datasheets/cr.pdf"
			(at 0 0 90)
			(layer "F.Fab")
			(hide yes)
			(effects
				(font
					(size 1.27 1.27)
					(thickness 0.15)
				)
			)
		)
		(property "Description" "SMD Chip Resistor, 100 kohm, ± 1%, 62.5 mW, 0402 [1005 Metric], Thick Film, General Purpose"
			(at 0 0 90)
			(layer "F.Fab")
			(hide yes)
			(effects
				(font
					(size 1.27 1.27)
					(thickness 0.15)
				)
			)
		)
		(property "Manufacturer" "Bourns"
			(at 0 0 270)
			(unlocked yes)
			(layer "F.Fab")
			(hide yes)
			(effects
				(font
					(size 1 1)
					(thickness 0.15)
				)
			)
		)
		(property "MPN" "CR0402-FX-1003GLF"
			(at 0 0 270)
			(unlocked yes)
			(layer "F.Fab")
			(hide yes)
			(effects
				(font
					(size 1 1)
					(thickness 0.15)
				)
			)
		)
		(property "Val" "100k"
			(at 0 0 270)
			(unlocked yes)
			(layer "F.Fab")
			(hide yes)
			(effects
				(font
					(size 1 1)
					(thickness 0.15)
				)
			)
		)
		(property "License" "Apache-2.0"
			(at 0 0 270)
			(unlocked yes)
			(layer "F.Fab")
			(hide yes)
			(effects
				(font
					(size 1 1)
					(thickness 0.15)
				)
			)
		)
		(property "Author" "Antmicro"
			(at 0 0 270)
			(unlocked yes)
			(layer "F.Fab")
			(hide yes)
			(effects
				(font
					(size 1 1)
					(thickness 0.15)
				)
			)
		)
		(property "Tolerance" "1%"
			(at 0 0 270)
			(unlocked yes)
			(layer "F.Fab")
			(hide yes)
			(effects
				(font
					(size 1 1)
					(thickness 0.15)
				)
			)
		)
		(sheetname "/CSI/")
		(sheetfile "csi.kicad_sch")
		(attr smd)
		(fp_rect
			(start -0.925 -0.47)
			(end 0.925 0.47)
			(stroke
				(width 0.05)
				(type default)
			)
			(fill no)
			(layer "F.CrtYd")
		)
		(fp_rect
			(start -0.5 -0.25)
			(end 0.5 0.25)
			(stroke
				(width 0.15)
				(type solid)
			)
			(fill no)
			(layer "F.Fab")
		)
		(fp_text user "${REFERENCE}"
			(at -0.95 3.168 90)
			(layer "F.Fab")
			(effects
				(font
					(size 0.7 0.7)
					(thickness 0.15)
				)
				(justify right top)
			)
		)
		(fp_text user "Author: Antmicro"
			(at -0.95 4.169 90)
			(layer "F.Fab")
			(effects
				(font
					(size 0.7 0.7)
					(thickness 0.15)
				)
				(justify right top)
			)
		)
		(fp_text user "License: Apache-2.0"
			(at -0.95 5.169 90)
			(layer "F.Fab")
			(effects
				(font
					(size 0.7 0.7)
					(thickness 0.15)
				)
				(justify right top)
			)
		)
		(pad "1" smd roundrect
			(at -0.48 0 270)
			(size 0.59 0.64)
			(layers "F.Cu" "F.Mask" "F.Paste")
			(roundrect_rratio 0.25)
			(net 1 "GND")
			(pintype "passive")
		)
		(pad "2" smd roundrect
			(at 0.48 0 270)
			(size 0.59 0.64)
			(layers "F.Cu" "F.Mask" "F.Paste")
			(roundrect_rratio 0.25)
			(net 74 "/CSI/CAM_CTRL.CSIA_PEN")
			(pintype "passive")
		)
	)
	(footprint "antmicro-footprints:C_0402_1005Metric"
		(layer "F.Cu")
		(at 206.88 134.8 90)
		(descr "Capacitor SMD 0402")
		(tags "capacitor SMD 0402")
		(property "Reference" "C255"
			(at -1.6 13.9 90)
			(layer "F.SilkS")
			(effects
				(font
					(size 0.7 0.7)
					(thickness 0.15)
				)
				(justify left bottom)
			)
		)
		(property "Value" "C_100n_0402"
			(at -1.022927 2.155213 90)
			(layer "F.Fab")
			(effects
				(font
					(size 0.7 0.7)
					(thickness 0.15)
				)
				(justify left bottom)
			)
		)
		(property "Datasheet" "https://www.murata.com/products/productdetail?partno=GRM155R61H104KE14%23"
			(at 0 0 90)
			(layer "F.Fab")
			(hide yes)
			(effects
				(font
					(size 1.27 1.27)
					(thickness 0.15)
				)
			)
		)
		(property "Description" "SMD Multilayer Ceramic Capacitor, 0.1 µF, 50 V, 0402 [1005 Metric], ± 10%, X5R, GRM Series"
			(at 0 0 90)
			(layer "F.Fab")
			(hide yes)
			(effects
				(font
					(size 1.27 1.27)
					(thickness 0.15)
				)
			)
		)
		(property "Manufacturer" "Murata"
			(at 0 0 90)
			(unlocked yes)
			(layer "F.Fab")
			(hide yes)
			(effects
				(font
					(size 1 1)
					(thickness 0.15)
				)
			)
		)
		(property "MPN" "GRM155R61H104KE14D"
			(at 0 0 90)
			(unlocked yes)
			(layer "F.Fab")
			(hide yes)
			(effects
				(font
					(size 1 1)
					(thickness 0.15)
				)
			)
		)
		(property "Val" "100n"
			(at 0 0 90)
			(unlocked yes)
			(layer "F.Fab")
			(hide yes)
			(effects
				(font
					(size 1 1)
					(thickness 0.15)
				)
			)
		)
		(property "License" "Apache-2.0"
			(at 0 0 90)
			(unlocked yes)
			(layer "F.Fab")
			(hide yes)
			(effects
				(font
					(size 1 1)
					(thickness 0.15)
				)
			)
		)
		(property "Author" "Antmicro"
			(at 0 0 90)
			(unlocked yes)
			(layer "F.Fab")
			(hide yes)
			(effects
				(font
					(size 1 1)
					(thickness 0.15)
				)
			)
		)
		(property "Voltage" "50V"
			(at 0 0 90)
			(unlocked yes)
			(layer "F.Fab")
			(hide yes)
			(effects
				(font
					(size 1 1)
					(thickness 0.15)
				)
			)
		)
		(property "Dielectric" "X5R"
			(at 0 0 90)
			(unlocked yes)
			(layer "F.Fab")
			(hide yes)
			(effects
				(font
					(size 1 1)
					(thickness 0.15)
				)
			)
		)
		(sheetname "/USB Hub/")
		(sheetfile "usb_hub.kicad_sch")
		(attr smd)
		(fp_rect
			(start -0.925 -0.47)
			(end 0.925 0.47)
			(stroke
				(width 0.05)
				(type default)
			)
			(fill no)
			(layer "F.CrtYd")
		)
		(fp_line
			(start 0.504 -0.25)
			(end 0.504 0.248)
			(stroke
				(width 0.15)
				(type solid)
			)
			(layer "F.Fab")
		)
		(fp_line
			(start -0.494 -0.25)
			(end 0.504 -0.25)
			(stroke
				(width 0.15)
				(type solid)
			)
			(layer "F.Fab")
		)
		(fp_line
			(start 0.504 0.248)
			(end -0.494 0.248)
			(stroke
				(width 0.15)
				(type solid)
			)
			(layer "F.Fab")
		)
		(fp_line
			(start -0.494 0.248)
			(end -0.494 -0.25)
			(stroke
				(width 0.15)
				(type solid)
			)
			(layer "F.Fab")
		)
		(fp_text user "License: Apache-2.0"
			(at -0.939 5.799 90)
			(layer "F.Fab")
			(effects
				(font
					(size 0.7 0.7)
					(thickness 0.15)
				)
				(justify left bottom)
			)
		)
		(fp_text user "Author: Antmicro"
			(at -0.939 3.399 90)
			(layer "F.Fab")
			(effects
				(font
					(size 0.7 0.7)
					(thickness 0.15)
				)
				(justify left bottom)
			)
		)
		(fp_text user "${REFERENCE}"
			(at -0.939 4.599 90)
			(layer "F.Fab")
			(effects
				(font
					(size 0.7 0.7)
					(thickness 0.15)
				)
				(justify left bottom)
			)
		)
		(pad "1" smd roundrect
			(at -0.48 0 90)
			(size 0.59 0.64)
			(layers "F.Cu" "F.Mask" "F.Paste")
			(roundrect_rratio 0.25)
			(net 623 "/SoM_IO2/USBSS2.RX-")
			(pintype "passive")
		)
		(pad "2" smd roundrect
			(at 0.48 0 90)
			(size 0.59 0.64)
			(layers "F.Cu" "F.Mask" "F.Paste")
			(roundrect_rratio 0.25)
			(net 1134 "/USB Hub/USBSS_TX_N")
			(pintype "passive")
		)
	)
	(footprint "antmicro-footprints:C_0805_2012Metric"
		(layer "F.Cu")
		(at 130.129997 57.539999 180)
		(descr "Capacitor SMD 0805")
		(tags "capacitor SMD 0805")
		(property "Reference" "C370"
			(at 9.929997 -8.840001 0)
			(layer "F.SilkS")
			(effects
				(font
					(size 0.7 0.7)
					(thickness 0.15)
				)
				(justify left bottom)
			)
		)
		(property "Value" "C_22u_25V_0805"
			(at -2.055717 1.963153 0)
			(layer "F.Fab")
			(effects
				(font
					(size 0.7 0.7)
					(thickness 0.15)
				)
				(justify right top)
			)
		)
		(property "Datasheet" "https://product.samsungsem.com/mlcc/CL21A226MAYNNN.do"
			(at 0 0 0)
			(layer "F.Fab")
			(hide yes)
			(effects
				(font
					(size 1.27 1.27)
					(thickness 0.15)
				)
			)
		)
		(property "Description" "SMT Multilayer Ceramic Capacitor, 22uF, +/-20%, 25V, X5R, 0805 [2012 Metric]"
			(at 0 0 0)
			(layer "F.Fab")
			(hide yes)
			(effects
				(font
					(size 1.27 1.27)
					(thickness 0.15)
				)
			)
		)
		(property "MPN" "CL21A226MAYNNNE"
			(at 0 0 180)
			(unlocked yes)
			(layer "F.Fab")
			(hide yes)
			(effects
				(font
					(size 1 1)
					(thickness 0.15)
				)
			)
		)
		(property "Manufacturer" "Samsung Electro-Mechanics"
			(at 0 0 180)
			(unlocked yes)
			(layer "F.Fab")
			(hide yes)
			(effects
				(font
					(size 1 1)
					(thickness 0.15)
				)
			)
		)
		(property "License" "Apache-2.0"
			(at 0 0 180)
			(unlocked yes)
			(layer "F.Fab")
			(hide yes)
			(effects
				(font
					(size 1 1)
					(thickness 0.15)
				)
			)
		)
		(property "Author" "Antmicro"
			(at 0 0 180)
			(unlocked yes)
			(layer "F.Fab")
			(hide yes)
			(effects
				(font
					(size 1 1)
					(thickness 0.15)
				)
			)
		)
		(property "Val" "22u"
			(at 0 0 180)
			(unlocked yes)
			(layer "F.Fab")
			(hide yes)
			(effects
				(font
					(size 1 1)
					(thickness 0.15)
				)
			)
		)
		(property "Voltage" "25V"
			(at 0 0 180)
			(unlocked yes)
			(layer "F.Fab")
			(hide yes)
			(effects
				(font
					(size 1 1)
					(thickness 0.15)
				)
			)
		)
		(property "Dielectric" "X5R"
			(at 0 0 180)
			(unlocked yes)
			(layer "F.Fab")
			(hide yes)
			(effects
				(font
					(size 1 1)
					(thickness 0.15)
				)
			)
		)
		(property "Public" "False"
			(at 0 0 180)
			(unlocked yes)
			(layer "F.Fab")
			(hide yes)
			(effects
				(font
					(size 1 1)
					(thickness 0.15)
				)
			)
		)
		(sheetname "/DCDC/")
		(sheetfile "dcdc.kicad_sch")
		(attr smd)
		(fp_line
			(start -0.3 0.7)
			(end 0.3 0.7)
			(stroke
				(width 0.15)
				(type solid)
			)
			(layer "F.SilkS")
		)
		(fp_line
			(start -0.3 -0.7)
			(end 0.3 -0.7)
			(stroke
				(width 0.15)
				(type solid)
			)
			(layer "F.SilkS")
		)
		(fp_poly
			(pts
				(xy 1.95 -0.9) (xy 1.95 0.9) (xy -1.95 0.9) (xy -1.95 -0.9)
			)
			(stroke
				(width 0.05)
				(type default)
			)
			(fill no)
			(layer "F.CrtYd")
		)
		(fp_poly
			(pts
				(xy -0.95 -0.675001) (xy -0.95 0.675001) (xy 0.95 0.675001) (xy 0.95 -0.675001)
			)
			(stroke
				(width 0.15)
				(type solid)
			)
			(fill no)
			(layer "F.Fab")
		)
		(fp_text user "License: Apache-2.0"
			(at -1.9 4.947 0)
			(layer "F.Fab")
			(effects
				(font
					(size 0.7 0.7)
					(thickness 0.15)
				)
				(justify right top)
			)
		)
		(fp_text user "Author: Antmicro"
			(at -1.9 5.947 0)
			(layer "F.Fab")
			(effects
				(font
					(size 0.7 0.7)
					(thickness 0.15)
				)
				(justify right top)
			)
		)
		(fp_text user "${REFERENCE}"
			(at -1.899999 3.947 0)
			(layer "F.Fab")
			(effects
				(font
					(size 0.7 0.7)
					(thickness 0.15)
				)
				(justify right top)
			)
		)
		(pad "1" smd roundrect
			(at -1.099999 0 180)
			(size 1.2 1.3)
			(layers "F.Cu" "F.Mask" "F.Paste")
			(roundrect_rratio 0.25)
			(net 1 "GND")
			(pintype "passive")
		)
		(pad "2" smd roundrect
			(at 1.099999 0 180)
			(size 1.2 1.3)
			(layers "F.Cu" "F.Mask" "F.Paste")
			(roundrect_rratio 0.25)
			(net 13 "VCC")
			(pintype "passive")
		)
	)
	(footprint "antmicro-footprints:SOT-523"
		(layer "F.Cu")
		(at 83.5 57.5 -90)
		(property "Reference" "Q18"
			(at -0.9 -1.4 270)
			(layer "F.SilkS")
			(effects
				(font
					(size 0.7 0.7)
					(thickness 0.15)
				)
				(justify right top)
			)
		)
		(property "Value" "DMG1012T-7"
			(at 0.1 1.824 90)
			(layer "F.Fab")
			(effects
				(font
					(size 0.7 0.7)
					(thickness 0.15)
				)
				(justify right top)
			)
		)
		(property "Datasheet" "https://www.diodes.com/assets/Datasheets/ds31783.pdf"
			(at 0 0 90)
			(layer "F.Fab")
			(hide yes)
			(effects
				(font
					(size 1.27 1.27)
					(thickness 0.15)
				)
			)
		)
		(property "Description" "Power MOSFET, N Channel, 20 V, 630 mA, 0.3 ohm, SOT-523, Surface Mount"
			(at 0 0 90)
			(layer "F.Fab")
			(hide yes)
			(effects
				(font
					(size 1.27 1.27)
					(thickness 0.15)
				)
			)
		)
		(property "MPN" "DMG1012T-7"
			(at 0 0 270)
			(unlocked yes)
			(layer "F.Fab")
			(hide yes)
			(effects
				(font
					(size 1 1)
					(thickness 0.15)
				)
			)
		)
		(property "Manufacturer" "Diodes Incorporated"
			(at 0 0 270)
			(unlocked yes)
			(layer "F.Fab")
			(hide yes)
			(effects
				(font
					(size 1 1)
					(thickness 0.15)
				)
			)
		)
		(property "Author" "Antmicro"
			(at 0 0 270)
			(unlocked yes)
			(layer "F.Fab")
			(hide yes)
			(effects
				(font
					(size 1 1)
					(thickness 0.15)
				)
			)
		)
		(property "License" "Apache-2.0"
			(at 0 0 270)
			(unlocked yes)
			(layer "F.Fab")
			(hide yes)
			(effects
				(font
					(size 1 1)
					(thickness 0.15)
				)
			)
		)
		(sheetname "/SoM_Power/")
		(sheetfile "som_power.kicad_sch")
		(attr smd)
		(fp_line
			(start -0.927 -0.051)
			(end -0.927 -0.351)
			(stroke
				(width 0.15)
				(type solid)
			)
			(layer "F.SilkS")
		)
		(fp_line
			(start -0.927 -0.351)
			(end -0.725 -0.551)
			(stroke
				(width 0.15)
				(type solid)
			)
			(layer "F.SilkS")
		)
		(fp_line
			(start -0.725 -0.551)
			(end -0.277 -0.551)
			(stroke
				(width 0.15)
				(type solid)
			)
			(layer "F.SilkS")
		)
		(fp_line
			(start -0.277 -0.551)
			(end -0.277 -0.75)
			(stroke
				(width 0.15)
				(type solid)
			)
			(layer "F.SilkS")
		)
		(fp_circle
			(center -0.9652 0.9652)
			(end -0.9152 0.9652)
			(stroke
				(width 0.15)
				(type solid)
			)
			(fill yes)
			(layer "F.SilkS")
		)
		(fp_line
			(start -1.12 1.15)
			(end 1.1 1.15)
			(stroke
				(width 0.05)
				(type solid)
			)
			(layer "F.CrtYd")
		)
		(fp_line
			(start -1.12 -1.16)
			(end -1.12 1.15)
			(stroke
				(width 0.05)
				(type solid)
			)
			(layer "F.CrtYd")
		)
		(fp_line
			(start -1.12 -1.16)
			(end 1.1 -1.16)
			(stroke
				(width 0.05)
				(type solid)
			)
			(layer "F.CrtYd")
		)
		(fp_line
			(start 1.1 -1.16)
			(end 1.1 1.15)
			(stroke
				(width 0.05)
				(type solid)
			)
			(layer "F.CrtYd")
		)
		(fp_line
			(start 0.8 0.424)
			(end -0.802 0.424)
			(stroke
				(width 0.15)
				(type solid)
			)
			(layer "F.Fab")
		)
		(fp_line
			(start -0.802 -0.276)
			(end -0.802 0.424)
			(stroke
				(width 0.15)
				(type solid)
			)
			(layer "F.Fab")
		)
		(fp_line
			(start -0.652 -0.425)
			(end -0.802 -0.276)
			(stroke
				(width 0.15)
				(type solid)
			)
			(layer "F.Fab")
		)
		(fp_line
			(start 0.8 -0.425)
			(end 0.8 0.424)
			(stroke
				(width 0.15)
				(type solid)
			)
			(layer "F.Fab")
		)
		(fp_line
			(start 0.8 -0.425)
			(end -0.652 -0.425)
			(stroke
				(width 0.15)
				(type solid)
			)
			(layer "F.Fab")
		)
		(fp_circle
			(center -0.9652 0.9652)
			(end -0.9144 0.9652)
			(stroke
				(width 0.15)
				(type solid)
			)
			(fill no)
			(layer "F.Fab")
		)
		(fp_text user "Author: Antmicro"
			(at -1.12 6.224 90)
			(layer "F.Fab")
			(effects
				(font
					(size 0.7 0.7)
					(thickness 0.15)
				)
				(justify right top)
			)
		)
		(fp_text user "License: Apache-2.0"
			(at -1.12 5.024 90)
			(layer "F.Fab")
			(effects
				(font
					(size 0.7 0.7)
					(thickness 0.15)
				)
				(justify right top)
			)
		)
		(fp_text user "${REFERENCE}"
			(at -1.12 3.824 90)
			(layer "F.Fab")
			(effects
				(font
					(size 0.7 0.7)
					(thickness 0.15)
				)
				(justify right top)
			)
		)
		(pad "1" smd rect
			(at -0.5 0.65 270)
			(size 0.4 0.51)
			(layers "F.Cu" "F.Mask" "F.Paste")
			(net 683 "/SoM_Power/~{SOM_PRSNT}")
			(pinfunction "G")
			(pintype "input")
		)
		(pad "2" smd rect
			(at 0.498 0.65 270)
			(size 0.4 0.51)
			(layers "F.Cu" "F.Mask" "F.Paste")
			(net 1 "GND")
			(pinfunction "S")
			(pintype "passive")
		)
		(pad "3" smd rect
			(at 0 -0.652 270)
			(size 0.4 0.51)
			(layers "F.Cu" "F.Mask" "F.Paste")
			(net 888 "Net-(Q18-D)")
			(pinfunction "D")
			(pintype "passive")
		)
	)
	(footprint "antmicro-footprints:C_0402_1005Metric"
		(layer "F.Cu")
		(at 170.784468 134.57)
		(descr "Capacitor SMD 0402")
		(tags "capacitor SMD 0402")
		(property "Reference" "C384"
			(at 1.015532 0.63 0)
			(layer "F.SilkS")
			(effects
				(font
					(size 0.7 0.7)
					(thickness 0.15)
				)
				(justify left bottom)
			)
		)
		(property "Value" "C_100n_0402"
			(at -1.022927 2.155213 0)
			(layer "F.Fab")
			(effects
				(font
					(size 0.7 0.7)
					(thickness 0.15)
				)
				(justify left bottom)
			)
		)
		(property "Datasheet" "https://www.murata.com/products/productdetail?partno=GRM155R61H104KE14%23"
			(at 0 0 0)
			(layer "F.Fab")
			(hide yes)
			(effects
				(font
					(size 1.27 1.27)
					(thickness 0.15)
				)
			)
		)
		(property "Description" "SMD Multilayer Ceramic Capacitor, 0.1 µF, 50 V, 0402 [1005 Metric], ± 10%, X5R, GRM Series"
			(at 0 0 0)
			(layer "F.Fab")
			(hide yes)
			(effects
				(font
					(size 1.27 1.27)
					(thickness 0.15)
				)
			)
		)
		(property "Manufacturer" "Murata"
			(at 0 0 0)
			(unlocked yes)
			(layer "F.Fab")
			(hide yes)
			(effects
				(font
					(size 1 1)
					(thickness 0.15)
				)
			)
		)
		(property "MPN" "GRM155R61H104KE14D"
			(at 0 0 0)
			(unlocked yes)
			(layer "F.Fab")
			(hide yes)
			(effects
				(font
					(size 1 1)
					(thickness 0.15)
				)
			)
		)
		(property "Val" "100n"
			(at 0 0 0)
			(unlocked yes)
			(layer "F.Fab")
			(hide yes)
			(effects
				(font
					(size 1 1)
					(thickness 0.15)
				)
			)
		)
		(property "License" "Apache-2.0"
			(at 0 0 0)
			(unlocked yes)
			(layer "F.Fab")
			(hide yes)
			(effects
				(font
					(size 1 1)
					(thickness 0.15)
				)
			)
		)
		(property "Author" "Antmicro"
			(at 0 0 0)
			(unlocked yes)
			(layer "F.Fab")
			(hide yes)
			(effects
				(font
					(size 1 1)
					(thickness 0.15)
				)
			)
		)
		(property "Voltage" "50V"
			(at 0 0 0)
			(unlocked yes)
			(layer "F.Fab")
			(hide yes)
			(effects
				(font
					(size 1 1)
					(thickness 0.15)
				)
			)
		)
		(property "Dielectric" "X5R"
			(at 0 0 0)
			(unlocked yes)
			(layer "F.Fab")
			(hide yes)
			(effects
				(font
					(size 1 1)
					(thickness 0.15)
				)
			)
		)
		(sheetname "/DCDC/")
		(sheetfile "dcdc.kicad_sch")
		(attr smd)
		(fp_rect
			(start -0.925 -0.47)
			(end 0.925 0.47)
			(stroke
				(width 0.05)
				(type default)
			)
			(fill no)
			(layer "F.CrtYd")
		)
		(fp_line
			(start -0.494 -0.25)
			(end 0.504 -0.25)
			(stroke
				(width 0.15)
				(type solid)
			)
			(layer "F.Fab")
		)
		(fp_line
			(start -0.494 0.248)
			(end -0.494 -0.25)
			(stroke
				(width 0.15)
				(type solid)
			)
			(layer "F.Fab")
		)
		(fp_line
			(start 0.504 -0.25)
			(end 0.504 0.248)
			(stroke
				(width 0.15)
				(type solid)
			)
			(layer "F.Fab")
		)
		(fp_line
			(start 0.504 0.248)
			(end -0.494 0.248)
			(stroke
				(width 0.15)
				(type solid)
			)
			(layer "F.Fab")
		)
		(fp_text user "Author: Antmicro"
			(at -0.939 3.399 0)
			(layer "F.Fab")
			(effects
				(font
					(size 0.7 0.7)
					(thickness 0.15)
				)
				(justify left bottom)
			)
		)
		(fp_text user "${REFERENCE}"
			(at -0.939 4.599 0)
			(layer "F.Fab")
			(effects
				(font
					(size 0.7 0.7)
					(thickness 0.15)
				)
				(justify left bottom)
			)
		)
		(fp_text user "License: Apache-2.0"
			(at -0.939 5.799 0)
			(layer "F.Fab")
			(effects
				(font
					(size 0.7 0.7)
					(thickness 0.15)
				)
				(justify left bottom)
			)
		)
		(pad "1" smd roundrect
			(at -0.48 0)
			(size 0.59 0.64)
			(layers "F.Cu" "F.Mask" "F.Paste")
			(roundrect_rratio 0.25)
			(net 1162 "Net-(U60-IN-)")
			(pintype "passive")
		)
		(pad "2" smd roundrect
			(at 0.48 0)
			(size 0.59 0.64)
			(layers "F.Cu" "F.Mask" "F.Paste")
			(roundrect_rratio 0.25)
			(net 1282 "Net-(U60-IN+)")
			(pintype "passive")
		)
	)
	(footprint "antmicro-footprints:C_0402_1005Metric"
		(layer "F.Cu")
		(at 218.8 112.7 180)
		(descr "Capacitor SMD 0402")
		(tags "capacitor SMD 0402")
		(property "Reference" "C102"
			(at 0.9 0.4 0)
			(layer "F.SilkS")
			(effects
				(font
					(size 0.7 0.7)
					(thickness 0.15)
				)
				(justify right top)
			)
		)
		(property "Value" "C_100n_0402"
			(at -1.022927 2.155213 0)
			(layer "F.Fab")
			(effects
				(font
					(size 0.7 0.7)
					(thickness 0.15)
				)
				(justify right top)
			)
		)
		(property "Datasheet" "https://www.murata.com/products/productdetail?partno=GRM155R61H104KE14%23"
			(at 0 0 0)
			(layer "F.Fab")
			(hide yes)
			(effects
				(font
					(size 1.27 1.27)
					(thickness 0.15)
				)
			)
		)
		(property "Description" "SMD Multilayer Ceramic Capacitor, 0.1 µF, 50 V, 0402 [1005 Metric], ± 10%, X5R, GRM Series"
			(at 0 0 0)
			(layer "F.Fab")
			(hide yes)
			(effects
				(font
					(size 1.27 1.27)
					(thickness 0.15)
				)
			)
		)
		(property "Manufacturer" "Murata"
			(at 0 0 180)
			(unlocked yes)
			(layer "F.Fab")
			(hide yes)
			(effects
				(font
					(size 1 1)
					(thickness 0.15)
				)
			)
		)
		(property "MPN" "GRM155R61H104KE14D"
			(at 0 0 180)
			(unlocked yes)
			(layer "F.Fab")
			(hide yes)
			(effects
				(font
					(size 1 1)
					(thickness 0.15)
				)
			)
		)
		(property "Val" "100n"
			(at 0 0 180)
			(unlocked yes)
			(layer "F.Fab")
			(hide yes)
			(effects
				(font
					(size 1 1)
					(thickness 0.15)
				)
			)
		)
		(property "License" "Apache-2.0"
			(at 0 0 180)
			(unlocked yes)
			(layer "F.Fab")
			(hide yes)
			(effects
				(font
					(size 1 1)
					(thickness 0.15)
				)
			)
		)
		(property "Author" "Antmicro"
			(at 0 0 180)
			(unlocked yes)
			(layer "F.Fab")
			(hide yes)
			(effects
				(font
					(size 1 1)
					(thickness 0.15)
				)
			)
		)
		(property "Voltage" "50V"
			(at 0 0 180)
			(unlocked yes)
			(layer "F.Fab")
			(hide yes)
			(effects
				(font
					(size 1 1)
					(thickness 0.15)
				)
			)
		)
		(property "Dielectric" "X5R"
			(at 0 0 180)
			(unlocked yes)
			(layer "F.Fab")
			(hide yes)
			(effects
				(font
					(size 1 1)
					(thickness 0.15)
				)
			)
		)
		(sheetname "/USB Hub/")
		(sheetfile "usb_hub.kicad_sch")
		(attr smd)
		(fp_rect
			(start -0.925 -0.47)
			(end 0.925 0.47)
			(stroke
				(width 0.05)
				(type default)
			)
			(fill no)
			(layer "F.CrtYd")
		)
		(fp_line
			(start 0.504 0.248)
			(end -0.494 0.248)
			(stroke
				(width 0.15)
				(type solid)
			)
			(layer "F.Fab")
		)
		(fp_line
			(start 0.504 -0.25)
			(end 0.504 0.248)
			(stroke
				(width 0.15)
				(type solid)
			)
			(layer "F.Fab")
		)
		(fp_line
			(start -0.494 0.248)
			(end -0.494 -0.25)
			(stroke
				(width 0.15)
				(type solid)
			)
			(layer "F.Fab")
		)
		(fp_line
			(start -0.494 -0.25)
			(end 0.504 -0.25)
			(stroke
				(width 0.15)
				(type solid)
			)
			(layer "F.Fab")
		)
		(fp_text user "License: Apache-2.0"
			(at -0.939 5.799 0)
			(layer "F.Fab")
			(effects
				(font
					(size 0.7 0.7)
					(thickness 0.15)
				)
				(justify right top)
			)
		)
		(fp_text user "${REFERENCE}"
			(at -0.939 4.599 0)
			(layer "F.Fab")
			(effects
				(font
					(size 0.7 0.7)
					(thickness 0.15)
				)
				(justify right top)
			)
		)
		(fp_text user "Author: Antmicro"
			(at -0.939 3.399 0)
			(layer "F.Fab")
			(effects
				(font
					(size 0.7 0.7)
					(thickness 0.15)
				)
				(justify right top)
			)
		)
		(pad "1" smd roundrect
			(at -0.48 0 180)
			(size 0.59 0.64)
			(layers "F.Cu" "F.Mask" "F.Paste")
			(roundrect_rratio 0.25)
			(net 103 "/USB Hub/USBC3_CONN_TX2_N")
			(pintype "passive")
		)
		(pad "2" smd roundrect
			(at 0.48 0 180)
			(size 0.59 0.64)
			(layers "F.Cu" "F.Mask" "F.Paste")
			(roundrect_rratio 0.25)
			(net 212 "/USB Hub/USBC3_TX_{2}+")
			(pintype "passive")
		)
	)
	(footprint "antmicro-footprints:VQFN-16-1EP_3x3mm_P0.5mm_EP1.68x1.68mm"
		(layer "F.Cu")
		(at 139.181999 107.9)
		(property "Reference" "U71"
			(at 0.918001 -1.9 0)
			(layer "F.SilkS")
			(effects
				(font
					(size 0.7 0.7)
					(thickness 0.15)
				)
				(justify left bottom)
			)
		)
		(property "Value" "PCAL6408A_VQFN"
			(at 0 2.95 0)
			(layer "F.Fab")
			(effects
				(font
					(size 0.7 0.7)
					(thickness 0.15)
				)
				(justify left bottom)
			)
		)
		(property "Datasheet" "https://eu.mouser.com/datasheet/2/302/PCAL6408A-3139197.pdf"
			(at 0 0 0)
			(layer "F.Fab")
			(hide yes)
			(effects
				(font
					(size 1.27 1.27)
					(thickness 0.15)
				)
			)
		)
		(property "Description" "I/O Expander, 8 bit, I2C, 1.65-5.5 V, HVQFN, 16 Pins"
			(at 0 0 0)
			(layer "F.Fab")
			(hide yes)
			(effects
				(font
					(size 1.27 1.27)
					(thickness 0.15)
				)
			)
		)
		(property "MPN" "PCAL6408ABSHP"
			(at 0 0 0)
			(unlocked yes)
			(layer "F.Fab")
			(hide yes)
			(effects
				(font
					(size 1 1)
					(thickness 0.15)
				)
			)
		)
		(property "Manufacturer" "NXP"
			(at 0 0 0)
			(unlocked yes)
			(layer "F.Fab")
			(hide yes)
			(effects
				(font
					(size 1 1)
					(thickness 0.15)
				)
			)
		)
		(property "Author" "Antmicro"
			(at 0 0 0)
			(unlocked yes)
			(layer "F.Fab")
			(hide yes)
			(effects
				(font
					(size 1 1)
					(thickness 0.15)
				)
			)
		)
		(property "License" "Apache-2.0"
			(at 0 0 0)
			(unlocked yes)
			(layer "F.Fab")
			(hide yes)
			(effects
				(font
					(size 1 1)
					(thickness 0.15)
				)
			)
		)
		(sheetname "/Peripherals/")
		(sheetfile "peripherals.kicad_sch")
		(attr smd)
		(fp_line
			(start -1.5 -1.2)
			(end -1.5 -1)
			(stroke
				(width 0.15)
				(type solid)
			)
			(layer "F.SilkS")
		)
		(fp_line
			(start -1.5 -1.2)
			(end -1.2 -1.5)
			(stroke
				(width 0.15)
				(type solid)
			)
			(layer "F.SilkS")
		)
		(fp_line
			(start -1.5 1.499)
			(end -1.5 1)
			(stroke
				(width 0.15)
				(type solid)
			)
			(layer "F.SilkS")
		)
		(fp_line
			(start -1.5 1.499)
			(end -1 1.5)
			(stroke
				(width 0.15)
				(type solid)
			)
			(layer "F.SilkS")
		)
		(fp_line
			(start -1 -1.501)
			(end -1.2 -1.5)
			(stroke
				(width 0.15)
				(type solid)
			)
			(layer "F.SilkS")
		)
		(fp_line
			(start 1 1.499)
			(end 1.499 1.499)
			(stroke
				(width 0.15)
				(type solid)
			)
			(layer "F.SilkS")
		)
		(fp_line
			(start 1.499 -1.5)
			(end 1 -1.5)
			(stroke
				(width 0.15)
				(type solid)
			)
			(layer "F.SilkS")
		)
		(fp_line
			(start 1.5 -1)
			(end 1.499 -1.5)
			(stroke
				(width 0.15)
				(type solid)
			)
			(layer "F.SilkS")
		)
		(fp_line
			(start 1.5 1)
			(end 1.499 1.499)
			(stroke
				(width 0.15)
				(type solid)
			)
			(layer "F.SilkS")
		)
		(fp_circle
			(center -1.6 -1.6)
			(end -1.55 -1.6)
			(stroke
				(width 0.15)
				(type solid)
			)
			(fill yes)
			(layer "F.SilkS")
		)
		(fp_rect
			(start -1.75 -1.75)
			(end 1.75 1.75)
			(stroke
				(width 0.05)
				(type solid)
			)
			(fill no)
			(layer "F.CrtYd")
		)
		(fp_line
			(start -1.5 -1.2)
			(end -1.5 1.499)
			(stroke
				(width 0.15)
				(type solid)
			)
			(layer "F.Fab")
		)
		(fp_line
			(start -1.5 -1.2)
			(end -1.2 -1.5)
			(stroke
				(width 0.15)
				(type solid)
			)
			(layer "F.Fab")
		)
		(fp_line
			(start -1.2 -1.5)
			(end 1.499 -1.5)
			(stroke
				(width 0.15)
				(type solid)
			)
			(layer "F.Fab")
		)
		(fp_line
			(start 1.499 1.499)
			(end -1.5 1.499)
			(stroke
				(width 0.15)
				(type solid)
			)
			(layer "F.Fab")
		)
		(fp_line
			(start 1.499 1.499)
			(end 1.499 -1.5)
			(stroke
				(width 0.15)
				(type solid)
			)
			(layer "F.Fab")
		)
		(fp_text user "License: Apache-2.0"
			(at -1.901 7.4 0)
			(layer "F.Fab")
			(effects
				(font
					(size 0.7 0.7)
					(thickness 0.15)
				)
				(justify left bottom)
			)
		)
		(fp_text user "${REFERENCE}"
			(at -1.901 4.998 0)
			(layer "F.Fab")
			(effects
				(font
					(size 0.7 0.7)
					(thickness 0.15)
				)
				(justify left bottom)
			)
		)
		(fp_text user "Author: Antmicro"
			(at -1.901 6.2 0)
			(layer "F.Fab")
			(effects
				(font
					(size 0.7 0.7)
					(thickness 0.15)
				)
				(justify left bottom)
			)
		)
		(pad "1" smd roundrect
			(at -1.4 -0.75)
			(size 0.6 0.25)
			(layers "F.Cu" "F.Mask" "F.Paste")
			(roundrect_rratio 0.2)
			(net 1310 "Net-(U71-~{RESET})")
			(pinfunction "~{RESET}")
			(pintype "input")
		)
		(pad "2" smd roundrect
			(at -1.4 -0.25)
			(size 0.6 0.25)
			(layers "F.Cu" "F.Mask" "F.Paste")
			(roundrect_rratio 0.2)
			(net 1315 "/Peripherals/GPIOEX_P0_0")
			(pinfunction "P0")
			(pintype "bidirectional")
		)
		(pad "3" smd roundrect
			(at -1.4 0.25)
			(size 0.6 0.25)
			(layers "F.Cu" "F.Mask" "F.Paste")
			(roundrect_rratio 0.2)
			(net 1314 "/Peripherals/GPIOEX_P0_1")
			(pinfunction "P1")
			(pintype "bidirectional")
		)
		(pad "4" smd roundrect
			(at -1.4 0.75)
			(size 0.6 0.25)
			(layers "F.Cu" "F.Mask" "F.Paste")
			(roundrect_rratio 0.2)
			(net 1313 "/Peripherals/GPIOEX_P0_2")
			(pinfunction "P2")
			(pintype "bidirectional")
		)
		(pad "5" smd roundrect
			(at -0.75 1.4 90)
			(size 0.6 0.25)
			(layers "F.Cu" "F.Mask" "F.Paste")
			(roundrect_rratio 0.2)
			(net 1312 "/Peripherals/GPIOEX_P0_3")
			(pinfunction "P3")
			(pintype "bidirectional")
		)
		(pad "6" smd roundrect
			(at -0.25 1.4 90)
			(size 0.6 0.25)
			(layers "F.Cu" "F.Mask" "F.Paste")
			(roundrect_rratio 0.2)
			(net 1 "GND")
			(pinfunction "V_{ss}")
			(pintype "power_in")
		)
		(pad "7" smd roundrect
			(at 0.25 1.4 90)
			(size 0.6 0.25)
			(layers "F.Cu" "F.Mask" "F.Paste")
			(roundrect_rratio 0.2)
			(net 1316 "/Peripherals/GPIOEX_P0_4")
			(pinfunction "P4")
			(pintype "bidirectional")
		)
		(pad "8" smd roundrect
			(at 0.75 1.4 90)
			(size 0.6 0.25)
			(layers "F.Cu" "F.Mask" "F.Paste")
			(roundrect_rratio 0.2)
			(net 1317 "/Peripherals/GPIOEX_P0_5")
			(pinfunction "P5")
			(pintype "bidirectional")
		)
		(pad "9" smd roundrect
			(at 1.4 0.75 180)
			(size 0.6 0.25)
			(layers "F.Cu" "F.Mask" "F.Paste")
			(roundrect_rratio 0.2)
			(net 1318 "/Peripherals/GPIOEX_P0_6")
			(pinfunction "P6")
			(pintype "bidirectional")
		)
		(pad "10" smd roundrect
			(at 1.4 0.25 180)
			(size 0.6 0.25)
			(layers "F.Cu" "F.Mask" "F.Paste")
			(roundrect_rratio 0.2)
			(net 1319 "/Peripherals/GPIOEX_P0_7")
			(pinfunction "P7")
			(pintype "bidirectional")
		)
		(pad "11" smd roundrect
			(at 1.4 -0.25 180)
			(size 0.6 0.25)
			(layers "F.Cu" "F.Mask" "F.Paste")
			(roundrect_rratio 0.2)
			(net 1309 "/Peripherals/GPIO_EXP_IRQ")
			(pinfunction "~{INT}")
			(pintype "output")
		)
		(pad "12" smd roundrect
			(at 1.4 -0.75 180)
			(size 0.6 0.25)
			(layers "F.Cu" "F.Mask" "F.Paste")
			(roundrect_rratio 0.2)
			(net 853 "/I2C_{SYS}.SCL")
			(pinfunction "SCL")
			(pintype "input")
		)
		(pad "13" smd roundrect
			(at 0.75 -1.4 270)
			(size 0.6 0.25)
			(layers "F.Cu" "F.Mask" "F.Paste")
			(roundrect_rratio 0.2)
			(net 850 "/I2C_{SYS}.SDA")
			(pinfunction "SDA")
			(pintype "bidirectional")
		)
		(pad "14" smd roundrect
			(at 0.25 -1.4 270)
			(size 0.6 0.25)
			(layers "F.Cu" "F.Mask" "F.Paste")
			(roundrect_rratio 0.2)
			(net 2 "+3V3")
			(pinfunction "VDD_{(P)}")
			(pintype "power_in")
		)
		(pad "15" smd roundrect
			(at -0.25 -1.4 270)
			(size 0.6 0.25)
			(layers "F.Cu" "F.Mask" "F.Paste")
			(roundrect_rratio 0.2)
			(net 2 "+3V3")
			(pinfunction "VDD_{(I2C)}")
			(pintype "power_in")
		)
		(pad "16" smd roundrect
			(at -0.75 -1.4 270)
			(size 0.6 0.25)
			(layers "F.Cu" "F.Mask" "F.Paste")
			(roundrect_rratio 0.2)
			(net 1311 "Net-(U71-ADDR)")
			(pinfunction "ADDR")
			(pintype "passive")
		)
		(pad "17" smd roundrect
			(at 0 0)
			(size 1.68 1.68)
			(layers "F.Cu" "F.Mask" "F.Paste")
			(roundrect_rratio 0.02976190476)
			(net 1324 "unconnected-(U71-EP-Pad17)")
			(pinfunction "EP")
			(pintype "power_in+no_connect")
		)
	)
	(footprint "antmicro-footprints:TP_SMD_0.75mm"
		(layer "F.Cu")
		(at 168.5 57.17 90)
		(property "Reference" "TP63"
			(at -2.15 -0.63 90)
			(layer "F.SilkS")
			(hide yes)
			(effects
				(font
					(size 0.7 0.7)
					(thickness 0.15)
				)
				(justify left bottom)
			)
		)
		(property "Value" "TP_0.75mm_SMD"
			(at 0 1.2 90)
			(layer "F.Fab")
			(effects
				(font
					(size 0.7 0.7)
					(thickness 0.15)
				)
				(justify left bottom)
			)
		)
		(property "Description" "SMT test point"
			(at 0 0 90)
			(layer "F.Fab")
			(hide yes)
			(effects
				(font
					(size 1.27 1.27)
					(thickness 0.15)
				)
			)
		)
		(property "MPN" ""
			(at 0 0 90)
			(unlocked yes)
			(layer "F.Fab")
			(hide yes)
			(effects
				(font
					(size 1 1)
					(thickness 0.15)
				)
			)
		)
		(property "Manufacturer" ""
			(at 0 0 90)
			(unlocked yes)
			(layer "F.Fab")
			(hide yes)
			(effects
				(font
					(size 1 1)
					(thickness 0.15)
				)
			)
		)
		(property "Author" "Antmicro"
			(at 0 0 90)
			(unlocked yes)
			(layer "F.Fab")
			(hide yes)
			(effects
				(font
					(size 1 1)
					(thickness 0.15)
				)
			)
		)
		(property "License" "Apache-2.0"
			(at 0 0 90)
			(unlocked yes)
			(layer "F.Fab")
			(hide yes)
			(effects
				(font
					(size 1 1)
					(thickness 0.15)
				)
			)
		)
		(sheetname "/Power/")
		(sheetfile "power.kicad_sch")
		(attr exclude_from_pos_files exclude_from_bom)
		(fp_circle
			(center 0 0)
			(end 0.475 0)
			(stroke
				(width 0.05)
				(type default)
			)
			(fill no)
			(layer "F.CrtYd")
		)
		(fp_text user "Author: Antmicro"
			(at -0.4 3.901 90)
			(layer "F.Fab")
			(effects
				(font
					(size 0.7 0.7)
					(thickness 0.15)
				)
				(justify left bottom)
			)
		)
		(fp_text user "${REFERENCE}"
			(at -0.4 2.7 90)
			(layer "F.Fab")
			(effects
				(font
					(size 0.7 0.7)
					(thickness 0.15)
				)
				(justify left bottom)
			)
		)
		(fp_text user "License: Apache-2.0"
			(at -0.4 5.101 90)
			(layer "F.Fab")
			(effects
				(font
					(size 0.7 0.7)
					(thickness 0.15)
				)
				(justify left bottom)
			)
		)
		(pad "1" smd circle
			(at 0 0 90)
			(size 0.75 0.75)
			(layers "F.Cu" "F.Mask")
			(net 4 "+3V3_AON")
			(pinfunction "1")
			(pintype "passive")
		)
	)
	(footprint "antmicro-footprints:C_0805_2012Metric"
		(layer "F.Cu")
		(at 162.2 93.3 -90)
		(descr "Capacitor SMD 0805")
		(tags "capacitor SMD 0805")
		(property "Reference" "C247"
			(at -4.7 0.3 90)
			(layer "F.SilkS")
			(effects
				(font
					(size 0.7 0.7)
					(thickness 0.15)
				)
				(justify right top)
			)
		)
		(property "Value" "C_22u_25V_0805"
			(at -2.055717 1.963152 90)
			(layer "F.Fab")
			(effects
				(font
					(size 0.7 0.7)
					(thickness 0.15)
				)
				(justify right top)
			)
		)
		(property "Datasheet" "https://product.samsungsem.com/mlcc/CL21A226MAYNNN.do"
			(at 0 0 90)
			(layer "F.Fab")
			(hide yes)
			(effects
				(font
					(size 1.27 1.27)
					(thickness 0.15)
				)
			)
		)
		(property "Description" "SMT Multilayer Ceramic Capacitor, 22uF, +/-20%, 25V, X5R, 0805 [2012 Metric]"
			(at 0 0 90)
			(layer "F.Fab")
			(hide yes)
			(effects
				(font
					(size 1.27 1.27)
					(thickness 0.15)
				)
			)
		)
		(property "MPN" "CL21A226MAYNNNE"
			(at 0 0 270)
			(unlocked yes)
			(layer "F.Fab")
			(hide yes)
			(effects
				(font
					(size 1 1)
					(thickness 0.15)
				)
			)
		)
		(property "Manufacturer" "Samsung Electro-Mechanics"
			(at 0 0 270)
			(unlocked yes)
			(layer "F.Fab")
			(hide yes)
			(effects
				(font
					(size 1 1)
					(thickness 0.15)
				)
			)
		)
		(property "License" "Apache-2.0"
			(at 0 0 270)
			(unlocked yes)
			(layer "F.Fab")
			(hide yes)
			(effects
				(font
					(size 1 1)
					(thickness 0.15)
				)
			)
		)
		(property "Author" "Antmicro"
			(at 0 0 270)
			(unlocked yes)
			(layer "F.Fab")
			(hide yes)
			(effects
				(font
					(size 1 1)
					(thickness 0.15)
				)
			)
		)
		(property "Val" "22u"
			(at 0 0 270)
			(unlocked yes)
			(layer "F.Fab")
			(hide yes)
			(effects
				(font
					(size 1 1)
					(thickness 0.15)
				)
			)
		)
		(property "Voltage" "25V"
			(at 0 0 270)
			(unlocked yes)
			(layer "F.Fab")
			(hide yes)
			(effects
				(font
					(size 1 1)
					(thickness 0.15)
				)
			)
		)
		(property "Dielectric" "X5R"
			(at 0 0 270)
			(unlocked yes)
			(layer "F.Fab")
			(hide yes)
			(effects
				(font
					(size 1 1)
					(thickness 0.15)
				)
			)
		)
		(property "Public" "False"
			(at 0 0 270)
			(unlocked yes)
			(layer "F.Fab")
			(hide yes)
			(effects
				(font
					(size 1 1)
					(thickness 0.15)
				)
			)
		)
		(component_classes
			(class "DCDC_SOM")
		)
		(sheetname "/DCDC/")
		(sheetfile "dcdc.kicad_sch")
		(attr smd)
		(fp_line
			(start -0.3 0.7)
			(end 0.3 0.7)
			(stroke
				(width 0.15)
				(type solid)
			)
			(layer "F.SilkS")
		)
		(fp_line
			(start -0.3 -0.7)
			(end 0.3 -0.7)
			(stroke
				(width 0.15)
				(type solid)
			)
			(layer "F.SilkS")
		)
		(fp_rect
			(start 1.95 -0.9)
			(end -1.95 0.9)
			(stroke
				(width 0.05)
				(type default)
			)
			(fill no)
			(layer "F.CrtYd")
		)
		(fp_rect
			(start -0.95 -0.675)
			(end 0.95 0.675)
			(stroke
				(width 0.15)
				(type solid)
			)
			(fill no)
			(layer "F.Fab")
		)
		(fp_text user "License: Apache-2.0"
			(at -1.9 4.947 90)
			(layer "F.Fab")
			(effects
				(font
					(size 0.7 0.7)
					(thickness 0.15)
				)
				(justify right top)
			)
		)
		(fp_text user "Author: Antmicro"
			(at -1.9 5.947 90)
			(layer "F.Fab")
			(effects
				(font
					(size 0.7 0.7)
					(thickness 0.15)
				)
				(justify right top)
			)
		)
		(fp_text user "${REFERENCE}"
			(at -1.9 3.947 90)
			(layer "F.Fab")
			(effects
				(font
					(size 0.7 0.7)
					(thickness 0.15)
				)
				(justify right top)
			)
		)
		(pad "1" smd roundrect
			(at -1.1 0 270)
			(size 1.2 1.3)
			(layers "F.Cu" "F.Mask" "F.Paste")
			(roundrect_rratio 0.25)
			(net 1 "GND")
			(pintype "passive")
		)
		(pad "2" smd roundrect
			(at 1.1 0 270)
			(size 1.2 1.3)
			(layers "F.Cu" "F.Mask" "F.Paste")
			(roundrect_rratio 0.25)
			(net 903 "/DCDC/16V_OUT")
			(pintype "passive")
		)
	)
	(footprint "antmicro-footprints:R_0402_1005Metric"
		(layer "F.Cu")
		(at 156.72 112.2 180)
		(descr "Resistor SMD 0402")
		(tags "resistor SMD 0402")
		(property "Reference" "R376"
			(at -3.68 0.4 0)
			(layer "F.SilkS")
			(effects
				(font
					(size 0.7 0.7)
					(thickness 0.15)
				)
				(justify right top)
			)
		)
		(property "Value" "R_2k2_0402"
			(at -1.011843 1.772047 0)
			(layer "F.Fab")
			(effects
				(font
					(size 0.7 0.7)
					(thickness 0.15)
				)
				(justify right top)
			)
		)
		(property "Datasheet" "https://www.bourns.com/docs/product-datasheets/cr.pdf"
			(at 0 0 0)
			(layer "F.Fab")
			(hide yes)
			(effects
				(font
					(size 1.27 1.27)
					(thickness 0.15)
				)
			)
		)
		(property "Description" "SMD Chip Resistor, 2.2 kohm, ± 1%, 62.5 mW, 0402 [1005 Metric], Thick Film, General Purpose"
			(at 0 0 0)
			(layer "F.Fab")
			(hide yes)
			(effects
				(font
					(size 1.27 1.27)
					(thickness 0.15)
				)
			)
		)
		(property "MPN" "CR0402-FX-2201GLF"
			(at 0 0 180)
			(unlocked yes)
			(layer "F.Fab")
			(hide yes)
			(effects
				(font
					(size 1 1)
					(thickness 0.15)
				)
			)
		)
		(property "Manufacturer" "Bourns"
			(at 0 0 180)
			(unlocked yes)
			(layer "F.Fab")
			(hide yes)
			(effects
				(font
					(size 1 1)
					(thickness 0.15)
				)
			)
		)
		(property "License" "Apache-2.0"
			(at 0 0 180)
			(unlocked yes)
			(layer "F.Fab")
			(hide yes)
			(effects
				(font
					(size 1 1)
					(thickness 0.15)
				)
			)
		)
		(property "Author" "Antmicro"
			(at 0 0 180)
			(unlocked yes)
			(layer "F.Fab")
			(hide yes)
			(effects
				(font
					(size 1 1)
					(thickness 0.15)
				)
			)
		)
		(property "Val" "2k2"
			(at 0 0 180)
			(unlocked yes)
			(layer "F.Fab")
			(hide yes)
			(effects
				(font
					(size 1 1)
					(thickness 0.15)
				)
			)
		)
		(property "Tolerance" "1%"
			(at 0 0 180)
			(unlocked yes)
			(layer "F.Fab")
			(hide yes)
			(effects
				(font
					(size 1 1)
					(thickness 0.15)
				)
			)
		)
		(sheetname "/SoM_IO/")
		(sheetfile "som_io.kicad_sch")
		(attr smd)
		(fp_rect
			(start -0.925 -0.47)
			(end 0.925 0.47)
			(stroke
				(width 0.05)
				(type default)
			)
			(fill no)
			(layer "F.CrtYd")
		)
		(fp_rect
			(start -0.5 -0.25)
			(end 0.5 0.25)
			(stroke
				(width 0.15)
				(type solid)
			)
			(fill no)
			(layer "F.Fab")
		)
		(fp_text user "Author: Antmicro"
			(at -0.95 4.169 0)
			(layer "F.Fab")
			(effects
				(font
					(size 0.7 0.7)
					(thickness 0.15)
				)
				(justify right top)
			)
		)
		(fp_text user "License: Apache-2.0"
			(at -0.95 5.169 0)
			(layer "F.Fab")
			(effects
				(font
					(size 0.7 0.7)
					(thickness 0.15)
				)
				(justify right top)
			)
		)
		(fp_text user "${REFERENCE}"
			(at -0.95 3.168 0)
			(layer "F.Fab")
			(effects
				(font
					(size 0.7 0.7)
					(thickness 0.15)
				)
				(justify right top)
			)
		)
		(pad "1" smd roundrect
			(at -0.48 0 180)
			(size 0.59 0.64)
			(layers "F.Cu" "F.Mask" "F.Paste")
			(roundrect_rratio 0.25)
			(net 2 "+3V3")
			(pintype "passive")
		)
		(pad "2" smd roundrect
			(at 0.48 0 180)
			(size 0.59 0.64)
			(layers "F.Cu" "F.Mask" "F.Paste")
			(roundrect_rratio 0.25)
			(net 850 "/I2C_{SYS}.SDA")
			(pintype "passive")
		)
	)
	(footprint "antmicro-footprints:C_0402_1005Metric"
		(layer "F.Cu")
		(at 176.63 90.39 -90)
		(descr "Capacitor SMD 0402")
		(tags "capacitor SMD 0402")
		(property "Reference" "C243"
			(at -3.685 0.445 90)
			(layer "F.SilkS")
			(effects
				(font
					(size 0.7 0.7)
					(thickness 0.15)
				)
				(justify right top)
			)
		)
		(property "Value" "C_100n_0402"
			(at -1.022927 2.155213 90)
			(layer "F.Fab")
			(effects
				(font
					(size 0.7 0.7)
					(thickness 0.15)
				)
				(justify right top)
			)
		)
		(property "Datasheet" "https://www.murata.com/products/productdetail?partno=GRM155R61H104KE14%23"
			(at 0 0 90)
			(layer "F.Fab")
			(hide yes)
			(effects
				(font
					(size 1.27 1.27)
					(thickness 0.15)
				)
			)
		)
		(property "Description" "SMD Multilayer Ceramic Capacitor, 0.1 µF, 50 V, 0402 [1005 Metric], ± 10%, X5R, GRM Series"
			(at 0 0 90)
			(layer "F.Fab")
			(hide yes)
			(effects
				(font
					(size 1.27 1.27)
					(thickness 0.15)
				)
			)
		)
		(property "Manufacturer" "Murata"
			(at 0 0 270)
			(unlocked yes)
			(layer "F.Fab")
			(hide yes)
			(effects
				(font
					(size 1 1)
					(thickness 0.15)
				)
			)
		)
		(property "MPN" "GRM155R61H104KE14D"
			(at 0 0 270)
			(unlocked yes)
			(layer "F.Fab")
			(hide yes)
			(effects
				(font
					(size 1 1)
					(thickness 0.15)
				)
			)
		)
		(property "Val" "100n"
			(at 0 0 270)
			(unlocked yes)
			(layer "F.Fab")
			(hide yes)
			(effects
				(font
					(size 1 1)
					(thickness 0.15)
				)
			)
		)
		(property "License" "Apache-2.0"
			(at 0 0 270)
			(unlocked yes)
			(layer "F.Fab")
			(hide yes)
			(effects
				(font
					(size 1 1)
					(thickness 0.15)
				)
			)
		)
		(property "Author" "Antmicro"
			(at 0 0 270)
			(unlocked yes)
			(layer "F.Fab")
			(hide yes)
			(effects
				(font
					(size 1 1)
					(thickness 0.15)
				)
			)
		)
		(property "Voltage" "50V"
			(at 0 0 270)
			(unlocked yes)
			(layer "F.Fab")
			(hide yes)
			(effects
				(font
					(size 1 1)
					(thickness 0.15)
				)
			)
		)
		(property "Dielectric" "X5R"
			(at 0 0 270)
			(unlocked yes)
			(layer "F.Fab")
			(hide yes)
			(effects
				(font
					(size 1 1)
					(thickness 0.15)
				)
			)
		)
		(component_classes
			(class "DCDC_SOM")
		)
		(sheetname "/DCDC/")
		(sheetfile "dcdc.kicad_sch")
		(attr smd)
		(fp_rect
			(start -0.925 -0.47)
			(end 0.925 0.47)
			(stroke
				(width 0.05)
				(type default)
			)
			(fill no)
			(layer "F.CrtYd")
		)
		(fp_line
			(start -0.494 0.248)
			(end -0.494 -0.25)
			(stroke
				(width 0.15)
				(type solid)
			)
			(layer "F.Fab")
		)
		(fp_line
			(start 0.504 0.248)
			(end -0.494 0.248)
			(stroke
				(width 0.15)
				(type solid)
			)
			(layer "F.Fab")
		)
		(fp_line
			(start -0.494 -0.25)
			(end 0.504 -0.25)
			(stroke
				(width 0.15)
				(type solid)
			)
			(layer "F.Fab")
		)
		(fp_line
			(start 0.504 -0.25)
			(end 0.504 0.248)
			(stroke
				(width 0.15)
				(type solid)
			)
			(layer "F.Fab")
		)
		(fp_text user "License: Apache-2.0"
			(at -0.939 5.799 90)
			(layer "F.Fab")
			(effects
				(font
					(size 0.7 0.7)
					(thickness 0.15)
				)
				(justify right top)
			)
		)
		(fp_text user "Author: Antmicro"
			(at -0.939 3.399 90)
			(layer "F.Fab")
			(effects
				(font
					(size 0.7 0.7)
					(thickness 0.15)
				)
				(justify right top)
			)
		)
		(fp_text user "${REFERENCE}"
			(at -0.939 4.599 90)
			(layer "F.Fab")
			(effects
				(font
					(size 0.7 0.7)
					(thickness 0.15)
				)
				(justify right top)
			)
		)
		(pad "1" smd roundrect
			(at -0.48 0 270)
			(size 0.59 0.64)
			(layers "F.Cu" "F.Mask" "F.Paste")
			(roundrect_rratio 0.25)
			(net 13 "VCC")
			(pintype "passive")
		)
		(pad "2" smd roundrect
			(at 0.48 0 270)
			(size 0.59 0.64)
			(layers "F.Cu" "F.Mask" "F.Paste")
			(roundrect_rratio 0.25)
			(net 1 "GND")
			(pintype "passive")
		)
	)
	(footprint "antmicro-footprints:R_0402_1005Metric"
		(layer "F.Cu")
		(at 161.734468 98.145 90)
		(descr "Resistor SMD 0402")
		(tags "resistor SMD 0402")
		(property "Reference" "R370"
			(at -0.955 -1.694468 90)
			(layer "F.SilkS")
			(effects
				(font
					(size 0.7 0.7)
					(thickness 0.15)
				)
				(justify left bottom)
			)
		)
		(property "Value" "R_27R_0402"
			(at -1.011843 1.772047 90)
			(layer "F.Fab")
			(effects
				(font
					(size 0.7 0.7)
					(thickness 0.15)
				)
				(justify left bottom)
			)
		)
		(property "Datasheet" "https://www.bourns.com/docs/product-datasheets/cr.pdf"
			(at 0 0 90)
			(layer "F.Fab")
			(hide yes)
			(effects
				(font
					(size 1.27 1.27)
					(thickness 0.15)
				)
			)
		)
		(property "Description" "SMD Chip Resistor, 27 ohm, ± 1%, 63 mW, 0402 [1005 Metric], Thick Film, General Purpose"
			(at 0 0 90)
			(layer "F.Fab")
			(hide yes)
			(effects
				(font
					(size 1.27 1.27)
					(thickness 0.15)
				)
			)
		)
		(property "Manufacturer" "Bourns"
			(at 0 0 90)
			(unlocked yes)
			(layer "F.Fab")
			(hide yes)
			(effects
				(font
					(size 1 1)
					(thickness 0.15)
				)
			)
		)
		(property "MPN" "CR0402-FX-27R0GLF"
			(at 0 0 90)
			(unlocked yes)
			(layer "F.Fab")
			(hide yes)
			(effects
				(font
					(size 1 1)
					(thickness 0.15)
				)
			)
		)
		(property "Val" "27R"
			(at 0 0 90)
			(unlocked yes)
			(layer "F.Fab")
			(hide yes)
			(effects
				(font
					(size 1 1)
					(thickness 0.15)
				)
			)
		)
		(property "License" "Apache-2.0"
			(at 0 0 90)
			(unlocked yes)
			(layer "F.Fab")
			(hide yes)
			(effects
				(font
					(size 1 1)
					(thickness 0.15)
				)
			)
		)
		(property "Author" "Antmicro"
			(at 0 0 90)
			(unlocked yes)
			(layer "F.Fab")
			(hide yes)
			(effects
				(font
					(size 1 1)
					(thickness 0.15)
				)
			)
		)
		(property "Tolerance" "1%"
			(at 0 0 90)
			(unlocked yes)
			(layer "F.Fab")
			(hide yes)
			(effects
				(font
					(size 1 1)
					(thickness 0.15)
				)
			)
		)
		(component_classes
			(class "DCDC_SOM")
		)
		(sheetname "/DCDC/")
		(sheetfile "dcdc.kicad_sch")
		(attr smd)
		(fp_rect
			(start -0.925 -0.47)
			(end 0.925 0.47)
			(stroke
				(width 0.05)
				(type default)
			)
			(fill no)
			(layer "F.CrtYd")
		)
		(fp_rect
			(start -0.5 -0.25)
			(end 0.5 0.25)
			(stroke
				(width 0.15)
				(type solid)
			)
			(fill no)
			(layer "F.Fab")
		)
		(fp_text user "License: Apache-2.0"
			(at -0.95 5.169 90)
			(layer "F.Fab")
			(effects
				(font
					(size 0.7 0.7)
					(thickness 0.15)
				)
				(justify left bottom)
			)
		)
		(fp_text user "${REFERENCE}"
			(at -0.95 3.168 90)
			(layer "F.Fab")
			(effects
				(font
					(size 0.7 0.7)
					(thickness 0.15)
				)
				(justify left bottom)
			)
		)
		(fp_text user "Author: Antmicro"
			(at -0.95 4.169 90)
			(layer "F.Fab")
			(effects
				(font
					(size 0.7 0.7)
					(thickness 0.15)
				)
				(justify left bottom)
			)
		)
		(pad "1" smd roundrect
			(at -0.48 0 90)
			(size 0.59 0.64)
			(layers "F.Cu" "F.Mask" "F.Paste")
			(roundrect_rratio 0.25)
			(net 1187 "Net-(U22-IN-)")
			(pintype "passive")
		)
		(pad "2" smd roundrect
			(at 0.48 0 90)
			(size 0.59 0.64)
			(layers "F.Cu" "F.Mask" "F.Paste")
			(roundrect_rratio 0.25)
			(net 12 "SYS_VIN_HV")
			(pintype "passive")
		)
	)
	(footprint "antmicro-footprints:R_0402_1005Metric"
		(layer "F.Cu")
		(at 183.2 107.98 180)
		(descr "Resistor SMD 0402")
		(tags "resistor SMD 0402")
		(property "Reference" "R52"
			(at -3.1 0.28 0)
			(layer "F.SilkS")
			(effects
				(font
					(size 0.7 0.7)
					(thickness 0.15)
				)
				(justify right top)
			)
		)
		(property "Value" "R_73k2_0402"
			(at -1.011843 1.772047 0)
			(layer "F.Fab")
			(effects
				(font
					(size 0.7 0.7)
					(thickness 0.15)
				)
				(justify right top)
			)
		)
		(property "Datasheet" "https://www.bourns.com/docs/product-datasheets/cr.pdf"
			(at 0 0 0)
			(layer "F.Fab")
			(hide yes)
			(effects
				(font
					(size 1.27 1.27)
					(thickness 0.15)
				)
			)
		)
		(property "Description" "SMD Chip Resistor"
			(at 0 0 0)
			(layer "F.Fab")
			(hide yes)
			(effects
				(font
					(size 1.27 1.27)
					(thickness 0.15)
				)
			)
		)
		(property "MPN" "CR0402-FX-7322GLF"
			(at 0 0 180)
			(unlocked yes)
			(layer "F.Fab")
			(hide yes)
			(effects
				(font
					(size 1 1)
					(thickness 0.15)
				)
			)
		)
		(property "Manufacturer" "Bourns"
			(at 0 0 180)
			(unlocked yes)
			(layer "F.Fab")
			(hide yes)
			(effects
				(font
					(size 1 1)
					(thickness 0.15)
				)
			)
		)
		(property "License" "Apache-2.0"
			(at 0 0 180)
			(unlocked yes)
			(layer "F.Fab")
			(hide yes)
			(effects
				(font
					(size 1 1)
					(thickness 0.15)
				)
			)
		)
		(property "Author" "Antmicro"
			(at 0 0 180)
			(unlocked yes)
			(layer "F.Fab")
			(hide yes)
			(effects
				(font
					(size 1 1)
					(thickness 0.15)
				)
			)
		)
		(property "Val" "73k2"
			(at 0 0 180)
			(unlocked yes)
			(layer "F.Fab")
			(hide yes)
			(effects
				(font
					(size 1 1)
					(thickness 0.15)
				)
			)
		)
		(property "Tolerance" "1%"
			(at 0 0 180)
			(unlocked yes)
			(layer "F.Fab")
			(hide yes)
			(effects
				(font
					(size 1 1)
					(thickness 0.15)
				)
			)
		)
		(sheetname "/DCDC/")
		(sheetfile "dcdc.kicad_sch")
		(attr smd)
		(fp_rect
			(start -0.925 -0.47)
			(end 0.925 0.47)
			(stroke
				(width 0.05)
				(type default)
			)
			(fill no)
			(layer "F.CrtYd")
		)
		(fp_rect
			(start -0.5 -0.25)
			(end 0.5 0.25)
			(stroke
				(width 0.15)
				(type solid)
			)
			(fill no)
			(layer "F.Fab")
		)
		(fp_text user "License: Apache-2.0"
			(at -0.95 5.169 0)
			(layer "F.Fab")
			(effects
				(font
					(size 0.7 0.7)
					(thickness 0.15)
				)
				(justify right top)
			)
		)
		(fp_text user "Author: Antmicro"
			(at -0.95 4.169 0)
			(layer "F.Fab")
			(effects
				(font
					(size 0.7 0.7)
					(thickness 0.15)
				)
				(justify right top)
			)
		)
		(fp_text user "${REFERENCE}"
			(at -0.95 3.168 0)
			(layer "F.Fab")
			(effects
				(font
					(size 0.7 0.7)
					(thickness 0.15)
				)
				(justify right top)
			)
		)
		(pad "1" smd roundrect
			(at -0.48 0 180)
			(size 0.59 0.64)
			(layers "F.Cu" "F.Mask" "F.Paste")
			(roundrect_rratio 0.25)
			(net 1217 "/DCDC/5V_FB")
			(pintype "passive")
		)
		(pad "2" smd roundrect
			(at 0.48 0 180)
			(size 0.59 0.64)
			(layers "F.Cu" "F.Mask" "F.Paste")
			(roundrect_rratio 0.25)
			(net 253 "/DCDC/5V_OUT")
			(pintype "passive")
		)
	)
	(footprint "antmicro-footprints:C_0402_1005Metric"
		(layer "F.Cu")
		(at 212.4 135.2 -90)
		(descr "Capacitor SMD 0402")
		(tags "capacitor SMD 0402")
		(property "Reference" "C93"
			(at -1 -1.8 90)
			(layer "F.SilkS")
			(effects
				(font
					(size 0.7 0.7)
					(thickness 0.15)
				)
				(justify right top)
			)
		)
		(property "Value" "C_100n_0402"
			(at -1.022927 2.155213 90)
			(layer "F.Fab")
			(effects
				(font
					(size 0.7 0.7)
					(thickness 0.15)
				)
				(justify right top)
			)
		)
		(property "Datasheet" "https://www.murata.com/products/productdetail?partno=GRM155R61H104KE14%23"
			(at 0 0 90)
			(layer "F.Fab")
			(hide yes)
			(effects
				(font
					(size 1.27 1.27)
					(thickness 0.15)
				)
			)
		)
		(property "Description" "SMD Multilayer Ceramic Capacitor, 0.1 µF, 50 V, 0402 [1005 Metric], ± 10%, X5R, GRM Series"
			(at 0 0 90)
			(layer "F.Fab")
			(hide yes)
			(effects
				(font
					(size 1.27 1.27)
					(thickness 0.15)
				)
			)
		)
		(property "MPN" "GRM155R61H104KE14D"
			(at 0 0 270)
			(unlocked yes)
			(layer "F.Fab")
			(hide yes)
			(effects
				(font
					(size 1 1)
					(thickness 0.15)
				)
			)
		)
		(property "Val" "100n"
			(at 0 0 270)
			(unlocked yes)
			(layer "F.Fab")
			(hide yes)
			(effects
				(font
					(size 1 1)
					(thickness 0.15)
				)
			)
		)
		(property "Voltage" "50V"
			(at 0 0 270)
			(unlocked yes)
			(layer "F.Fab")
			(hide yes)
			(effects
				(font
					(size 1 1)
					(thickness 0.15)
				)
			)
		)
		(property "Dielectric" "X5R"
			(at 0 0 270)
			(unlocked yes)
			(layer "F.Fab")
			(hide yes)
			(effects
				(font
					(size 1 1)
					(thickness 0.15)
				)
			)
		)
		(property "Manufacturer" "Murata"
			(at 0 0 270)
			(unlocked yes)
			(layer "F.Fab")
			(hide yes)
			(effects
				(font
					(size 1 1)
					(thickness 0.15)
				)
			)
		)
		(property "License" "Apache-2.0"
			(at 0 0 270)
			(unlocked yes)
			(layer "F.Fab")
			(hide yes)
			(effects
				(font
					(size 1 1)
					(thickness 0.15)
				)
			)
		)
		(property "Author" "Antmicro"
			(at 0 0 270)
			(unlocked yes)
			(layer "F.Fab")
			(hide yes)
			(effects
				(font
					(size 1 1)
					(thickness 0.15)
				)
			)
		)
		(sheetname "/USB Hub/")
		(sheetfile "usb_hub.kicad_sch")
		(attr smd)
		(fp_rect
			(start -0.925 -0.47)
			(end 0.925 0.47)
			(stroke
				(width 0.05)
				(type default)
			)
			(fill no)
			(layer "F.CrtYd")
		)
		(fp_line
			(start -0.494 0.248)
			(end -0.494 -0.25)
			(stroke
				(width 0.15)
				(type solid)
			)
			(layer "F.Fab")
		)
		(fp_line
			(start 0.504 0.248)
			(end -0.494 0.248)
			(stroke
				(width 0.15)
				(type solid)
			)
			(layer "F.Fab")
		)
		(fp_line
			(start -0.494 -0.25)
			(end 0.504 -0.25)
			(stroke
				(width 0.15)
				(type solid)
			)
			(layer "F.Fab")
		)
		(fp_line
			(start 0.504 -0.25)
			(end 0.504 0.248)
			(stroke
				(width 0.15)
				(type solid)
			)
			(layer "F.Fab")
		)
		(fp_text user "${REFERENCE}"
			(at -0.939 4.599 90)
			(layer "F.Fab")
			(effects
				(font
					(size 0.7 0.7)
					(thickness 0.15)
				)
				(justify right top)
			)
		)
		(fp_text user "License: Apache-2.0"
			(at -0.939 5.799 90)
			(layer "F.Fab")
			(effects
				(font
					(size 0.7 0.7)
					(thickness 0.15)
				)
				(justify right top)
			)
		)
		(fp_text user "Author: Antmicro"
			(at -0.939 3.399 90)
			(layer "F.Fab")
			(effects
				(font
					(size 0.7 0.7)
					(thickness 0.15)
				)
				(justify right top)
			)
		)
		(pad "1" smd roundrect
			(at -0.48 0 270)
			(size 0.59 0.64)
			(layers "F.Cu" "F.Mask" "F.Paste")
			(roundrect_rratio 0.25)
			(net 1 "GND")
			(pintype "passive")
		)
		(pad "2" smd roundrect
			(at 0.48 0 270)
			(size 0.59 0.64)
			(layers "F.Cu" "F.Mask" "F.Paste")
			(roundrect_rratio 0.25)
			(net 2 "+3V3")
			(pintype "passive")
		)
	)
	(footprint "antmicro-footprints:C_0805_2012Metric"
		(layer "F.Cu")
		(at 165.91 99.81 90)
		(descr "Capacitor SMD 0805")
		(tags "capacitor SMD 0805")
		(property "Reference" "C299"
			(at -4.595 0.345 90)
			(layer "F.SilkS")
			(effects
				(font
					(size 0.7 0.7)
					(thickness 0.15)
				)
				(justify left bottom)
			)
		)
		(property "Value" "C_22u_25V_0805"
			(at -2.055717 1.963152 90)
			(layer "F.Fab")
			(effects
				(font
					(size 0.7 0.7)
					(thickness 0.15)
				)
				(justify left bottom)
			)
		)
		(property "Datasheet" "https://product.samsungsem.com/mlcc/CL21A226MAYNNN.do"
			(at 0 0 90)
			(layer "F.Fab")
			(hide yes)
			(effects
				(font
					(size 1.27 1.27)
					(thickness 0.15)
				)
			)
		)
		(property "Description" "SMT Multilayer Ceramic Capacitor, 22uF, +/-20%, 25V, X5R, 0805 [2012 Metric]"
			(at 0 0 90)
			(layer "F.Fab")
			(hide yes)
			(effects
				(font
					(size 1.27 1.27)
					(thickness 0.15)
				)
			)
		)
		(property "MPN" "CL21A226MAYNNNE"
			(at 0 0 90)
			(unlocked yes)
			(layer "F.Fab")
			(hide yes)
			(effects
				(font
					(size 1 1)
					(thickness 0.15)
				)
			)
		)
		(property "Manufacturer" "Samsung Electro-Mechanics"
			(at 0 0 90)
			(unlocked yes)
			(layer "F.Fab")
			(hide yes)
			(effects
				(font
					(size 1 1)
					(thickness 0.15)
				)
			)
		)
		(property "License" "Apache-2.0"
			(at 0 0 90)
			(unlocked yes)
			(layer "F.Fab")
			(hide yes)
			(effects
				(font
					(size 1 1)
					(thickness 0.15)
				)
			)
		)
		(property "Author" "Antmicro"
			(at 0 0 90)
			(unlocked yes)
			(layer "F.Fab")
			(hide yes)
			(effects
				(font
					(size 1 1)
					(thickness 0.15)
				)
			)
		)
		(property "Val" "22u"
			(at 0 0 90)
			(unlocked yes)
			(layer "F.Fab")
			(hide yes)
			(effects
				(font
					(size 1 1)
					(thickness 0.15)
				)
			)
		)
		(property "Voltage" "25V"
			(at 0 0 90)
			(unlocked yes)
			(layer "F.Fab")
			(hide yes)
			(effects
				(font
					(size 1 1)
					(thickness 0.15)
				)
			)
		)
		(property "Dielectric" "X5R"
			(at 0 0 90)
			(unlocked yes)
			(layer "F.Fab")
			(hide yes)
			(effects
				(font
					(size 1 1)
					(thickness 0.15)
				)
			)
		)
		(property "Public" "False"
			(at 0 0 90)
			(unlocked yes)
			(layer "F.Fab")
			(hide yes)
			(effects
				(font
					(size 1 1)
					(thickness 0.15)
				)
			)
		)
		(component_classes
			(class "DCDC_SOM")
		)
		(sheetname "/DCDC/")
		(sheetfile "dcdc.kicad_sch")
		(attr smd)
		(fp_line
			(start -0.3 -0.7)
			(end 0.3 -0.7)
			(stroke
				(width 0.15)
				(type solid)
			)
			(layer "F.SilkS")
		)
		(fp_line
			(start -0.3 0.7)
			(end 0.3 0.7)
			(stroke
				(width 0.15)
				(type solid)
			)
			(layer "F.SilkS")
		)
		(fp_rect
			(start 1.95 -0.9)
			(end -1.95 0.9)
			(stroke
				(width 0.05)
				(type default)
			)
			(fill no)
			(layer "F.CrtYd")
		)
		(fp_rect
			(start -0.95 -0.675)
			(end 0.95 0.675)
			(stroke
				(width 0.15)
				(type solid)
			)
			(fill no)
			(layer "F.Fab")
		)
		(fp_text user "${REFERENCE}"
			(at -1.9 3.947 90)
			(layer "F.Fab")
			(effects
				(font
					(size 0.7 0.7)
					(thickness 0.15)
				)
				(justify left bottom)
			)
		)
		(fp_text user "License: Apache-2.0"
			(at -1.9 4.947 90)
			(layer "F.Fab")
			(effects
				(font
					(size 0.7 0.7)
					(thickness 0.15)
				)
				(justify left bottom)
			)
		)
		(fp_text user "Author: Antmicro"
			(at -1.9 5.947 90)
			(layer "F.Fab")
			(effects
				(font
					(size 0.7 0.7)
					(thickness 0.15)
				)
				(justify left bottom)
			)
		)
		(pad "1" smd roundrect
			(at -1.1 0 90)
			(size 1.2 1.3)
			(layers "F.Cu" "F.Mask" "F.Paste")
			(roundrect_rratio 0.25)
			(net 1 "GND")
			(pintype "passive")
		)
		(pad "2" smd roundrect
			(at 1.1 0 90)
			(size 1.2 1.3)
			(layers "F.Cu" "F.Mask" "F.Paste")
			(roundrect_rratio 0.25)
			(net 903 "/DCDC/16V_OUT")
			(pintype "passive")
		)
	)
	(footprint "antmicro-footprints:R_0402_1005Metric"
		(layer "F.Cu")
		(at 182.933525 124.897019 180)
		(descr "Resistor SMD 0402")
		(tags "resistor SMD 0402")
		(property "Reference" "R54"
			(at -1.866475 2.197019 0)
			(layer "F.SilkS")
			(effects
				(font
					(size 0.7 0.7)
					(thickness 0.15)
				)
				(justify right top)
			)
		)
		(property "Value" "R_45k3_0402"
			(at -1.011843 1.772047 0)
			(layer "F.Fab")
			(effects
				(font
					(size 0.7 0.7)
					(thickness 0.15)
				)
				(justify right top)
			)
		)
		(property "Datasheet" "https://www.bourns.com/docs/product-datasheets/cr.pdf"
			(at 0 0 0)
			(layer "F.Fab")
			(hide yes)
			(effects
				(font
					(size 1.27 1.27)
					(thickness 0.15)
				)
			)
		)
		(property "Description" "SMD Chip Resistor"
			(at 0 0 0)
			(layer "F.Fab")
			(hide yes)
			(effects
				(font
					(size 1.27 1.27)
					(thickness 0.15)
				)
			)
		)
		(property "MPN" "CR0402-FX-4532GLF"
			(at 0 0 180)
			(unlocked yes)
			(layer "F.Fab")
			(hide yes)
			(effects
				(font
					(size 1 1)
					(thickness 0.15)
				)
			)
		)
		(property "Manufacturer" "Bourns"
			(at 0 0 180)
			(unlocked yes)
			(layer "F.Fab")
			(hide yes)
			(effects
				(font
					(size 1 1)
					(thickness 0.15)
				)
			)
		)
		(property "License" "Apache-2.0"
			(at 0 0 180)
			(unlocked yes)
			(layer "F.Fab")
			(hide yes)
			(effects
				(font
					(size 1 1)
					(thickness 0.15)
				)
			)
		)
		(property "Author" "Antmicro"
			(at 0 0 180)
			(unlocked yes)
			(layer "F.Fab")
			(hide yes)
			(effects
				(font
					(size 1 1)
					(thickness 0.15)
				)
			)
		)
		(property "Val" "45k3"
			(at 0 0 180)
			(unlocked yes)
			(layer "F.Fab")
			(hide yes)
			(effects
				(font
					(size 1 1)
					(thickness 0.15)
				)
			)
		)
		(property "Tolerance" "1%"
			(at 0 0 180)
			(unlocked yes)
			(layer "F.Fab")
			(hide yes)
			(effects
				(font
					(size 1 1)
					(thickness 0.15)
				)
			)
		)
		(sheetname "/DCDC/")
		(sheetfile "dcdc.kicad_sch")
		(attr smd)
		(fp_rect
			(start -0.925 -0.47)
			(end 0.925 0.47)
			(stroke
				(width 0.05)
				(type default)
			)
			(fill no)
			(layer "F.CrtYd")
		)
		(fp_rect
			(start -0.5 -0.25)
			(end 0.5 0.25)
			(stroke
				(width 0.15)
				(type solid)
			)
			(fill no)
			(layer "F.Fab")
		)
		(fp_text user "Author: Antmicro"
			(at -0.95 4.169 0)
			(layer "F.Fab")
			(effects
				(font
					(size 0.7 0.7)
					(thickness 0.15)
				)
				(justify right top)
			)
		)
		(fp_text user "License: Apache-2.0"
			(at -0.95 5.169 0)
			(layer "F.Fab")
			(effects
				(font
					(size 0.7 0.7)
					(thickness 0.15)
				)
				(justify right top)
			)
		)
		(fp_text user "${REFERENCE}"
			(at -0.95 3.168 0)
			(layer "F.Fab")
			(effects
				(font
					(size 0.7 0.7)
					(thickness 0.15)
				)
				(justify right top)
			)
		)
		(pad "1" smd roundrect
			(at -0.48 0 180)
			(size 0.59 0.64)
			(layers "F.Cu" "F.Mask" "F.Paste")
			(roundrect_rratio 0.25)
			(net 1218 "/DCDC/3V3_FB")
			(pintype "passive")
		)
		(pad "2" smd roundrect
			(at 0.48 0 180)
			(size 0.59 0.64)
			(layers "F.Cu" "F.Mask" "F.Paste")
			(roundrect_rratio 0.25)
			(net 567 "/DCDC/3V3_OUT")
			(pintype "passive")
		)
	)
	(footprint "antmicro-footprints:C_0402_1005Metric"
		(layer "F.Cu")
		(at 153.499999 96 180)
		(descr "Capacitor SMD 0402")
		(tags "capacitor SMD 0402")
		(property "Reference" "C355"
			(at -1.700001 1.4 0)
			(layer "F.SilkS")
			(effects
				(font
					(size 0.7 0.7)
					(thickness 0.15)
				)
				(justify right top)
			)
		)
		(property "Value" "C_100n_0402"
			(at -1.022927 2.155213 0)
			(layer "F.Fab")
			(effects
				(font
					(size 0.7 0.7)
					(thickness 0.15)
				)
				(justify right top)
			)
		)
		(property "Datasheet" "https://www.murata.com/products/productdetail?partno=GRM155R61H104KE14%23"
			(at 0 0 0)
			(layer "F.Fab")
			(hide yes)
			(effects
				(font
					(size 1.27 1.27)
					(thickness 0.15)
				)
			)
		)
		(property "Description" "SMD Multilayer Ceramic Capacitor, 0.1 µF, 50 V, 0402 [1005 Metric], ± 10%, X5R, GRM Series"
			(at 0 0 0)
			(layer "F.Fab")
			(hide yes)
			(effects
				(font
					(size 1.27 1.27)
					(thickness 0.15)
				)
			)
		)
		(property "Manufacturer" "Murata"
			(at 0 0 180)
			(unlocked yes)
			(layer "F.Fab")
			(hide yes)
			(effects
				(font
					(size 1 1)
					(thickness 0.15)
				)
			)
		)
		(property "MPN" "GRM155R61H104KE14D"
			(at 0 0 180)
			(unlocked yes)
			(layer "F.Fab")
			(hide yes)
			(effects
				(font
					(size 1 1)
					(thickness 0.15)
				)
			)
		)
		(property "Val" "100n"
			(at 0 0 180)
			(unlocked yes)
			(layer "F.Fab")
			(hide yes)
			(effects
				(font
					(size 1 1)
					(thickness 0.15)
				)
			)
		)
		(property "License" "Apache-2.0"
			(at 0 0 180)
			(unlocked yes)
			(layer "F.Fab")
			(hide yes)
			(effects
				(font
					(size 1 1)
					(thickness 0.15)
				)
			)
		)
		(property "Author" "Antmicro"
			(at 0 0 180)
			(unlocked yes)
			(layer "F.Fab")
			(hide yes)
			(effects
				(font
					(size 1 1)
					(thickness 0.15)
				)
			)
		)
		(property "Voltage" "50V"
			(at 0 0 180)
			(unlocked yes)
			(layer "F.Fab")
			(hide yes)
			(effects
				(font
					(size 1 1)
					(thickness 0.15)
				)
			)
		)
		(property "Dielectric" "X5R"
			(at 0 0 180)
			(unlocked yes)
			(layer "F.Fab")
			(hide yes)
			(effects
				(font
					(size 1 1)
					(thickness 0.15)
				)
			)
		)
		(sheetname "/SoM_IO/")
		(sheetfile "som_io.kicad_sch")
		(attr smd)
		(fp_poly
			(pts
				(xy -0.925 -0.47) (xy 0.925 -0.47) (xy 0.925 0.47) (xy -0.925 0.47)
			)
			(stroke
				(width 0.05)
				(type default)
			)
			(fill no)
			(layer "F.CrtYd")
		)
		(fp_line
			(start 0.504 0.248)
			(end -0.494 0.248)
			(stroke
				(width 0.15)
				(type solid)
			)
			(layer "F.Fab")
		)
		(fp_line
			(start 0.504 -0.25)
			(end 0.504 0.248)
			(stroke
				(width 0.15)
				(type solid)
			)
			(layer "F.Fab")
		)
		(fp_line
			(start -0.494 0.248)
			(end -0.494 -0.25)
			(stroke
				(width 0.15)
				(type solid)
			)
			(layer "F.Fab")
		)
		(fp_line
			(start -0.494 -0.25)
			(end 0.504 -0.25)
			(stroke
				(width 0.15)
				(type solid)
			)
			(layer "F.Fab")
		)
		(fp_text user "Author: Antmicro"
			(at -0.939 3.399 0)
			(layer "F.Fab")
			(effects
				(font
					(size 0.7 0.7)
					(thickness 0.15)
				)
				(justify right top)
			)
		)
		(fp_text user "${REFERENCE}"
			(at -0.939 4.599 0)
			(layer "F.Fab")
			(effects
				(font
					(size 0.7 0.7)
					(thickness 0.15)
				)
				(justify right top)
			)
		)
		(fp_text user "License: Apache-2.0"
			(at -0.939 5.799 0)
			(layer "F.Fab")
			(effects
				(font
					(size 0.7 0.7)
					(thickness 0.15)
				)
				(justify right top)
			)
		)
		(pad "1" smd roundrect
			(at -0.48 0 180)
			(size 0.59 0.64)
			(layers "F.Cu" "F.Mask" "F.Paste")
			(roundrect_rratio 0.25)
			(net 1 "GND")
			(pintype "passive")
		)
		(pad "2" smd roundrect
			(at 0.48 0 180)
			(size 0.59 0.64)
			(layers "F.Cu" "F.Mask" "F.Paste")
			(roundrect_rratio 0.25)
			(net 2 "+3V3")
			(pintype "passive")
		)
	)
	(footprint "antmicro-footprints:C_0402_1005Metric"
		(layer "F.Cu")
		(at 211 101.38)
		(descr "Capacitor SMD 0402")
		(tags "capacitor SMD 0402")
		(property "Reference" "C252"
			(at -3.79 0.33 0)
			(layer "F.SilkS")
			(effects
				(font
					(size 0.7 0.7)
					(thickness 0.15)
				)
				(justify left bottom)
			)
		)
		(property "Value" "C_100n_0402"
			(at -1.022927 2.155213 0)
			(layer "F.Fab")
			(effects
				(font
					(size 0.7 0.7)
					(thickness 0.15)
				)
				(justify left bottom)
			)
		)
		(property "Datasheet" "https://www.murata.com/products/productdetail?partno=GRM155R61H104KE14%23"
			(at 0 0 0)
			(layer "F.Fab")
			(hide yes)
			(effects
				(font
					(size 1.27 1.27)
					(thickness 0.15)
				)
			)
		)
		(property "Description" "SMD Multilayer Ceramic Capacitor, 0.1 µF, 50 V, 0402 [1005 Metric], ± 10%, X5R, GRM Series"
			(at 0 0 0)
			(layer "F.Fab")
			(hide yes)
			(effects
				(font
					(size 1.27 1.27)
					(thickness 0.15)
				)
			)
		)
		(property "Manufacturer" "Murata"
			(at 0 0 0)
			(unlocked yes)
			(layer "F.Fab")
			(hide yes)
			(effects
				(font
					(size 1 1)
					(thickness 0.15)
				)
			)
		)
		(property "MPN" "GRM155R61H104KE14D"
			(at 0 0 0)
			(unlocked yes)
			(layer "F.Fab")
			(hide yes)
			(effects
				(font
					(size 1 1)
					(thickness 0.15)
				)
			)
		)
		(property "Val" "100n"
			(at 0 0 0)
			(unlocked yes)
			(layer "F.Fab")
			(hide yes)
			(effects
				(font
					(size 1 1)
					(thickness 0.15)
				)
			)
		)
		(property "License" "Apache-2.0"
			(at 0 0 0)
			(unlocked yes)
			(layer "F.Fab")
			(hide yes)
			(effects
				(font
					(size 1 1)
					(thickness 0.15)
				)
			)
		)
		(property "Author" "Antmicro"
			(at 0 0 0)
			(unlocked yes)
			(layer "F.Fab")
			(hide yes)
			(effects
				(font
					(size 1 1)
					(thickness 0.15)
				)
			)
		)
		(property "Voltage" "50V"
			(at 0 0 0)
			(unlocked yes)
			(layer "F.Fab")
			(hide yes)
			(effects
				(font
					(size 1 1)
					(thickness 0.15)
				)
			)
		)
		(property "Dielectric" "X5R"
			(at 0 0 0)
			(unlocked yes)
			(layer "F.Fab")
			(hide yes)
			(effects
				(font
					(size 1 1)
					(thickness 0.15)
				)
			)
		)
		(sheetname "/Recovery USB/")
		(sheetfile "recovery_usb.kicad_sch")
		(attr smd)
		(fp_rect
			(start -0.925 -0.47)
			(end 0.925 0.47)
			(stroke
				(width 0.05)
				(type default)
			)
			(fill no)
			(layer "F.CrtYd")
		)
		(fp_line
			(start -0.494 -0.25)
			(end 0.504 -0.25)
			(stroke
				(width 0.15)
				(type solid)
			)
			(layer "F.Fab")
		)
		(fp_line
			(start -0.494 0.248)
			(end -0.494 -0.25)
			(stroke
				(width 0.15)
				(type solid)
			)
			(layer "F.Fab")
		)
		(fp_line
			(start 0.504 -0.25)
			(end 0.504 0.248)
			(stroke
				(width 0.15)
				(type solid)
			)
			(layer "F.Fab")
		)
		(fp_line
			(start 0.504 0.248)
			(end -0.494 0.248)
			(stroke
				(width 0.15)
				(type solid)
			)
			(layer "F.Fab")
		)
		(fp_text user "License: Apache-2.0"
			(at -0.939 5.799 0)
			(layer "F.Fab")
			(effects
				(font
					(size 0.7 0.7)
					(thickness 0.15)
				)
				(justify left bottom)
			)
		)
		(fp_text user "${REFERENCE}"
			(at -0.939 4.599 0)
			(layer "F.Fab")
			(effects
				(font
					(size 0.7 0.7)
					(thickness 0.15)
				)
				(justify left bottom)
			)
		)
		(fp_text user "Author: Antmicro"
			(at -0.939 3.399 0)
			(layer "F.Fab")
			(effects
				(font
					(size 0.7 0.7)
					(thickness 0.15)
				)
				(justify left bottom)
			)
		)
		(pad "1" smd roundrect
			(at -0.48 0)
			(size 0.59 0.64)
			(layers "F.Cu" "F.Mask" "F.Paste")
			(roundrect_rratio 0.25)
			(net 630 "/Recovery USB/USBSS0.TX-")
			(pintype "passive")
		)
		(pad "2" smd roundrect
			(at 0.48 0)
			(size 0.59 0.64)
			(layers "F.Cu" "F.Mask" "F.Paste")
			(roundrect_rratio 0.25)
			(net 1131 "/Recovery USB/USBSS_TX_P")
			(pintype "passive")
		)
	)
	(footprint "antmicro-footprints:SOD-523"
		(layer "F.Cu")
		(at 168.2 150.4)
		(property "Reference" "D39"
			(at -1.101 1.5 0)
			(layer "F.SilkS")
			(effects
				(font
					(size 0.7 0.7)
					(thickness 0.15)
				)
				(justify left bottom)
			)
		)
		(property "Value" "PESD5Z5.0F"
			(at 0 1.499 0)
			(layer "F.Fab")
			(effects
				(font
					(size 0.7 0.7)
					(thickness 0.15)
				)
				(justify left bottom)
			)
		)
		(property "Datasheet" "https://assets.nexperia.com/documents/data-sheet/PESD5Z5_0.pdf"
			(at 0 0 0)
			(layer "F.Fab")
			(hide yes)
			(effects
				(font
					(size 1.27 1.27)
					(thickness 0.15)
				)
			)
		)
		(property "Description" "Unidirectional TVS, 30 kV,  SOD-523, 5 V, 89 pF"
			(at 0 0 0)
			(layer "F.Fab")
			(hide yes)
			(effects
				(font
					(size 1.27 1.27)
					(thickness 0.15)
				)
			)
		)
		(property "Manufacturer" "Nexperia"
			(at 0 0 0)
			(unlocked yes)
			(layer "F.Fab")
			(hide yes)
			(effects
				(font
					(size 1 1)
					(thickness 0.15)
				)
			)
		)
		(property "MPN" "PESD5Z5.0F"
			(at 0 0 0)
			(unlocked yes)
			(layer "F.Fab")
			(hide yes)
			(effects
				(font
					(size 1 1)
					(thickness 0.15)
				)
			)
		)
		(property "Author" "Antmicro"
			(at 0 0 0)
			(unlocked yes)
			(layer "F.Fab")
			(hide yes)
			(effects
				(font
					(size 1 1)
					(thickness 0.15)
				)
			)
		)
		(property "License" "Apache-2.0"
			(at 0 0 0)
			(unlocked yes)
			(layer "F.Fab")
			(hide yes)
			(effects
				(font
					(size 1 1)
					(thickness 0.15)
				)
			)
		)
		(sheetname "/Peripherals/")
		(sheetfile "peripherals.kicad_sch")
		(attr smd)
		(fp_line
			(start -0.35 -0.5)
			(end -0.35 0.5)
			(stroke
				(width 0.15)
				(type solid)
			)
			(layer "F.SilkS")
		)
		(fp_rect
			(start -1 -0.6)
			(end 1 0.6)
			(stroke
				(width 0.05)
				(type solid)
			)
			(fill no)
			(layer "F.CrtYd")
		)
		(fp_line
			(start -0.652 -0.425)
			(end 0.65 -0.425)
			(stroke
				(width 0.15)
				(type solid)
			)
			(layer "F.Fab")
		)
		(fp_line
			(start -0.652 0.423)
			(end -0.652 -0.425)
			(stroke
				(width 0.15)
				(type solid)
			)
			(layer "F.Fab")
		)
		(fp_line
			(start -0.652 0.423)
			(end 0.65 0.423)
			(stroke
				(width 0.15)
				(type solid)
			)
			(layer "F.Fab")
		)
		(fp_line
			(start -0.35 -0.4)
			(end -0.35 0.4)
			(stroke
				(width 0.15)
				(type solid)
			)
			(layer "F.Fab")
		)
		(fp_line
			(start 0.65 -0.425)
			(end 0.65 0.423)
			(stroke
				(width 0.15)
				(type solid)
			)
			(layer "F.Fab")
		)
		(fp_text user "License: Apache-2.0"
			(at -1.276 5.9 0)
			(layer "F.Fab")
			(effects
				(font
					(size 0.7 0.7)
					(thickness 0.15)
				)
				(justify left bottom)
			)
		)
		(fp_text user "Author: Antmicro"
			(at -1.276 4.7 0)
			(layer "F.Fab")
			(effects
				(font
					(size 0.7 0.7)
					(thickness 0.15)
				)
				(justify left bottom)
			)
		)
		(fp_text user "${REFERENCE}"
			(at -1.276 3.499 0)
			(layer "F.Fab")
			(effects
				(font
					(size 0.7 0.7)
					(thickness 0.15)
				)
				(justify left bottom)
			)
		)
		(pad "1" smd roundrect
			(at -0.701 0)
			(size 0.5 0.6)
			(layers "F.Cu" "F.Mask" "F.Paste")
			(roundrect_rratio 0.25)
			(net 5 "+5V")
			(pinfunction "C")
			(pintype "passive")
		)
		(pad "2" smd roundrect
			(at 0.699 0)
			(size 0.5 0.6)
			(layers "F.Cu" "F.Mask" "F.Paste")
			(roundrect_rratio 0.25)
			(net 1 "GND")
			(pinfunction "A")
			(pintype "passive")
		)
	)
	(footprint "antmicro-footprints:C_0402_1005Metric"
		(layer "F.Cu")
		(at 186.2 122.299 180)
		(descr "Capacitor SMD 0402")
		(tags "capacitor SMD 0402")
		(property "Reference" "C111"
			(at 0.1 1.599 0)
			(layer "F.SilkS")
			(effects
				(font
					(size 0.7 0.7)
					(thickness 0.15)
				)
				(justify right top)
			)
		)
		(property "Value" "C_100n_0402"
			(at -1.022927 2.155213 0)
			(layer "F.Fab")
			(effects
				(font
					(size 0.7 0.7)
					(thickness 0.15)
				)
				(justify right top)
			)
		)
		(property "Datasheet" "https://www.murata.com/products/productdetail?partno=GRM155R61H104KE14%23"
			(at 0 0 0)
			(layer "F.Fab")
			(hide yes)
			(effects
				(font
					(size 1.27 1.27)
					(thickness 0.15)
				)
			)
		)
		(property "Description" "SMD Multilayer Ceramic Capacitor, 0.1 µF, 50 V, 0402 [1005 Metric], ± 10%, X5R, GRM Series"
			(at 0 0 0)
			(layer "F.Fab")
			(hide yes)
			(effects
				(font
					(size 1.27 1.27)
					(thickness 0.15)
				)
			)
		)
		(property "Manufacturer" "Murata"
			(at 0 0 180)
			(unlocked yes)
			(layer "F.Fab")
			(hide yes)
			(effects
				(font
					(size 1 1)
					(thickness 0.15)
				)
			)
		)
		(property "MPN" "GRM155R61H104KE14D"
			(at 0 0 180)
			(unlocked yes)
			(layer "F.Fab")
			(hide yes)
			(effects
				(font
					(size 1 1)
					(thickness 0.15)
				)
			)
		)
		(property "Val" "100n"
			(at 0 0 180)
			(unlocked yes)
			(layer "F.Fab")
			(hide yes)
			(effects
				(font
					(size 1 1)
					(thickness 0.15)
				)
			)
		)
		(property "License" "Apache-2.0"
			(at 0 0 180)
			(unlocked yes)
			(layer "F.Fab")
			(hide yes)
			(effects
				(font
					(size 1 1)
					(thickness 0.15)
				)
			)
		)
		(property "Author" "Antmicro"
			(at 0 0 180)
			(unlocked yes)
			(layer "F.Fab")
			(hide yes)
			(effects
				(font
					(size 1 1)
					(thickness 0.15)
				)
			)
		)
		(property "Voltage" "50V"
			(at 0 0 180)
			(unlocked yes)
			(layer "F.Fab")
			(hide yes)
			(effects
				(font
					(size 1 1)
					(thickness 0.15)
				)
			)
		)
		(property "Dielectric" "X5R"
			(at 0 0 180)
			(unlocked yes)
			(layer "F.Fab")
			(hide yes)
			(effects
				(font
					(size 1 1)
					(thickness 0.15)
				)
			)
		)
		(sheetname "/USB Hub/")
		(sheetfile "usb_hub.kicad_sch")
		(attr smd)
		(fp_poly
			(pts
				(xy -0.925 -0.47) (xy 0.925 -0.47) (xy 0.925 0.47) (xy -0.925 0.47)
			)
			(stroke
				(width 0.05)
				(type default)
			)
			(fill no)
			(layer "F.CrtYd")
		)
		(fp_line
			(start 0.504 0.248)
			(end -0.494 0.248)
			(stroke
				(width 0.15)
				(type solid)
			)
			(layer "F.Fab")
		)
		(fp_line
			(start 0.504 -0.25)
			(end 0.504 0.248)
			(stroke
				(width 0.15)
				(type solid)
			)
			(layer "F.Fab")
		)
		(fp_line
			(start -0.494 0.248)
			(end -0.494 -0.25)
			(stroke
				(width 0.15)
				(type solid)
			)
			(layer "F.Fab")
		)
		(fp_line
			(start -0.494 -0.25)
			(end 0.504 -0.25)
			(stroke
				(width 0.15)
				(type solid)
			)
			(layer "F.Fab")
		)
		(fp_text user "License: Apache-2.0"
			(at -0.939 5.799 0)
			(layer "F.Fab")
			(effects
				(font
					(size 0.7 0.7)
					(thickness 0.15)
				)
				(justify right top)
			)
		)
		(fp_text user "${REFERENCE}"
			(at -0.939 4.599 0)
			(layer "F.Fab")
			(effects
				(font
					(size 0.7 0.7)
					(thickness 0.15)
				)
				(justify right top)
			)
		)
		(fp_text user "Author: Antmicro"
			(at -0.939 3.399 0)
			(layer "F.Fab")
			(effects
				(font
					(size 0.7 0.7)
					(thickness 0.15)
				)
				(justify right top)
			)
		)
		(pad "1" smd roundrect
			(at -0.48 0 180)
			(size 0.59 0.64)
			(layers "F.Cu" "F.Mask" "F.Paste")
			(roundrect_rratio 0.25)
			(net 1 "GND")
			(pintype "passive")
		)
		(pad "2" smd roundrect
			(at 0.48 0 180)
			(size 0.59 0.64)
			(layers "F.Cu" "F.Mask" "F.Paste")
			(roundrect_rratio 0.25)
			(net 271 "FLASH_PWR")
			(pintype "passive")
		)
	)
	(footprint "antmicro-footprints:R_0402_1005Metric"
		(layer "F.Cu")
		(at 147 113)
		(descr "Resistor SMD 0402")
		(tags "resistor SMD 0402")
		(property "Reference" "R354"
			(at -3.6 0.4 0)
			(layer "F.SilkS")
			(effects
				(font
					(size 0.7 0.7)
					(thickness 0.15)
				)
				(justify left bottom)
			)
		)
		(property "Value" "R_2k2_0402"
			(at -1.011843 1.772047 0)
			(layer "F.Fab")
			(effects
				(font
					(size 0.7 0.7)
					(thickness 0.15)
				)
				(justify left bottom)
			)
		)
		(property "Datasheet" "https://www.bourns.com/docs/product-datasheets/cr.pdf"
			(at 0 0 0)
			(layer "F.Fab")
			(hide yes)
			(effects
				(font
					(size 1.27 1.27)
					(thickness 0.15)
				)
			)
		)
		(property "Description" "SMD Chip Resistor, 2.2 kohm, ± 1%, 62.5 mW, 0402 [1005 Metric], Thick Film, General Purpose"
			(at 0 0 0)
			(layer "F.Fab")
			(hide yes)
			(effects
				(font
					(size 1.27 1.27)
					(thickness 0.15)
				)
			)
		)
		(property "MPN" "CR0402-FX-2201GLF"
			(at 0 0 0)
			(unlocked yes)
			(layer "F.Fab")
			(hide yes)
			(effects
				(font
					(size 1 1)
					(thickness 0.15)
				)
			)
		)
		(property "Manufacturer" "Bourns"
			(at 0 0 0)
			(unlocked yes)
			(layer "F.Fab")
			(hide yes)
			(effects
				(font
					(size 1 1)
					(thickness 0.15)
				)
			)
		)
		(property "License" "Apache-2.0"
			(at 0 0 0)
			(unlocked yes)
			(layer "F.Fab")
			(hide yes)
			(effects
				(font
					(size 1 1)
					(thickness 0.15)
				)
			)
		)
		(property "Author" "Antmicro"
			(at 0 0 0)
			(unlocked yes)
			(layer "F.Fab")
			(hide yes)
			(effects
				(font
					(size 1 1)
					(thickness 0.15)
				)
			)
		)
		(property "Val" "2k2"
			(at 0 0 0)
			(unlocked yes)
			(layer "F.Fab")
			(hide yes)
			(effects
				(font
					(size 1 1)
					(thickness 0.15)
				)
			)
		)
		(property "Tolerance" "1%"
			(at 0 0 0)
			(unlocked yes)
			(layer "F.Fab")
			(hide yes)
			(effects
				(font
					(size 1 1)
					(thickness 0.15)
				)
			)
		)
		(sheetname "/SoM_IO/")
		(sheetfile "som_io.kicad_sch")
		(attr smd exclude_from_pos_files exclude_from_bom dnp)
		(fp_rect
			(start -0.925 -0.47)
			(end 0.925 0.47)
			(stroke
				(width 0.05)
				(type default)
			)
			(fill no)
			(layer "F.CrtYd")
		)
		(fp_rect
			(start -0.5 -0.25)
			(end 0.5 0.25)
			(stroke
				(width 0.15)
				(type solid)
			)
			(fill no)
			(layer "F.Fab")
		)
		(fp_text user "License: Apache-2.0"
			(at -0.95 5.169 0)
			(layer "F.Fab")
			(effects
				(font
					(size 0.7 0.7)
					(thickness 0.15)
				)
				(justify left bottom)
			)
		)
		(fp_text user "${REFERENCE}"
			(at -0.95 3.168 0)
			(layer "F.Fab")
			(effects
				(font
					(size 0.7 0.7)
					(thickness 0.15)
				)
				(justify left bottom)
			)
		)
		(fp_text user "Author: Antmicro"
			(at -0.95 4.169 0)
			(layer "F.Fab")
			(effects
				(font
					(size 0.7 0.7)
					(thickness 0.15)
				)
				(justify left bottom)
			)
		)
		(pad "1" smd roundrect
			(at -0.48 0)
			(size 0.59 0.64)
			(layers "F.Cu" "F.Mask" "F.Paste")
			(roundrect_rratio 0.25)
			(net 11 "+1V8")
			(pintype "passive")
		)
		(pad "2" smd roundrect
			(at 0.48 0)
			(size 0.59 0.64)
			(layers "F.Cu" "F.Mask" "F.Paste")
			(roundrect_rratio 0.25)
			(net 112 "/SoM_IO/I2C5_SDA_1V8")
			(pintype "passive")
		)
	)
	(footprint "antmicro-footprints:R_0402_1005Metric"
		(layer "F.Cu")
		(at 147.8 120.2)
		(descr "Resistor SMD 0402")
		(tags "resistor SMD 0402")
		(property "Reference" "R374"
			(at -3.7 0.5 0)
			(layer "F.SilkS")
			(effects
				(font
					(size 0.7 0.7)
					(thickness 0.15)
				)
				(justify left bottom)
			)
		)
		(property "Value" "R_2k2_0402"
			(at -1.011843 1.772047 0)
			(layer "F.Fab")
			(effects
				(font
					(size 0.7 0.7)
					(thickness 0.15)
				)
				(justify left bottom)
			)
		)
		(property "Datasheet" "https://www.bourns.com/docs/product-datasheets/cr.pdf"
			(at 0 0 0)
			(layer "F.Fab")
			(hide yes)
			(effects
				(font
					(size 1.27 1.27)
					(thickness 0.15)
				)
			)
		)
		(property "Description" "SMD Chip Resistor, 2.2 kohm, ± 1%, 62.5 mW, 0402 [1005 Metric], Thick Film, General Purpose"
			(at 0 0 0)
			(layer "F.Fab")
			(hide yes)
			(effects
				(font
					(size 1.27 1.27)
					(thickness 0.15)
				)
			)
		)
		(property "MPN" "CR0402-FX-2201GLF"
			(at 0 0 0)
			(unlocked yes)
			(layer "F.Fab")
			(hide yes)
			(effects
				(font
					(size 1 1)
					(thickness 0.15)
				)
			)
		)
		(property "Manufacturer" "Bourns"
			(at 0 0 0)
			(unlocked yes)
			(layer "F.Fab")
			(hide yes)
			(effects
				(font
					(size 1 1)
					(thickness 0.15)
				)
			)
		)
		(property "License" "Apache-2.0"
			(at 0 0 0)
			(unlocked yes)
			(layer "F.Fab")
			(hide yes)
			(effects
				(font
					(size 1 1)
					(thickness 0.15)
				)
			)
		)
		(property "Author" "Antmicro"
			(at 0 0 0)
			(unlocked yes)
			(layer "F.Fab")
			(hide yes)
			(effects
				(font
					(size 1 1)
					(thickness 0.15)
				)
			)
		)
		(property "Val" "2k2"
			(at 0 0 0)
			(unlocked yes)
			(layer "F.Fab")
			(hide yes)
			(effects
				(font
					(size 1 1)
					(thickness 0.15)
				)
			)
		)
		(property "Tolerance" "1%"
			(at 0 0 0)
			(unlocked yes)
			(layer "F.Fab")
			(hide yes)
			(effects
				(font
					(size 1 1)
					(thickness 0.15)
				)
			)
		)
		(sheetname "/SoM_IO/")
		(sheetfile "som_io.kicad_sch")
		(attr smd)
		(fp_rect
			(start -0.925 -0.47)
			(end 0.925 0.47)
			(stroke
				(width 0.05)
				(type default)
			)
			(fill no)
			(layer "F.CrtYd")
		)
		(fp_rect
			(start -0.5 -0.25)
			(end 0.5 0.25)
			(stroke
				(width 0.15)
				(type solid)
			)
			(fill no)
			(layer "F.Fab")
		)
		(fp_text user "License: Apache-2.0"
			(at -0.95 5.169 0)
			(layer "F.Fab")
			(effects
				(font
					(size 0.7 0.7)
					(thickness 0.15)
				)
				(justify left bottom)
			)
		)
		(fp_text user "Author: Antmicro"
			(at -0.95 4.169 0)
			(layer "F.Fab")
			(effects
				(font
					(size 0.7 0.7)
					(thickness 0.15)
				)
				(justify left bottom)
			)
		)
		(fp_text user "${REFERENCE}"
			(at -0.95 3.168 0)
			(layer "F.Fab")
			(effects
				(font
					(size 0.7 0.7)
					(thickness 0.15)
				)
				(justify left bottom)
			)
		)
		(pad "1" smd roundrect
			(at -0.48 0)
			(size 0.59 0.64)
			(layers "F.Cu" "F.Mask" "F.Paste")
			(roundrect_rratio 0.25)
			(net 2 "+3V3")
			(pintype "passive")
		)
		(pad "2" smd roundrect
			(at 0.48 0)
			(size 0.59 0.64)
			(layers "F.Cu" "F.Mask" "F.Paste")
			(roundrect_rratio 0.25)
			(net 407 "/Expansion connector/I2C0.SCL")
			(pintype "passive")
		)
	)
	(footprint "antmicro-footprints:C_0805_2012Metric"
		(layer "F.Cu")
		(at 130.129998 55.68 180)
		(descr "Capacitor SMD 0805")
		(tags "capacitor SMD 0805")
		(property "Reference" "C371"
			(at 9.919998 -9.73 0)
			(layer "F.SilkS")
			(effects
				(font
					(size 0.7 0.7)
					(thickness 0.15)
				)
				(justify left bottom)
			)
		)
		(property "Value" "C_22u_25V_0805"
			(at -2.055717 1.963153 0)
			(layer "F.Fab")
			(effects
				(font
					(size 0.7 0.7)
					(thickness 0.15)
				)
				(justify right top)
			)
		)
		(property "Datasheet" "https://product.samsungsem.com/mlcc/CL21A226MAYNNN.do"
			(at 0 0 0)
			(layer "F.Fab")
			(hide yes)
			(effects
				(font
					(size 1.27 1.27)
					(thickness 0.15)
				)
			)
		)
		(property "Description" "SMT Multilayer Ceramic Capacitor, 22uF, +/-20%, 25V, X5R, 0805 [2012 Metric]"
			(at 0 0 0)
			(layer "F.Fab")
			(hide yes)
			(effects
				(font
					(size 1.27 1.27)
					(thickness 0.15)
				)
			)
		)
		(property "MPN" "CL21A226MAYNNNE"
			(at 0 0 180)
			(unlocked yes)
			(layer "F.Fab")
			(hide yes)
			(effects
				(font
					(size 1 1)
					(thickness 0.15)
				)
			)
		)
		(property "Manufacturer" "Samsung Electro-Mechanics"
			(at 0 0 180)
			(unlocked yes)
			(layer "F.Fab")
			(hide yes)
			(effects
				(font
					(size 1 1)
					(thickness 0.15)
				)
			)
		)
		(property "License" "Apache-2.0"
			(at 0 0 180)
			(unlocked yes)
			(layer "F.Fab")
			(hide yes)
			(effects
				(font
					(size 1 1)
					(thickness 0.15)
				)
			)
		)
		(property "Author" "Antmicro"
			(at 0 0 180)
			(unlocked yes)
			(layer "F.Fab")
			(hide yes)
			(effects
				(font
					(size 1 1)
					(thickness 0.15)
				)
			)
		)
		(property "Val" "22u"
			(at 0 0 180)
			(unlocked yes)
			(layer "F.Fab")
			(hide yes)
			(effects
				(font
					(size 1 1)
					(thickness 0.15)
				)
			)
		)
		(property "Voltage" "25V"
			(at 0 0 180)
			(unlocked yes)
			(layer "F.Fab")
			(hide yes)
			(effects
				(font
					(size 1 1)
					(thickness 0.15)
				)
			)
		)
		(property "Dielectric" "X5R"
			(at 0 0 180)
			(unlocked yes)
			(layer "F.Fab")
			(hide yes)
			(effects
				(font
					(size 1 1)
					(thickness 0.15)
				)
			)
		)
		(property "Public" "False"
			(at 0 0 180)
			(unlocked yes)
			(layer "F.Fab")
			(hide yes)
			(effects
				(font
					(size 1 1)
					(thickness 0.15)
				)
			)
		)
		(sheetname "/DCDC/")
		(sheetfile "dcdc.kicad_sch")
		(attr smd)
		(fp_line
			(start -0.3 0.7)
			(end 0.3 0.7)
			(stroke
				(width 0.15)
				(type solid)
			)
			(layer "F.SilkS")
		)
		(fp_line
			(start -0.3 -0.7)
			(end 0.3 -0.7)
			(stroke
				(width 0.15)
				(type solid)
			)
			(layer "F.SilkS")
		)
		(fp_poly
			(pts
				(xy 1.95 -0.9) (xy 1.95 0.9) (xy -1.95 0.9) (xy -1.95 -0.9)
			)
			(stroke
				(width 0.05)
				(type default)
			)
			(fill no)
			(layer "F.CrtYd")
		)
		(fp_poly
			(pts
				(xy -0.95 -0.675001) (xy -0.95 0.675001) (xy 0.95 0.675001) (xy 0.95 -0.675001)
			)
			(stroke
				(width 0.15)
				(type solid)
			)
			(fill no)
			(layer "F.Fab")
		)
		(fp_text user "License: Apache-2.0"
			(at -1.9 4.947 0)
			(layer "F.Fab")
			(effects
				(font
					(size 0.7 0.7)
					(thickness 0.15)
				)
				(justify right top)
			)
		)
		(fp_text user "${REFERENCE}"
			(at -1.899999 3.947 0)
			(layer "F.Fab")
			(effects
				(font
					(size 0.7 0.7)
					(thickness 0.15)
				)
				(justify right top)
			)
		)
		(fp_text user "Author: Antmicro"
			(at -1.9 5.947 0)
			(layer "F.Fab")
			(effects
				(font
					(size 0.7 0.7)
					(thickness 0.15)
				)
				(justify right top)
			)
		)
		(pad "1" smd roundrect
			(at -1.099999 0 180)
			(size 1.2 1.3)
			(layers "F.Cu" "F.Mask" "F.Paste")
			(roundrect_rratio 0.25)
			(net 1 "GND")
			(pintype "passive")
		)
		(pad "2" smd roundrect
			(at 1.099999 0 180)
			(size 1.2 1.3)
			(layers "F.Cu" "F.Mask" "F.Paste")
			(roundrect_rratio 0.25)
			(net 13 "VCC")
			(pintype "passive")
		)
	)
	(footprint "antmicro-footprints:C_0402_1005Metric"
		(layer "F.Cu")
		(at 217.2 94.2)
		(descr "Capacitor SMD 0402")
		(tags "capacitor SMD 0402")
		(property "Reference" "C131"
			(at -0.5 1.5 0)
			(layer "F.SilkS")
			(effects
				(font
					(size 0.7 0.7)
					(thickness 0.15)
				)
				(justify left bottom)
			)
		)
		(property "Value" "C_100n_0402"
			(at -1.022927 2.155213 0)
			(layer "F.Fab")
			(effects
				(font
					(size 0.7 0.7)
					(thickness 0.15)
				)
				(justify left bottom)
			)
		)
		(property "Datasheet" "https://www.murata.com/products/productdetail?partno=GRM155R61H104KE14%23"
			(at 0 0 0)
			(layer "F.Fab")
			(hide yes)
			(effects
				(font
					(size 1.27 1.27)
					(thickness 0.15)
				)
			)
		)
		(property "Description" "SMD Multilayer Ceramic Capacitor, 0.1 µF, 50 V, 0402 [1005 Metric], ± 10%, X5R, GRM Series"
			(at 0 0 0)
			(layer "F.Fab")
			(hide yes)
			(effects
				(font
					(size 1.27 1.27)
					(thickness 0.15)
				)
			)
		)
		(property "Manufacturer" "Murata"
			(at 0 0 0)
			(unlocked yes)
			(layer "F.Fab")
			(hide yes)
			(effects
				(font
					(size 1 1)
					(thickness 0.15)
				)
			)
		)
		(property "MPN" "GRM155R61H104KE14D"
			(at 0 0 0)
			(unlocked yes)
			(layer "F.Fab")
			(hide yes)
			(effects
				(font
					(size 1 1)
					(thickness 0.15)
				)
			)
		)
		(property "Val" "100n"
			(at 0 0 0)
			(unlocked yes)
			(layer "F.Fab")
			(hide yes)
			(effects
				(font
					(size 1 1)
					(thickness 0.15)
				)
			)
		)
		(property "License" "Apache-2.0"
			(at 0 0 0)
			(unlocked yes)
			(layer "F.Fab")
			(hide yes)
			(effects
				(font
					(size 1 1)
					(thickness 0.15)
				)
			)
		)
		(property "Author" "Antmicro"
			(at 0 0 0)
			(unlocked yes)
			(layer "F.Fab")
			(hide yes)
			(effects
				(font
					(size 1 1)
					(thickness 0.15)
				)
			)
		)
		(property "Voltage" "50V"
			(at 0 0 0)
			(unlocked yes)
			(layer "F.Fab")
			(hide yes)
			(effects
				(font
					(size 1 1)
					(thickness 0.15)
				)
			)
		)
		(property "Dielectric" "X5R"
			(at 0 0 0)
			(unlocked yes)
			(layer "F.Fab")
			(hide yes)
			(effects
				(font
					(size 1 1)
					(thickness 0.15)
				)
			)
		)
		(sheetname "/USB DP Alt mode/")
		(sheetfile "usb_dp.kicad_sch")
		(attr smd)
		(fp_poly
			(pts
				(xy -0.925 -0.47) (xy -0.925 0.47) (xy 0.925 0.47) (xy 0.925 -0.47)
			)
			(stroke
				(width 0.05)
				(type default)
			)
			(fill no)
			(layer "F.CrtYd")
		)
		(fp_line
			(start -0.494 -0.25)
			(end 0.504 -0.25)
			(stroke
				(width 0.15)
				(type solid)
			)
			(layer "F.Fab")
		)
		(fp_line
			(start -0.494 0.248)
			(end -0.494 -0.25)
			(stroke
				(width 0.15)
				(type solid)
			)
			(layer "F.Fab")
		)
		(fp_line
			(start 0.504 -0.25)
			(end 0.504 0.248)
			(stroke
				(width 0.15)
				(type solid)
			)
			(layer "F.Fab")
		)
		(fp_line
			(start 0.504 0.248)
			(end -0.494 0.248)
			(stroke
				(width 0.15)
				(type solid)
			)
			(layer "F.Fab")
		)
		(fp_text user "License: Apache-2.0"
			(at -0.939 5.799 0)
			(layer "F.Fab")
			(effects
				(font
					(size 0.7 0.7)
					(thickness 0.15)
				)
				(justify left bottom)
			)
		)
		(fp_text user "${REFERENCE}"
			(at -0.939 4.599 0)
			(layer "F.Fab")
			(effects
				(font
					(size 0.7 0.7)
					(thickness 0.15)
				)
				(justify left bottom)
			)
		)
		(fp_text user "Author: Antmicro"
			(at -0.939 3.399 0)
			(layer "F.Fab")
			(effects
				(font
					(size 0.7 0.7)
					(thickness 0.15)
				)
				(justify left bottom)
			)
		)
		(pad "1" smd roundrect
			(at -0.48 0)
			(size 0.59 0.64)
			(layers "F.Cu" "F.Mask" "F.Paste")
			(roundrect_rratio 0.25)
			(net 2 "+3V3")
			(pintype "passive")
		)
		(pad "2" smd roundrect
			(at 0.48 0)
			(size 0.59 0.64)
			(layers "F.Cu" "F.Mask" "F.Paste")
			(roundrect_rratio 0.25)
			(net 1 "GND")
			(pintype "passive")
		)
	)
	(footprint "antmicro-footprints:R_0402_1005Metric"
		(layer "F.Cu")
		(at 92.98 149.18)
		(descr "Resistor SMD 0402")
		(tags "resistor SMD 0402")
		(property "Reference" "R196"
			(at 1.02 0.394264 0)
			(layer "F.SilkS")
			(effects
				(font
					(size 0.7 0.7)
					(thickness 0.15)
				)
				(justify left bottom)
			)
		)
		(property "Value" "R_0R_0402"
			(at -1.011843 1.772046 0)
			(layer "F.Fab")
			(effects
				(font
					(size 0.7 0.7)
					(thickness 0.15)
				)
				(justify left bottom)
			)
		)
		(property "Datasheet" "https://industrial.panasonic.com/cdbs/www-data/pdf/RDA0000/AOA0000C301.pdf"
			(at 0 0 0)
			(layer "F.Fab")
			(hide yes)
			(effects
				(font
					(size 1.27 1.27)
					(thickness 0.15)
				)
			)
		)
		(property "Description" "SMD Chip Resistor, Jumper, 0 ohm, 100 mW, 0402 [1005 Metric], Thick Film, General Purpose"
			(at 0 0 0)
			(layer "F.Fab")
			(hide yes)
			(effects
				(font
					(size 1.27 1.27)
					(thickness 0.15)
				)
			)
		)
		(property "MPN" "ERJ2GE0R00X"
			(at 0 0 0)
			(unlocked yes)
			(layer "F.Fab")
			(hide yes)
			(effects
				(font
					(size 1 1)
					(thickness 0.15)
				)
			)
		)
		(property "Manufacturer" "Panasonic"
			(at 0 0 0)
			(unlocked yes)
			(layer "F.Fab")
			(hide yes)
			(effects
				(font
					(size 1 1)
					(thickness 0.15)
				)
			)
		)
		(property "License" "Apache-2.0"
			(at 0 0 0)
			(unlocked yes)
			(layer "F.Fab")
			(hide yes)
			(effects
				(font
					(size 1 1)
					(thickness 0.15)
				)
			)
		)
		(property "Author" "Antmicro"
			(at 0 0 0)
			(unlocked yes)
			(layer "F.Fab")
			(hide yes)
			(effects
				(font
					(size 1 1)
					(thickness 0.15)
				)
			)
		)
		(property "Val" "0R"
			(at 0 0 0)
			(unlocked yes)
			(layer "F.Fab")
			(hide yes)
			(effects
				(font
					(size 1 1)
					(thickness 0.15)
				)
			)
		)
		(property "Tolerance" "~"
			(at 0 0 0)
			(unlocked yes)
			(layer "F.Fab")
			(hide yes)
			(effects
				(font
					(size 1 1)
					(thickness 0.15)
				)
			)
		)
		(property "Current" "1A"
			(at 0 0 0)
			(unlocked yes)
			(layer "F.Fab")
			(hide yes)
			(effects
				(font
					(size 1 1)
					(thickness 0.15)
				)
			)
		)
		(sheetname "/SoM_IO2/")
		(sheetfile "som_io2.kicad_sch")
		(attr smd exclude_from_pos_files exclude_from_bom dnp)
		(fp_poly
			(pts
				(xy -0.925 -0.47) (xy -0.925 0.47) (xy 0.925 0.47) (xy 0.925 -0.47)
			)
			(stroke
				(width 0.05)
				(type default)
			)
			(fill no)
			(layer "F.CrtYd")
		)
		(fp_poly
			(pts
				(xy -0.5 -0.25) (xy -0.5 0.25) (xy 0.5 0.25) (xy 0.5 -0.25)
			)
			(stroke
				(width 0.15)
				(type solid)
			)
			(fill no)
			(layer "F.Fab")
		)
		(fp_text user "License: Apache-2.0"
			(at -0.949999 5.169 0)
			(layer "F.Fab")
			(effects
				(font
					(size 0.7 0.7)
					(thickness 0.15)
				)
				(justify left bottom)
			)
		)
		(fp_text user "${REFERENCE}"
			(at -0.95 3.168 0)
			(layer "F.Fab")
			(effects
				(font
					(size 0.7 0.7)
					(thickness 0.15)
				)
				(justify left bottom)
			)
		)
		(fp_text user "Author: Antmicro"
			(at -0.95 4.169 0)
			(layer "F.Fab")
			(effects
				(font
					(size 0.7 0.7)
					(thickness 0.15)
				)
				(justify left bottom)
			)
		)
		(pad "1" smd roundrect
			(at -0.48 0)
			(size 0.59 0.64)
			(layers "F.Cu" "F.Mask" "F.Paste")
			(roundrect_rratio 0.25)
			(net 898 "/SoM_IO2/C2_REFCLK+")
			(pintype "passive")
		)
		(pad "2" smd roundrect
			(at 0.48 0)
			(size 0.59 0.64)
			(layers "F.Cu" "F.Mask" "F.Paste")
			(roundrect_rratio 0.25)
			(net 720 "/SoM_IO2/PCIe_{C2x1}R_CLK+")
			(pintype "passive")
		)
	)
	(footprint "antmicro-footprints:R_0402_1005Metric"
		(layer "F.Cu")
		(at 183.25 139)
		(descr "Resistor SMD 0402")
		(tags "resistor SMD 0402")
		(property "Reference" "R18"
			(at -0.35 -1.6 0)
			(layer "F.SilkS")
			(effects
				(font
					(size 0.7 0.7)
					(thickness 0.15)
				)
				(justify left bottom)
			)
		)
		(property "Value" "R_10k_0402"
			(at -1.011843 1.772047 0)
			(layer "F.Fab")
			(effects
				(font
					(size 0.7 0.7)
					(thickness 0.15)
				)
				(justify left bottom)
			)
		)
		(property "Datasheet" "https://www.bourns.com/docs/product-datasheets/cr.pdf"
			(at 0 0 0)
			(layer "F.Fab")
			(hide yes)
			(effects
				(font
					(size 1.27 1.27)
					(thickness 0.15)
				)
			)
		)
		(property "Description" "SMD Chip Resistor, 10 kohm, ± 1%, 62.5 mW, 0402 [1005 Metric], Thick Film, General Purpose"
			(at 0 0 0)
			(layer "F.Fab")
			(hide yes)
			(effects
				(font
					(size 1.27 1.27)
					(thickness 0.15)
				)
			)
		)
		(property "MPN" "CR0402-FX-1002GLF"
			(at 0 0 0)
			(unlocked yes)
			(layer "F.Fab")
			(hide yes)
			(effects
				(font
					(size 1 1)
					(thickness 0.15)
				)
			)
		)
		(property "Manufacturer" "Bourns"
			(at 0 0 0)
			(unlocked yes)
			(layer "F.Fab")
			(hide yes)
			(effects
				(font
					(size 1 1)
					(thickness 0.15)
				)
			)
		)
		(property "License" "Apache-2.0"
			(at 0 0 0)
			(unlocked yes)
			(layer "F.Fab")
			(hide yes)
			(effects
				(font
					(size 1 1)
					(thickness 0.15)
				)
			)
		)
		(property "Author" "Antmicro"
			(at 0 0 0)
			(unlocked yes)
			(layer "F.Fab")
			(hide yes)
			(effects
				(font
					(size 1 1)
					(thickness 0.15)
				)
			)
		)
		(property "Val" "10k"
			(at 0 0 0)
			(unlocked yes)
			(layer "F.Fab")
			(hide yes)
			(effects
				(font
					(size 1 1)
					(thickness 0.15)
				)
			)
		)
		(property "Tolerance" "1%"
			(at 0 0 0)
			(unlocked yes)
			(layer "F.Fab")
			(hide yes)
			(effects
				(font
					(size 1 1)
					(thickness 0.15)
				)
			)
		)
		(sheetname "/DCDC/")
		(sheetfile "dcdc.kicad_sch")
		(attr smd)
		(fp_rect
			(start -0.925 -0.47)
			(end 0.925 0.47)
			(stroke
				(width 0.05)
				(type default)
			)
			(fill no)
			(layer "F.CrtYd")
		)
		(fp_rect
			(start -0.5 -0.25)
			(end 0.5 0.25)
			(stroke
				(width 0.15)
				(type solid)
			)
			(fill no)
			(layer "F.Fab")
		)
		(fp_text user "License: Apache-2.0"
			(at -0.95 5.169 0)
			(layer "F.Fab")
			(effects
				(font
					(size 0.7 0.7)
					(thickness 0.15)
				)
				(justify left bottom)
			)
		)
		(fp_text user "${REFERENCE}"
			(at -0.95 3.168 0)
			(layer "F.Fab")
			(effects
				(font
					(size 0.7 0.7)
					(thickness 0.15)
				)
				(justify left bottom)
			)
		)
		(fp_text user "Author: Antmicro"
			(at -0.95 4.169 0)
			(layer "F.Fab")
			(effects
				(font
					(size 0.7 0.7)
					(thickness 0.15)
				)
				(justify left bottom)
			)
		)
		(pad "1" smd roundrect
			(at -0.48 0)
			(size 0.59 0.64)
			(layers "F.Cu" "F.Mask" "F.Paste")
			(roundrect_rratio 0.25)
			(net 1 "GND")
			(pintype "passive")
		)
		(pad "2" smd roundrect
			(at 0.48 0)
			(size 0.59 0.64)
			(layers "F.Cu" "F.Mask" "F.Paste")
			(roundrect_rratio 0.25)
			(net 1206 "/DCDC/12V_FB")
			(pintype "passive")
		)
	)
	(footprint "antmicro-footprints:C_0402_1005Metric"
		(layer "F.Cu")
		(at 205.9 134.8 90)
		(descr "Capacitor SMD 0402")
		(tags "capacitor SMD 0402")
		(property "Reference" "C253"
			(at -1.59 13.89 90)
			(layer "F.SilkS")
			(effects
				(font
					(size 0.7 0.7)
					(thickness 0.15)
				)
				(justify left bottom)
			)
		)
		(property "Value" "C_100n_0402"
			(at -1.022927 2.155213 90)
			(layer "F.Fab")
			(effects
				(font
					(size 0.7 0.7)
					(thickness 0.15)
				)
				(justify left bottom)
			)
		)
		(property "Datasheet" "https://www.murata.com/products/productdetail?partno=GRM155R61H104KE14%23"
			(at 0 0 90)
			(layer "F.Fab")
			(hide yes)
			(effects
				(font
					(size 1.27 1.27)
					(thickness 0.15)
				)
			)
		)
		(property "Description" "SMD Multilayer Ceramic Capacitor, 0.1 µF, 50 V, 0402 [1005 Metric], ± 10%, X5R, GRM Series"
			(at 0 0 90)
			(layer "F.Fab")
			(hide yes)
			(effects
				(font
					(size 1.27 1.27)
					(thickness 0.15)
				)
			)
		)
		(property "Manufacturer" "Murata"
			(at 0 0 90)
			(unlocked yes)
			(layer "F.Fab")
			(hide yes)
			(effects
				(font
					(size 1 1)
					(thickness 0.15)
				)
			)
		)
		(property "MPN" "GRM155R61H104KE14D"
			(at 0 0 90)
			(unlocked yes)
			(layer "F.Fab")
			(hide yes)
			(effects
				(font
					(size 1 1)
					(thickness 0.15)
				)
			)
		)
		(property "Val" "100n"
			(at 0 0 90)
			(unlocked yes)
			(layer "F.Fab")
			(hide yes)
			(effects
				(font
					(size 1 1)
					(thickness 0.15)
				)
			)
		)
		(property "License" "Apache-2.0"
			(at 0 0 90)
			(unlocked yes)
			(layer "F.Fab")
			(hide yes)
			(effects
				(font
					(size 1 1)
					(thickness 0.15)
				)
			)
		)
		(property "Author" "Antmicro"
			(at 0 0 90)
			(unlocked yes)
			(layer "F.Fab")
			(hide yes)
			(effects
				(font
					(size 1 1)
					(thickness 0.15)
				)
			)
		)
		(property "Voltage" "50V"
			(at 0 0 90)
			(unlocked yes)
			(layer "F.Fab")
			(hide yes)
			(effects
				(font
					(size 1 1)
					(thickness 0.15)
				)
			)
		)
		(property "Dielectric" "X5R"
			(at 0 0 90)
			(unlocked yes)
			(layer "F.Fab")
			(hide yes)
			(effects
				(font
					(size 1 1)
					(thickness 0.15)
				)
			)
		)
		(sheetname "/USB Hub/")
		(sheetfile "usb_hub.kicad_sch")
		(attr smd)
		(fp_rect
			(start -0.925 -0.47)
			(end 0.925 0.47)
			(stroke
				(width 0.05)
				(type default)
			)
			(fill no)
			(layer "F.CrtYd")
		)
		(fp_line
			(start 0.504 -0.25)
			(end 0.504 0.248)
			(stroke
				(width 0.15)
				(type solid)
			)
			(layer "F.Fab")
		)
		(fp_line
			(start -0.494 -0.25)
			(end 0.504 -0.25)
			(stroke
				(width 0.15)
				(type solid)
			)
			(layer "F.Fab")
		)
		(fp_line
			(start 0.504 0.248)
			(end -0.494 0.248)
			(stroke
				(width 0.15)
				(type solid)
			)
			(layer "F.Fab")
		)
		(fp_line
			(start -0.494 0.248)
			(end -0.494 -0.25)
			(stroke
				(width 0.15)
				(type solid)
			)
			(layer "F.Fab")
		)
		(fp_text user "${REFERENCE}"
			(at -0.939 4.599 90)
			(layer "F.Fab")
			(effects
				(font
					(size 0.7 0.7)
					(thickness 0.15)
				)
				(justify left bottom)
			)
		)
		(fp_text user "License: Apache-2.0"
			(at -0.939 5.799 90)
			(layer "F.Fab")
			(effects
				(font
					(size 0.7 0.7)
					(thickness 0.15)
				)
				(justify left bottom)
			)
		)
		(fp_text user "Author: Antmicro"
			(at -0.939 3.399 90)
			(layer "F.Fab")
			(effects
				(font
					(size 0.7 0.7)
					(thickness 0.15)
				)
				(justify left bottom)
			)
		)
		(pad "1" smd roundrect
			(at -0.48 0 90)
			(size 0.59 0.64)
			(layers "F.Cu" "F.Mask" "F.Paste")
			(roundrect_rratio 0.25)
			(net 770 "/SoM_IO2/USBSS2.RX+")
			(pintype "passive")
		)
		(pad "2" smd roundrect
			(at 0.48 0 90)
			(size 0.59 0.64)
			(layers "F.Cu" "F.Mask" "F.Paste")
			(roundrect_rratio 0.25)
			(net 1132 "/USB Hub/USBSS_TX_P")
			(pintype "passive")
		)
	)
	(footprint "antmicro-footprints:C_0402_1005Metric"
		(layer "F.Cu")
		(at 94 60.5 180)
		(descr "Capacitor SMD 0402")
		(tags "capacitor SMD 0402")
		(property "Reference" "C251"
			(at -9.75 -0.78 0)
			(layer "F.SilkS")
			(effects
				(font
					(size 0.7 0.7)
					(thickness 0.15)
				)
				(justify right top)
			)
		)
		(property "Value" "C_1u_25V_0402"
			(at -1.022927 2.155213 0)
			(layer "F.Fab")
			(effects
				(font
					(size 0.7 0.7)
					(thickness 0.15)
				)
				(justify right top)
			)
		)
		(property "Datasheet" "https://www.murata.com/products/productdetail?partno=GRM155R61E105KE11%23"
			(at 0 0 0)
			(layer "F.Fab")
			(hide yes)
			(effects
				(font
					(size 1.27 1.27)
					(thickness 0.15)
				)
			)
		)
		(property "Description" "SMD Multilayer Ceramic Capacitor, 1 µF, 25 V, 0402 [1005 Metric], ± 10%, X5R, GRM Series"
			(at 0 0 0)
			(layer "F.Fab")
			(hide yes)
			(effects
				(font
					(size 1.27 1.27)
					(thickness 0.15)
				)
			)
		)
		(property "MPN" "GRM155R61E105KE11J"
			(at 0 0 180)
			(unlocked yes)
			(layer "F.Fab")
			(hide yes)
			(effects
				(font
					(size 1 1)
					(thickness 0.15)
				)
			)
		)
		(property "Manufacturer" "Murata"
			(at 0 0 180)
			(unlocked yes)
			(layer "F.Fab")
			(hide yes)
			(effects
				(font
					(size 1 1)
					(thickness 0.15)
				)
			)
		)
		(property "License" "Apache-2.0"
			(at 0 0 180)
			(unlocked yes)
			(layer "F.Fab")
			(hide yes)
			(effects
				(font
					(size 1 1)
					(thickness 0.15)
				)
			)
		)
		(property "Author" "Antmicro"
			(at 0 0 180)
			(unlocked yes)
			(layer "F.Fab")
			(hide yes)
			(effects
				(font
					(size 1 1)
					(thickness 0.15)
				)
			)
		)
		(property "Val" "1u"
			(at 0 0 180)
			(unlocked yes)
			(layer "F.Fab")
			(hide yes)
			(effects
				(font
					(size 1 1)
					(thickness 0.15)
				)
			)
		)
		(property "Voltage" "25V"
			(at 0 0 180)
			(unlocked yes)
			(layer "F.Fab")
			(hide yes)
			(effects
				(font
					(size 1 1)
					(thickness 0.15)
				)
			)
		)
		(property "Dielectric" "X5R"
			(at 0 0 180)
			(unlocked yes)
			(layer "F.Fab")
			(hide yes)
			(effects
				(font
					(size 1 1)
					(thickness 0.15)
				)
			)
		)
		(sheetname "/SoM_Power/")
		(sheetfile "som_power.kicad_sch")
		(attr smd)
		(fp_rect
			(start -0.925 -0.47)
			(end 0.925 0.47)
			(stroke
				(width 0.05)
				(type default)
			)
			(fill no)
			(layer "F.CrtYd")
		)
		(fp_line
			(start 0.504 0.248)
			(end -0.494 0.248)
			(stroke
				(width 0.15)
				(type solid)
			)
			(layer "F.Fab")
		)
		(fp_line
			(start 0.504 -0.25)
			(end 0.504 0.248)
			(stroke
				(width 0.15)
				(type solid)
			)
			(layer "F.Fab")
		)
		(fp_line
			(start -0.494 0.248)
			(end -0.494 -0.25)
			(stroke
				(width 0.15)
				(type solid)
			)
			(layer "F.Fab")
		)
		(fp_line
			(start -0.494 -0.25)
			(end 0.504 -0.25)
			(stroke
				(width 0.15)
				(type solid)
			)
			(layer "F.Fab")
		)
		(fp_text user "Author: Antmicro"
			(at -0.939 3.399 0)
			(layer "F.Fab")
			(effects
				(font
					(size 0.7 0.7)
					(thickness 0.15)
				)
				(justify right top)
			)
		)
		(fp_text user "License: Apache-2.0"
			(at -0.939 5.799 0)
			(layer "F.Fab")
			(effects
				(font
					(size 0.7 0.7)
					(thickness 0.15)
				)
				(justify right top)
			)
		)
		(fp_text user "${REFERENCE}"
			(at -0.939 4.599 0)
			(layer "F.Fab")
			(effects
				(font
					(size 0.7 0.7)
					(thickness 0.15)
				)
				(justify right top)
			)
		)
		(pad "1" smd roundrect
			(at -0.48 0 180)
			(size 0.59 0.64)
			(layers "F.Cu" "F.Mask" "F.Paste")
			(roundrect_rratio 0.25)
			(net 524 "Net-(Q22-D)")
			(pintype "passive")
		)
		(pad "2" smd roundrect
			(at 0.48 0 180)
			(size 0.59 0.64)
			(layers "F.Cu" "F.Mask" "F.Paste")
			(roundrect_rratio 0.25)
			(net 610 "/SoM_Power/~{PWR_BTN}")
			(pintype "passive")
		)
	)
	(footprint "antmicro-footprints:C_0402_1005Metric"
		(layer "F.Cu")
		(at 197.215 121.9)
		(descr "Capacitor SMD 0402")
		(tags "capacitor SMD 0402")
		(property "Reference" "C47"
			(at -1.315 -1.8 0)
			(layer "F.SilkS")
			(effects
				(font
					(size 0.7 0.7)
					(thickness 0.15)
				)
				(justify left bottom)
			)
		)
		(property "Value" "C_100n_0402"
			(at -1.022927 2.155213 0)
			(layer "F.Fab")
			(effects
				(font
					(size 0.7 0.7)
					(thickness 0.15)
				)
				(justify left bottom)
			)
		)
		(property "Datasheet" "https://www.murata.com/products/productdetail?partno=GRM155R61H104KE14%23"
			(at 0 0 0)
			(layer "F.Fab")
			(hide yes)
			(effects
				(font
					(size 1.27 1.27)
					(thickness 0.15)
				)
			)
		)
		(property "Description" "SMD Multilayer Ceramic Capacitor, 0.1 µF, 50 V, 0402 [1005 Metric], ± 10%, X5R, GRM Series"
			(at 0 0 0)
			(layer "F.Fab")
			(hide yes)
			(effects
				(font
					(size 1.27 1.27)
					(thickness 0.15)
				)
			)
		)
		(property "MPN" "GRM155R61H104KE14D"
			(at 0 0 0)
			(unlocked yes)
			(layer "F.Fab")
			(hide yes)
			(effects
				(font
					(size 1 1)
					(thickness 0.15)
				)
			)
		)
		(property "Val" "100n"
			(at 0 0 0)
			(unlocked yes)
			(layer "F.Fab")
			(hide yes)
			(effects
				(font
					(size 1 1)
					(thickness 0.15)
				)
			)
		)
		(property "Voltage" "50V"
			(at 0 0 0)
			(unlocked yes)
			(layer "F.Fab")
			(hide yes)
			(effects
				(font
					(size 1 1)
					(thickness 0.15)
				)
			)
		)
		(property "Dielectric" "X5R"
			(at 0 0 0)
			(unlocked yes)
			(layer "F.Fab")
			(hide yes)
			(effects
				(font
					(size 1 1)
					(thickness 0.15)
				)
			)
		)
		(property "Manufacturer" "Murata"
			(at 0 0 0)
			(unlocked yes)
			(layer "F.Fab")
			(hide yes)
			(effects
				(font
					(size 1 1)
					(thickness 0.15)
				)
			)
		)
		(property "License" "Apache-2.0"
			(at 0 0 0)
			(unlocked yes)
			(layer "F.Fab")
			(hide yes)
			(effects
				(font
					(size 1 1)
					(thickness 0.15)
				)
			)
		)
		(property "Author" "Antmicro"
			(at 0 0 0)
			(unlocked yes)
			(layer "F.Fab")
			(hide yes)
			(effects
				(font
					(size 1 1)
					(thickness 0.15)
				)
			)
		)
		(sheetname "/USB Hub/")
		(sheetfile "usb_hub.kicad_sch")
		(attr smd)
		(fp_rect
			(start -0.925 -0.47)
			(end 0.925 0.47)
			(stroke
				(width 0.05)
				(type default)
			)
			(fill no)
			(layer "F.CrtYd")
		)
		(fp_line
			(start -0.494 -0.25)
			(end 0.504 -0.25)
			(stroke
				(width 0.15)
				(type solid)
			)
			(layer "F.Fab")
		)
		(fp_line
			(start -0.494 0.248)
			(end -0.494 -0.25)
			(stroke
				(width 0.15)
				(type solid)
			)
			(layer "F.Fab")
		)
		(fp_line
			(start 0.504 -0.25)
			(end 0.504 0.248)
			(stroke
				(width 0.15)
				(type solid)
			)
			(layer "F.Fab")
		)
		(fp_line
			(start 0.504 0.248)
			(end -0.494 0.248)
			(stroke
				(width 0.15)
				(type solid)
			)
			(layer "F.Fab")
		)
		(fp_text user "${REFERENCE}"
			(at -0.939 4.599 0)
			(layer "F.Fab")
			(effects
				(font
					(size 0.7 0.7)
					(thickness 0.15)
				)
				(justify left bottom)
			)
		)
		(fp_text user "Author: Antmicro"
			(at -0.939 3.399 0)
			(layer "F.Fab")
			(effects
				(font
					(size 0.7 0.7)
					(thickness 0.15)
				)
				(justify left bottom)
			)
		)
		(fp_text user "License: Apache-2.0"
			(at -0.939 5.799 0)
			(layer "F.Fab")
			(effects
				(font
					(size 0.7 0.7)
					(thickness 0.15)
				)
				(justify left bottom)
			)
		)
		(pad "1" smd roundrect
			(at -0.48 0)
			(size 0.59 0.64)
			(layers "F.Cu" "F.Mask" "F.Paste")
			(roundrect_rratio 0.25)
			(net 1 "GND")
			(pintype "passive")
		)
		(pad "2" smd roundrect
			(at 0.48 0)
			(size 0.59 0.64)
			(layers "F.Cu" "F.Mask" "F.Paste")
			(roundrect_rratio 0.25)
			(net 2 "+3V3")
			(pintype "passive")
		)
	)
	(footprint "antmicro-footprints:R_0402_1005Metric"
		(layer "F.Cu")
		(at 156.72 111.2 180)
		(descr "Resistor SMD 0402")
		(tags "resistor SMD 0402")
		(property "Reference" "R377"
			(at -3.68 0.4 0)
			(layer "F.SilkS")
			(effects
				(font
					(size 0.7 0.7)
					(thickness 0.15)
				)
				(justify right top)
			)
		)
		(property "Value" "R_2k2_0402"
			(at -1.011843 1.772047 0)
			(layer "F.Fab")
			(effects
				(font
					(size 0.7 0.7)
					(thickness 0.15)
				)
				(justify right top)
			)
		)
		(property "Datasheet" "https://www.bourns.com/docs/product-datasheets/cr.pdf"
			(at 0 0 0)
			(layer "F.Fab")
			(hide yes)
			(effects
				(font
					(size 1.27 1.27)
					(thickness 0.15)
				)
			)
		)
		(property "Description" "SMD Chip Resistor, 2.2 kohm, ± 1%, 62.5 mW, 0402 [1005 Metric], Thick Film, General Purpose"
			(at 0 0 0)
			(layer "F.Fab")
			(hide yes)
			(effects
				(font
					(size 1.27 1.27)
					(thickness 0.15)
				)
			)
		)
		(property "MPN" "CR0402-FX-2201GLF"
			(at 0 0 180)
			(unlocked yes)
			(layer "F.Fab")
			(hide yes)
			(effects
				(font
					(size 1 1)
					(thickness 0.15)
				)
			)
		)
		(property "Manufacturer" "Bourns"
			(at 0 0 180)
			(unlocked yes)
			(layer "F.Fab")
			(hide yes)
			(effects
				(font
					(size 1 1)
					(thickness 0.15)
				)
			)
		)
		(property "License" "Apache-2.0"
			(at 0 0 180)
			(unlocked yes)
			(layer "F.Fab")
			(hide yes)
			(effects
				(font
					(size 1 1)
					(thickness 0.15)
				)
			)
		)
		(property "Author" "Antmicro"
			(at 0 0 180)
			(unlocked yes)
			(layer "F.Fab")
			(hide yes)
			(effects
				(font
					(size 1 1)
					(thickness 0.15)
				)
			)
		)
		(property "Val" "2k2"
			(at 0 0 180)
			(unlocked yes)
			(layer "F.Fab")
			(hide yes)
			(effects
				(font
					(size 1 1)
					(thickness 0.15)
				)
			)
		)
		(property "Tolerance" "1%"
			(at 0 0 180)
			(unlocked yes)
			(layer "F.Fab")
			(hide yes)
			(effects
				(font
					(size 1 1)
					(thickness 0.15)
				)
			)
		)
		(sheetname "/SoM_IO/")
		(sheetfile "som_io.kicad_sch")
		(attr smd)
		(fp_rect
			(start -0.925 -0.47)
			(end 0.925 0.47)
			(stroke
				(width 0.05)
				(type default)
			)
			(fill no)
			(layer "F.CrtYd")
		)
		(fp_rect
			(start -0.5 -0.25)
			(end 0.5 0.25)
			(stroke
				(width 0.15)
				(type solid)
			)
			(fill no)
			(layer "F.Fab")
		)
		(fp_text user "${REFERENCE}"
			(at -0.95 3.168 0)
			(layer "F.Fab")
			(effects
				(font
					(size 0.7 0.7)
					(thickness 0.15)
				)
				(justify right top)
			)
		)
		(fp_text user "Author: Antmicro"
			(at -0.95 4.169 0)
			(layer "F.Fab")
			(effects
				(font
					(size 0.7 0.7)
					(thickness 0.15)
				)
				(justify right top)
			)
		)
		(fp_text user "License: Apache-2.0"
			(at -0.95 5.169 0)
			(layer "F.Fab")
			(effects
				(font
					(size 0.7 0.7)
					(thickness 0.15)
				)
				(justify right top)
			)
		)
		(pad "1" smd roundrect
			(at -0.48 0 180)
			(size 0.59 0.64)
			(layers "F.Cu" "F.Mask" "F.Paste")
			(roundrect_rratio 0.25)
			(net 2 "+3V3")
			(pintype "passive")
		)
		(pad "2" smd roundrect
			(at 0.48 0 180)
			(size 0.59 0.64)
			(layers "F.Cu" "F.Mask" "F.Paste")
			(roundrect_rratio 0.25)
			(net 853 "/I2C_{SYS}.SCL")
			(pintype "passive")
		)
	)
	(footprint "antmicro-footprints:R_0402_1005Metric"
		(layer "F.Cu")
		(at 92.7 119.1 180)
		(descr "Resistor SMD 0402")
		(tags "resistor SMD 0402")
		(property "Reference" "R351"
			(at -1.1 0.5 180)
			(layer "F.SilkS")
			(effects
				(font
					(size 0.7 0.7)
					(thickness 0.15)
				)
				(justify left bottom)
			)
		)
		(property "Value" "R_0R_0402"
			(at -1.011843 1.772046 180)
			(layer "F.Fab")
			(effects
				(font
					(size 0.7 0.7)
					(thickness 0.15)
				)
				(justify left bottom)
			)
		)
		(property "Datasheet" "https://industrial.panasonic.com/cdbs/www-data/pdf/RDA0000/AOA0000C301.pdf"
			(at 0 0 180)
			(layer "F.Fab")
			(hide yes)
			(effects
				(font
					(size 1.27 1.27)
					(thickness 0.15)
				)
			)
		)
		(property "Description" "SMD Chip Resistor, Jumper, 0 ohm, 100 mW, 0402 [1005 Metric], Thick Film, General Purpose"
			(at 0 0 180)
			(layer "F.Fab")
			(hide yes)
			(effects
				(font
					(size 1.27 1.27)
					(thickness 0.15)
				)
			)
		)
		(property "MPN" "ERJ2GE0R00X"
			(at 0 0 180)
			(unlocked yes)
			(layer "F.Fab")
			(hide yes)
			(effects
				(font
					(size 1 1)
					(thickness 0.15)
				)
			)
		)
		(property "Manufacturer" "Panasonic"
			(at 0 0 180)
			(unlocked yes)
			(layer "F.Fab")
			(hide yes)
			(effects
				(font
					(size 1 1)
					(thickness 0.15)
				)
			)
		)
		(property "License" "Apache-2.0"
			(at 0 0 180)
			(unlocked yes)
			(layer "F.Fab")
			(hide yes)
			(effects
				(font
					(size 1 1)
					(thickness 0.15)
				)
			)
		)
		(property "Author" "Antmicro"
			(at 0 0 180)
			(unlocked yes)
			(layer "F.Fab")
			(hide yes)
			(effects
				(font
					(size 1 1)
					(thickness 0.15)
				)
			)
		)
		(property "Val" "0R"
			(at 0 0 180)
			(unlocked yes)
			(layer "F.Fab")
			(hide yes)
			(effects
				(font
					(size 1 1)
					(thickness 0.15)
				)
			)
		)
		(property "Tolerance" "~"
			(at 0 0 180)
			(unlocked yes)
			(layer "F.Fab")
			(hide yes)
			(effects
				(font
					(size 1 1)
					(thickness 0.15)
				)
			)
		)
		(property "Current" "1A"
			(at 0 0 180)
			(unlocked yes)
			(layer "F.Fab")
			(hide yes)
			(effects
				(font
					(size 1 1)
					(thickness 0.15)
				)
			)
		)
		(sheetname "/Expansion connector/")
		(sheetfile "expansion_connector.kicad_sch")
		(attr smd)
		(fp_poly
			(pts
				(xy -0.925 -0.47) (xy 0.925 -0.47) (xy 0.925 0.47) (xy -0.925 0.47)
			)
			(stroke
				(width 0.05)
				(type default)
			)
			(fill no)
			(layer "F.CrtYd")
		)
		(fp_poly
			(pts
				(xy -0.5 -0.25) (xy 0.5 -0.25) (xy 0.5 0.25) (xy -0.5 0.25)
			)
			(stroke
				(width 0.15)
				(type solid)
			)
			(fill no)
			(layer "F.Fab")
		)
		(fp_text user "${REFERENCE}"
			(at -0.95 3.168 180)
			(layer "F.Fab")
			(effects
				(font
					(size 0.7 0.7)
					(thickness 0.15)
				)
				(justify left bottom)
			)
		)
		(fp_text user "Author: Antmicro"
			(at -0.95 4.169 180)
			(layer "F.Fab")
			(effects
				(font
					(size 0.7 0.7)
					(thickness 0.15)
				)
				(justify left bottom)
			)
		)
		(fp_text user "License: Apache-2.0"
			(at -0.949999 5.169 180)
			(layer "F.Fab")
			(effects
				(font
					(size 0.7 0.7)
					(thickness 0.15)
				)
				(justify left bottom)
			)
		)
		(pad "1" smd roundrect
			(at -0.48 0 180)
			(size 0.59 0.64)
			(layers "F.Cu" "F.Mask" "F.Paste")
			(roundrect_rratio 0.25)
			(net 790 "/Expansion connector/PCIe_{C2x1}.RX0+")
			(pintype "passive")
		)
		(pad "2" smd roundrect
			(at 0.48 0 180)
			(size 0.59 0.64)
			(layers "F.Cu" "F.Mask" "F.Paste")
			(roundrect_rratio 0.25)
			(net 471 "/Expansion connector/PER0_C2_N")
			(pintype "passive")
		)
	)
	(footprint "antmicro-footprints:R_0402_1005Metric"
		(layer "F.Cu")
		(at 156.72 113.2 180)
		(descr "Resistor SMD 0402")
		(tags "resistor SMD 0402")
		(property "Reference" "R375"
			(at -3.68 0.4 0)
			(layer "F.SilkS")
			(effects
				(font
					(size 0.7 0.7)
					(thickness 0.15)
				)
				(justify right top)
			)
		)
		(property "Value" "R_2k2_0402"
			(at -1.011843 1.772047 0)
			(layer "F.Fab")
			(effects
				(font
					(size 0.7 0.7)
					(thickness 0.15)
				)
				(justify right top)
			)
		)
		(property "Datasheet" "https://www.bourns.com/docs/product-datasheets/cr.pdf"
			(at 0 0 0)
			(layer "F.Fab")
			(hide yes)
			(effects
				(font
					(size 1.27 1.27)
					(thickness 0.15)
				)
			)
		)
		(property "Description" "SMD Chip Resistor, 2.2 kohm, ± 1%, 62.5 mW, 0402 [1005 Metric], Thick Film, General Purpose"
			(at 0 0 0)
			(layer "F.Fab")
			(hide yes)
			(effects
				(font
					(size 1.27 1.27)
					(thickness 0.15)
				)
			)
		)
		(property "MPN" "CR0402-FX-2201GLF"
			(at 0 0 180)
			(unlocked yes)
			(layer "F.Fab")
			(hide yes)
			(effects
				(font
					(size 1 1)
					(thickness 0.15)
				)
			)
		)
		(property "Manufacturer" "Bourns"
			(at 0 0 180)
			(unlocked yes)
			(layer "F.Fab")
			(hide yes)
			(effects
				(font
					(size 1 1)
					(thickness 0.15)
				)
			)
		)
		(property "License" "Apache-2.0"
			(at 0 0 180)
			(unlocked yes)
			(layer "F.Fab")
			(hide yes)
			(effects
				(font
					(size 1 1)
					(thickness 0.15)
				)
			)
		)
		(property "Author" "Antmicro"
			(at 0 0 180)
			(unlocked yes)
			(layer "F.Fab")
			(hide yes)
			(effects
				(font
					(size 1 1)
					(thickness 0.15)
				)
			)
		)
		(property "Val" "2k2"
			(at 0 0 180)
			(unlocked yes)
			(layer "F.Fab")
			(hide yes)
			(effects
				(font
					(size 1 1)
					(thickness 0.15)
				)
			)
		)
		(property "Tolerance" "1%"
			(at 0 0 180)
			(unlocked yes)
			(layer "F.Fab")
			(hide yes)
			(effects
				(font
					(size 1 1)
					(thickness 0.15)
				)
			)
		)
		(sheetname "/SoM_IO/")
		(sheetfile "som_io.kicad_sch")
		(attr smd)
		(fp_rect
			(start -0.925 -0.47)
			(end 0.925 0.47)
			(stroke
				(width 0.05)
				(type default)
			)
			(fill no)
			(layer "F.CrtYd")
		)
		(fp_rect
			(start -0.5 -0.25)
			(end 0.5 0.25)
			(stroke
				(width 0.15)
				(type solid)
			)
			(fill no)
			(layer "F.Fab")
		)
		(fp_text user "Author: Antmicro"
			(at -0.95 4.169 0)
			(layer "F.Fab")
			(effects
				(font
					(size 0.7 0.7)
					(thickness 0.15)
				)
				(justify right top)
			)
		)
		(fp_text user "License: Apache-2.0"
			(at -0.95 5.169 0)
			(layer "F.Fab")
			(effects
				(font
					(size 0.7 0.7)
					(thickness 0.15)
				)
				(justify right top)
			)
		)
		(fp_text user "${REFERENCE}"
			(at -0.95 3.168 0)
			(layer "F.Fab")
			(effects
				(font
					(size 0.7 0.7)
					(thickness 0.15)
				)
				(justify right top)
			)
		)
		(pad "1" smd roundrect
			(at -0.48 0 180)
			(size 0.59 0.64)
			(layers "F.Cu" "F.Mask" "F.Paste")
			(roundrect_rratio 0.25)
			(net 2 "+3V3")
			(pintype "passive")
		)
		(pad "2" smd roundrect
			(at 0.48 0 180)
			(size 0.59 0.64)
			(layers "F.Cu" "F.Mask" "F.Paste")
			(roundrect_rratio 0.25)
			(net 42 "/Peripherals/I2C_{CONN}.SCL")
			(pintype "passive")
		)
	)
	(footprint "antmicro-footprints:R_0402_1005Metric"
		(layer "F.Cu")
		(at 179.949468 66.47 -90)
		(descr "Resistor SMD 0402")
		(tags "resistor SMD 0402")
		(property "Reference" "R29"
			(at -3.01 0.3 90)
			(layer "F.SilkS")
			(effects
				(font
					(size 0.7 0.7)
					(thickness 0.15)
				)
				(justify right top)
			)
		)
		(property "Value" "R_100k_0402"
			(at -1.011843 1.772047 90)
			(layer "F.Fab")
			(effects
				(font
					(size 0.7 0.7)
					(thickness 0.15)
				)
				(justify right top)
			)
		)
		(property "Datasheet" "https://www.bourns.com/docs/product-datasheets/cr.pdf"
			(at 0 0 90)
			(layer "F.Fab")
			(hide yes)
			(effects
				(font
					(size 1.27 1.27)
					(thickness 0.15)
				)
			)
		)
		(property "Description" "SMD Chip Resistor, 100 kohm, ± 1%, 62.5 mW, 0402 [1005 Metric], Thick Film, General Purpose"
			(at 0 0 90)
			(layer "F.Fab")
			(hide yes)
			(effects
				(font
					(size 1.27 1.27)
					(thickness 0.15)
				)
			)
		)
		(property "MPN" "CR0402-FX-1003GLF"
			(at 0 0 90)
			(unlocked yes)
			(layer "F.Fab")
			(hide yes)
			(effects
				(font
					(size 1 1)
					(thickness 0.15)
				)
			)
		)
		(property "Manufacturer" "Bourns"
			(at 0 0 90)
			(unlocked yes)
			(layer "F.Fab")
			(hide yes)
			(effects
				(font
					(size 1 1)
					(thickness 0.15)
				)
			)
		)
		(property "License" "Apache-2.0"
			(at 0 0 90)
			(unlocked yes)
			(layer "F.Fab")
			(hide yes)
			(effects
				(font
					(size 1 1)
					(thickness 0.15)
				)
			)
		)
		(property "Author" "Antmicro"
			(at 0 0 90)
			(unlocked yes)
			(layer "F.Fab")
			(hide yes)
			(effects
				(font
					(size 1 1)
					(thickness 0.15)
				)
			)
		)
		(property "Val" "100k"
			(at 0 0 90)
			(unlocked yes)
			(layer "F.Fab")
			(hide yes)
			(effects
				(font
					(size 1 1)
					(thickness 0.15)
				)
			)
		)
		(property "Tolerance" "1%"
			(at 0 0 90)
			(unlocked yes)
			(layer "F.Fab")
			(hide yes)
			(effects
				(font
					(size 1 1)
					(thickness 0.15)
				)
			)
		)
		(component_classes
			(class "DCDC_20V")
		)
		(sheetname "/DCDC/")
		(sheetfile "dcdc.kicad_sch")
		(attr smd)
		(fp_rect
			(start -0.925 -0.47)
			(end 0.925 0.47)
			(stroke
				(width 0.05)
				(type default)
			)
			(fill no)
			(layer "F.CrtYd")
		)
		(fp_rect
			(start -0.5 -0.25)
			(end 0.5 0.25)
			(stroke
				(width 0.15)
				(type solid)
			)
			(fill no)
			(layer "F.Fab")
		)
		(fp_text user "${REFERENCE}"
			(at -0.95 3.168 90)
			(layer "F.Fab")
			(effects
				(font
					(size 0.7 0.7)
					(thickness 0.15)
				)
				(justify right top)
			)
		)
		(fp_text user "Author: Antmicro"
			(at -0.95 4.169 90)
			(layer "F.Fab")
			(effects
				(font
					(size 0.7 0.7)
					(thickness 0.15)
				)
				(justify right top)
			)
		)
		(fp_text user "License: Apache-2.0"
			(at -0.95 5.169 90)
			(layer "F.Fab")
			(effects
				(font
					(size 0.7 0.7)
					(thickness 0.15)
				)
				(justify right top)
			)
		)
		(pad "1" smd roundrect
			(at -0.48 0 270)
			(size 0.59 0.64)
			(layers "F.Cu" "F.Mask" "F.Paste")
			(roundrect_rratio 0.25)
			(net 1 "GND")
			(pintype "passive")
		)
		(pad "2" smd roundrect
			(at 0.48 0 270)
			(size 0.59 0.64)
			(layers "F.Cu" "F.Mask" "F.Paste")
			(roundrect_rratio 0.25)
			(net 1208 "/DCDC/20V_MODE1")
			(pintype "passive")
		)
	)
	(footprint "antmicro-footprints:USON-10_2.5x1mm_P0.5mm"
		(layer "F.Cu")
		(at 221.369 105.46 180)
		(descr "USON-10 2.5x1mm_ Pitch 0.5mm")
		(tags "USON-10 2.5x1mm Pitch 0.5mm")
		(property "Reference" "U57"
			(at -1.081 0.96 90)
			(layer "F.SilkS")
			(effects
				(font
					(size 0.7 0.7)
					(thickness 0.15)
				)
				(justify right top)
			)
		)
		(property "Value" "TPD4E05U06QDQARQ1"
			(at 0.018 2.499 0)
			(layer "F.Fab")
			(effects
				(font
					(size 0.7 0.7)
					(thickness 0.15)
				)
				(justify right top)
			)
		)
		(property "Datasheet" "https://www.ti.com/lit/ds/symlink/tpd4e05u06-q1.pdf?HQS=dis-mous-null-mousermode-dsf-pf-null-wwe&ts=1663591265741&ref_url=https%253A%252F%252Fwww.mouser.com%252F"
			(at 0 0 0)
			(layer "F.Fab")
			(hide yes)
			(effects
				(font
					(size 1.27 1.27)
					(thickness 0.15)
				)
			)
		)
		(property "Description" "TVS diode array, 12 kV, USON-10, 5.5 V, 0.5 pF"
			(at 0 0 0)
			(layer "F.Fab")
			(hide yes)
			(effects
				(font
					(size 1.27 1.27)
					(thickness 0.15)
				)
			)
		)
		(property "Manufacturer" "Texas Instruments"
			(at 0 0 180)
			(unlocked yes)
			(layer "F.Fab")
			(hide yes)
			(effects
				(font
					(size 1 1)
					(thickness 0.15)
				)
			)
		)
		(property "MPN" "TPD4E05U06QDQARQ1"
			(at 0 0 180)
			(unlocked yes)
			(layer "F.Fab")
			(hide yes)
			(effects
				(font
					(size 1 1)
					(thickness 0.15)
				)
			)
		)
		(property "Author" "Antmicro"
			(at 0 0 180)
			(unlocked yes)
			(layer "F.Fab")
			(hide yes)
			(effects
				(font
					(size 1 1)
					(thickness 0.15)
				)
			)
		)
		(property "License" "Apache-2.0"
			(at 0 0 180)
			(unlocked yes)
			(layer "F.Fab")
			(hide yes)
			(effects
				(font
					(size 1 1)
					(thickness 0.15)
				)
			)
		)
		(sheetname "/Recovery USB/")
		(sheetfile "recovery_usb.kicad_sch")
		(attr smd)
		(fp_line
			(start 0.498 1.398)
			(end -0.5 1.398)
			(stroke
				(width 0.15)
				(type solid)
			)
			(layer "F.SilkS")
		)
		(fp_line
			(start 0.498 -1.401)
			(end -0.5 -1.401)
			(stroke
				(width 0.15)
				(type solid)
			)
			(layer "F.SilkS")
		)
		(fp_circle
			(center -0.68 -1.27)
			(end -0.63 -1.27)
			(stroke
				(width 0.15)
				(type solid)
			)
			(fill yes)
			(layer "F.SilkS")
		)
		(fp_rect
			(start -0.8 -1.5)
			(end 0.8 1.499)
			(stroke
				(width 0.05)
				(type solid)
			)
			(fill no)
			(layer "F.CrtYd")
		)
		(fp_line
			(start 0.498 -1.25)
			(end 0.498 1.249)
			(stroke
				(width 0.15)
				(type solid)
			)
			(layer "F.Fab")
		)
		(fp_line
			(start 0.498 -1.25)
			(end -0.25 -1.25)
			(stroke
				(width 0.15)
				(type solid)
			)
			(layer "F.Fab")
		)
		(fp_line
			(start -0.25 -1.25)
			(end -0.5 -1)
			(stroke
				(width 0.15)
				(type solid)
			)
			(layer "F.Fab")
		)
		(fp_line
			(start -0.5 1.249)
			(end 0.498 1.249)
			(stroke
				(width 0.15)
				(type solid)
			)
			(layer "F.Fab")
		)
		(fp_line
			(start -0.5 -1)
			(end -0.5 1.249)
			(stroke
				(width 0.15)
				(type solid)
			)
			(layer "F.Fab")
		)
		(fp_text user "Author: Antmicro"
			(at -0.802 5.7 0)
			(layer "F.Fab")
			(effects
				(font
					(size 0.7 0.7)
					(thickness 0.15)
				)
				(justify right top)
			)
		)
		(fp_text user "License: Apache-2.0"
			(at -0.802 6.9 0)
			(layer "F.Fab")
			(effects
				(font
					(size 0.7 0.7)
					(thickness 0.15)
				)
				(justify right top)
			)
		)
		(fp_text user "${REFERENCE}"
			(at -0.802 4.498 0)
			(layer "F.Fab")
			(effects
				(font
					(size 0.7 0.7)
					(thickness 0.15)
				)
				(justify right top)
			)
		)
		(pad "1" smd roundrect
			(at -0.387 -1 90)
			(size 0.25 0.55)
			(layers "F.Cu" "F.Mask" "F.Paste")
			(roundrect_rratio 0.25)
			(net 800 "/Recovery USB/USBC2_RX1_N")
			(pintype "passive")
		)
		(pad "2" smd roundrect
			(at -0.387 -0.5 90)
			(size 0.25 0.55)
			(layers "F.Cu" "F.Mask" "F.Paste")
			(roundrect_rratio 0.25)
			(net 802 "/Recovery USB/USBC2_RX1_P")
			(pintype "passive")
		)
		(pad "3" smd roundrect
			(at -0.387 0 90)
			(size 0.4 0.55)
			(layers "F.Cu" "F.Mask" "F.Paste")
			(roundrect_rratio 0.25)
			(net 1 "GND")
			(pintype "power_in")
		)
		(pad "4" smd roundrect
			(at -0.387 0.498 90)
			(size 0.25 0.55)
			(layers "F.Cu" "F.Mask" "F.Paste")
			(roundrect_rratio 0.25)
			(net 215 "/Recovery USB/USBC2_CONN_TX1_N")
			(pintype "passive")
		)
		(pad "5" smd roundrect
			(at -0.387 0.998 90)
			(size 0.25 0.55)
			(layers "F.Cu" "F.Mask" "F.Paste")
			(roundrect_rratio 0.25)
			(net 245 "/Recovery USB/USBC2_CONN_TX1_P")
			(pintype "passive")
		)
		(pad "6" smd roundrect
			(at 0.385 0.998 90)
			(size 0.25 0.55)
			(layers "F.Cu" "F.Mask" "F.Paste")
			(roundrect_rratio 0.25)
			(net 245 "/Recovery USB/USBC2_CONN_TX1_P")
			(pintype "passive")
		)
		(pad "7" smd roundrect
			(at 0.385 0.498 90)
			(size 0.25 0.55)
			(layers "F.Cu" "F.Mask" "F.Paste")
			(roundrect_rratio 0.25)
			(net 215 "/Recovery USB/USBC2_CONN_TX1_N")
			(pintype "passive")
		)
		(pad "8" smd roundrect
			(at 0.385 0 90)
			(size 0.4 0.55)
			(layers "F.Cu" "F.Mask" "F.Paste")
			(roundrect_rratio 0.25)
			(net 1 "GND")
			(pintype "passive")
		)
		(pad "9" smd roundrect
			(at 0.385 -0.5 90)
			(size 0.25 0.55)
			(layers "F.Cu" "F.Mask" "F.Paste")
			(roundrect_rratio 0.25)
			(net 802 "/Recovery USB/USBC2_RX1_P")
			(pintype "passive")
		)
		(pad "10" smd roundrect
			(at 0.385 -1 90)
			(size 0.25 0.55)
			(layers "F.Cu" "F.Mask" "F.Paste")
			(roundrect_rratio 0.25)
			(net 800 "/Recovery USB/USBC2_RX1_N")
			(pintype "passive")
		)
	)
	(footprint "antmicro-footprints:C_0402_1005Metric"
		(layer "F.Cu")
		(at 128.6 132.8)
		(descr "Capacitor SMD 0402")
		(tags "capacitor SMD 0402")
		(property "Reference" "C5"
			(at -2.63 0.4 0)
			(layer "F.SilkS")
			(effects
				(font
					(size 0.7 0.7)
					(thickness 0.15)
				)
				(justify left bottom)
			)
		)
		(property "Value" "C_100n_0402"
			(at -1.022927 2.155213 0)
			(layer "F.Fab")
			(effects
				(font
					(size 0.7 0.7)
					(thickness 0.15)
				)
				(justify left bottom)
			)
		)
		(property "Datasheet" "https://www.murata.com/products/productdetail?partno=GRM155R61H104KE14%23"
			(at 0 0 0)
			(layer "F.Fab")
			(hide yes)
			(effects
				(font
					(size 1.27 1.27)
					(thickness 0.15)
				)
			)
		)
		(property "Description" "SMD Multilayer Ceramic Capacitor, 0.1 µF, 50 V, 0402 [1005 Metric], ± 10%, X5R, GRM Series"
			(at 0 0 0)
			(layer "F.Fab")
			(hide yes)
			(effects
				(font
					(size 1.27 1.27)
					(thickness 0.15)
				)
			)
		)
		(property "Manufacturer" "Murata"
			(at 0 0 0)
			(unlocked yes)
			(layer "F.Fab")
			(hide yes)
			(effects
				(font
					(size 1 1)
					(thickness 0.15)
				)
			)
		)
		(property "MPN" "GRM155R61H104KE14D"
			(at 0 0 0)
			(unlocked yes)
			(layer "F.Fab")
			(hide yes)
			(effects
				(font
					(size 1 1)
					(thickness 0.15)
				)
			)
		)
		(property "Val" "100n"
			(at 0 0 0)
			(unlocked yes)
			(layer "F.Fab")
			(hide yes)
			(effects
				(font
					(size 1 1)
					(thickness 0.15)
				)
			)
		)
		(property "License" "Apache-2.0"
			(at 0 0 0)
			(unlocked yes)
			(layer "F.Fab")
			(hide yes)
			(effects
				(font
					(size 1 1)
					(thickness 0.15)
				)
			)
		)
		(property "Author" "Antmicro"
			(at 0 0 0)
			(unlocked yes)
			(layer "F.Fab")
			(hide yes)
			(effects
				(font
					(size 1 1)
					(thickness 0.15)
				)
			)
		)
		(property "Voltage" "50V"
			(at 0 0 0)
			(unlocked yes)
			(layer "F.Fab")
			(hide yes)
			(effects
				(font
					(size 1 1)
					(thickness 0.15)
				)
			)
		)
		(property "Dielectric" "X5R"
			(at 0 0 0)
			(unlocked yes)
			(layer "F.Fab")
			(hide yes)
			(effects
				(font
					(size 1 1)
					(thickness 0.15)
				)
			)
		)
		(sheetname "/Expansion connector/")
		(sheetfile "expansion_connector.kicad_sch")
		(attr smd)
		(fp_poly
			(pts
				(xy -0.925 -0.47) (xy -0.925 0.47) (xy 0.925 0.47) (xy 0.925 -0.47)
			)
			(stroke
				(width 0.05)
				(type default)
			)
			(fill no)
			(layer "F.CrtYd")
		)
		(fp_line
			(start -0.494 -0.25)
			(end 0.504 -0.25)
			(stroke
				(width 0.15)
				(type solid)
			)
			(layer "F.Fab")
		)
		(fp_line
			(start -0.494 0.248)
			(end -0.494 -0.25)
			(stroke
				(width 0.15)
				(type solid)
			)
			(layer "F.Fab")
		)
		(fp_line
			(start 0.504 -0.25)
			(end 0.504 0.248)
			(stroke
				(width 0.15)
				(type solid)
			)
			(layer "F.Fab")
		)
		(fp_line
			(start 0.504 0.248)
			(end -0.494 0.248)
			(stroke
				(width 0.15)
				(type solid)
			)
			(layer "F.Fab")
		)
		(fp_text user "Author: Antmicro"
			(at -0.939 3.399 0)
			(layer "F.Fab")
			(effects
				(font
					(size 0.7 0.7)
					(thickness 0.15)
				)
				(justify left bottom)
			)
		)
		(fp_text user "${REFERENCE}"
			(at -0.939 4.599 0)
			(layer "F.Fab")
			(effects
				(font
					(size 0.7 0.7)
					(thickness 0.15)
				)
				(justify left bottom)
			)
		)
		(fp_text user "License: Apache-2.0"
			(at -0.939 5.799 0)
			(layer "F.Fab")
			(effects
				(font
					(size 0.7 0.7)
					(thickness 0.15)
				)
				(justify left bottom)
			)
		)
		(pad "1" smd roundrect
			(at -0.48 0)
			(size 0.59 0.64)
			(layers "F.Cu" "F.Mask" "F.Paste")
			(roundrect_rratio 0.25)
			(net 1 "GND")
			(pintype "passive")
		)
		(pad "2" smd roundrect
			(at 0.48 0)
			(size 0.59 0.64)
			(layers "F.Cu" "F.Mask" "F.Paste")
			(roundrect_rratio 0.25)
			(net 148 "/Expansion connector/+3V3_AUX")
			(pintype "passive")
		)
	)
	(footprint "antmicro-footprints:C_0805_2012Metric"
		(layer "F.Cu")
		(at 176.33 142.41 90)
		(descr "Capacitor SMD 0805")
		(tags "capacitor SMD 0805")
		(property "Reference" "C309"
			(at 1.87 -0.26 90)
			(layer "F.SilkS")
			(effects
				(font
					(size 0.7 0.7)
					(thickness 0.15)
				)
				(justify left bottom)
			)
		)
		(property "Value" "C_22u_25V_0805"
			(at -2.055717 1.963152 90)
			(layer "F.Fab")
			(effects
				(font
					(size 0.7 0.7)
					(thickness 0.15)
				)
				(justify left bottom)
			)
		)
		(property "Datasheet" "https://product.samsungsem.com/mlcc/CL21A226MAYNNN.do"
			(at 0 0 90)
			(layer "F.Fab")
			(hide yes)
			(effects
				(font
					(size 1.27 1.27)
					(thickness 0.15)
				)
			)
		)
		(property "Description" "SMT Multilayer Ceramic Capacitor, 22uF, +/-20%, 25V, X5R, 0805 [2012 Metric]"
			(at 0 0 90)
			(layer "F.Fab")
			(hide yes)
			(effects
				(font
					(size 1.27 1.27)
					(thickness 0.15)
				)
			)
		)
		(property "Manufacturer" "Samsung Electro-Mechanics"
			(at 0 0 90)
			(unlocked yes)
			(layer "F.Fab")
			(hide yes)
			(effects
				(font
					(size 1 1)
					(thickness 0.15)
				)
			)
		)
		(property "MPN" "CL21A226MAYNNNE"
			(at 0 0 90)
			(unlocked yes)
			(layer "F.Fab")
			(hide yes)
			(effects
				(font
					(size 1 1)
					(thickness 0.15)
				)
			)
		)
		(property "Val" "22u"
			(at 0 0 90)
			(unlocked yes)
			(layer "F.Fab")
			(hide yes)
			(effects
				(font
					(size 1 1)
					(thickness 0.15)
				)
			)
		)
		(property "License" "Apache-2.0"
			(at 0 0 90)
			(unlocked yes)
			(layer "F.Fab")
			(hide yes)
			(effects
				(font
					(size 1 1)
					(thickness 0.15)
				)
			)
		)
		(property "Author" "Antmicro"
			(at 0 0 90)
			(unlocked yes)
			(layer "F.Fab")
			(hide yes)
			(effects
				(font
					(size 1 1)
					(thickness 0.15)
				)
			)
		)
		(property "Voltage" "25V"
			(at 0 0 90)
			(unlocked yes)
			(layer "F.Fab")
			(hide yes)
			(effects
				(font
					(size 1 1)
					(thickness 0.15)
				)
			)
		)
		(property "Dielectric" "X5R"
			(at 0 0 90)
			(unlocked yes)
			(layer "F.Fab")
			(hide yes)
			(effects
				(font
					(size 1 1)
					(thickness 0.15)
				)
			)
		)
		(property "Public" "False"
			(at 0 0 90)
			(unlocked yes)
			(layer "F.Fab")
			(hide yes)
			(effects
				(font
					(size 1 1)
					(thickness 0.15)
				)
			)
		)
		(sheetname "/DCDC/")
		(sheetfile "dcdc.kicad_sch")
		(attr smd)
		(fp_line
			(start -0.3 -0.7)
			(end 0.3 -0.7)
			(stroke
				(width 0.15)
				(type solid)
			)
			(layer "F.SilkS")
		)
		(fp_line
			(start -0.3 0.7)
			(end 0.3 0.7)
			(stroke
				(width 0.15)
				(type solid)
			)
			(layer "F.SilkS")
		)
		(fp_rect
			(start 1.95 -0.9)
			(end -1.95 0.9)
			(stroke
				(width 0.05)
				(type default)
			)
			(fill no)
			(layer "F.CrtYd")
		)
		(fp_rect
			(start -0.95 -0.675)
			(end 0.95 0.675)
			(stroke
				(width 0.15)
				(type solid)
			)
			(fill no)
			(layer "F.Fab")
		)
		(fp_text user "${REFERENCE}"
			(at -1.9 3.947 90)
			(layer "F.Fab")
			(effects
				(font
					(size 0.7 0.7)
					(thickness 0.15)
				)
				(justify left bottom)
			)
		)
		(fp_text user "License: Apache-2.0"
			(at -1.9 4.947 90)
			(layer "F.Fab")
			(effects
				(font
					(size 0.7 0.7)
					(thickness 0.15)
				)
				(justify left bottom)
			)
		)
		(fp_text user "Author: Antmicro"
			(at -1.9 5.947 90)
			(layer "F.Fab")
			(effects
				(font
					(size 0.7 0.7)
					(thickness 0.15)
				)
				(justify left bottom)
			)
		)
		(pad "1" smd roundrect
			(at -1.1 0 90)
			(size 1.2 1.3)
			(layers "F.Cu" "F.Mask" "F.Paste")
			(roundrect_rratio 0.25)
			(net 1 "GND")
			(pintype "passive")
		)
		(pad "2" smd roundrect
			(at 1.1 0 90)
			(size 1.2 1.3)
			(layers "F.Cu" "F.Mask" "F.Paste")
			(roundrect_rratio 0.25)
			(net 13 "VCC")
			(pintype "passive")
		)
	)
	(footprint "antmicro-footprints:R_0402_1005Metric"
		(layer "F.Cu")
		(at 189.49 124.92 90)
		(descr "Resistor SMD 0402")
		(tags "resistor SMD 0402")
		(property "Reference" "R9"
			(at -0.28 1.41 90)
			(layer "F.SilkS")
			(effects
				(font
					(size 0.7 0.7)
					(thickness 0.15)
				)
				(justify left bottom)
			)
		)
		(property "Value" "R_11k_0402"
			(at -1.011843 1.772047 90)
			(layer "F.Fab")
			(effects
				(font
					(size 0.7 0.7)
					(thickness 0.15)
				)
				(justify left bottom)
			)
		)
		(property "Datasheet" "https://www.bourns.com/docs/product-datasheets/cr.pdf"
			(at 0 0 90)
			(layer "F.Fab")
			(hide yes)
			(effects
				(font
					(size 1.27 1.27)
					(thickness 0.15)
				)
			)
		)
		(property "Description" "SMD Chip Resistor, 11 kohm, ± 1%, 62.5 mW, 0402 [1005 Metric], Thick Film, General Purpose"
			(at 0 0 90)
			(layer "F.Fab")
			(hide yes)
			(effects
				(font
					(size 1.27 1.27)
					(thickness 0.15)
				)
			)
		)
		(property "MPN" "CR0402-FX-1102GLF"
			(at 0 0 90)
			(unlocked yes)
			(layer "F.Fab")
			(hide yes)
			(effects
				(font
					(size 1 1)
					(thickness 0.15)
				)
			)
		)
		(property "Manufacturer" "Bourns"
			(at 0 0 90)
			(unlocked yes)
			(layer "F.Fab")
			(hide yes)
			(effects
				(font
					(size 1 1)
					(thickness 0.15)
				)
			)
		)
		(property "License" "Apache-2.0"
			(at 0 0 90)
			(unlocked yes)
			(layer "F.Fab")
			(hide yes)
			(effects
				(font
					(size 1 1)
					(thickness 0.15)
				)
			)
		)
		(property "Author" "Antmicro"
			(at 0 0 90)
			(unlocked yes)
			(layer "F.Fab")
			(hide yes)
			(effects
				(font
					(size 1 1)
					(thickness 0.15)
				)
			)
		)
		(property "Val" "11k"
			(at 0 0 90)
			(unlocked yes)
			(layer "F.Fab")
			(hide yes)
			(effects
				(font
					(size 1 1)
					(thickness 0.15)
				)
			)
		)
		(property "Tolerance" "1%"
			(at 0 0 90)
			(unlocked yes)
			(layer "F.Fab")
			(hide yes)
			(effects
				(font
					(size 1 1)
					(thickness 0.15)
				)
			)
		)
		(component_classes
			(class "DCDC_1V15")
		)
		(sheetname "/DCDC/")
		(sheetfile "dcdc.kicad_sch")
		(attr smd)
		(fp_rect
			(start -0.925 -0.47)
			(end 0.925 0.47)
			(stroke
				(width 0.05)
				(type default)
			)
			(fill no)
			(layer "F.CrtYd")
		)
		(fp_rect
			(start -0.5 -0.25)
			(end 0.5 0.25)
			(stroke
				(width 0.15)
				(type solid)
			)
			(fill no)
			(layer "F.Fab")
		)
		(fp_text user "License: Apache-2.0"
			(at -0.95 5.169 90)
			(layer "F.Fab")
			(effects
				(font
					(size 0.7 0.7)
					(thickness 0.15)
				)
				(justify left bottom)
			)
		)
		(fp_text user "${REFERENCE}"
			(at -0.95 3.168 90)
			(layer "F.Fab")
			(effects
				(font
					(size 0.7 0.7)
					(thickness 0.15)
				)
				(justify left bottom)
			)
		)
		(fp_text user "Author: Antmicro"
			(at -0.95 4.169 90)
			(layer "F.Fab")
			(effects
				(font
					(size 0.7 0.7)
					(thickness 0.15)
				)
				(justify left bottom)
			)
		)
		(pad "1" smd roundrect
			(at -0.48 0 90)
			(size 0.59 0.64)
			(layers "F.Cu" "F.Mask" "F.Paste")
			(roundrect_rratio 0.25)
			(net 1232 "/DCDC/1V15_FB")
			(pintype "passive")
		)
		(pad "2" smd roundrect
			(at 0.48 0 90)
			(size 0.59 0.64)
			(layers "F.Cu" "F.Mask" "F.Paste")
			(roundrect_rratio 0.25)
			(net 280 "/DCDC/1V15_OUT")
			(pintype "passive")
		)
	)
	(footprint "antmicro-footprints:SOT-523"
		(layer "F.Cu")
		(at 96.9 63.5 90)
		(property "Reference" "Q30"
			(at -1 2.1 90)
			(layer "F.SilkS")
			(effects
				(font
					(size 0.7 0.7)
					(thickness 0.15)
				)
				(justify left bottom)
			)
		)
		(property "Value" "DMG1012T-7"
			(at 0.1 1.824 90)
			(layer "F.Fab")
			(effects
				(font
					(size 0.7 0.7)
					(thickness 0.15)
				)
				(justify left bottom)
			)
		)
		(property "Datasheet" "https://www.diodes.com/assets/Datasheets/ds31783.pdf"
			(at 0 0 90)
			(layer "F.Fab")
			(hide yes)
			(effects
				(font
					(size 1.27 1.27)
					(thickness 0.15)
				)
			)
		)
		(property "Description" "Power MOSFET, N Channel, 20 V, 630 mA, 0.3 ohm, SOT-523, Surface Mount"
			(at 0 0 90)
			(layer "F.Fab")
			(hide yes)
			(effects
				(font
					(size 1.27 1.27)
					(thickness 0.15)
				)
			)
		)
		(property "MPN" "DMG1012T-7"
			(at 0 0 90)
			(unlocked yes)
			(layer "F.Fab")
			(hide yes)
			(effects
				(font
					(size 1 1)
					(thickness 0.15)
				)
			)
		)
		(property "Manufacturer" "Diodes Incorporated"
			(at 0 0 90)
			(unlocked yes)
			(layer "F.Fab")
			(hide yes)
			(effects
				(font
					(size 1 1)
					(thickness 0.15)
				)
			)
		)
		(property "Author" "Antmicro"
			(at 0 0 90)
			(unlocked yes)
			(layer "F.Fab")
			(hide yes)
			(effects
				(font
					(size 1 1)
					(thickness 0.15)
				)
			)
		)
		(property "License" "Apache-2.0"
			(at 0 0 90)
			(unlocked yes)
			(layer "F.Fab")
			(hide yes)
			(effects
				(font
					(size 1 1)
					(thickness 0.15)
				)
			)
		)
		(sheetname "/SoM_Power/")
		(sheetfile "som_power.kicad_sch")
		(attr smd)
		(fp_line
			(start -0.277 -0.551)
			(end -0.277 -0.75)
			(stroke
				(width 0.15)
				(type solid)
			)
			(layer "F.SilkS")
		)
		(fp_line
			(start -0.725 -0.551)
			(end -0.277 -0.551)
			(stroke
				(width 0.15)
				(type solid)
			)
			(layer "F.SilkS")
		)
		(fp_line
			(start -0.927 -0.351)
			(end -0.725 -0.551)
			(stroke
				(width 0.15)
				(type solid)
			)
			(layer "F.SilkS")
		)
		(fp_line
			(start -0.927 -0.051)
			(end -0.927 -0.351)
			(stroke
				(width 0.15)
				(type solid)
			)
			(layer "F.SilkS")
		)
		(fp_circle
			(center -0.9652 0.9652)
			(end -0.9152 0.9652)
			(stroke
				(width 0.15)
				(type solid)
			)
			(fill yes)
			(layer "F.SilkS")
		)
		(fp_line
			(start 1.1 -1.16)
			(end 1.1 1.15)
			(stroke
				(width 0.05)
				(type solid)
			)
			(layer "F.CrtYd")
		)
		(fp_line
			(start -1.12 -1.16)
			(end 1.1 -1.16)
			(stroke
				(width 0.05)
				(type solid)
			)
			(layer "F.CrtYd")
		)
		(fp_line
			(start -1.12 -1.16)
			(end -1.12 1.15)
			(stroke
				(width 0.05)
				(type solid)
			)
			(layer "F.CrtYd")
		)
		(fp_line
			(start -1.12 1.15)
			(end 1.1 1.15)
			(stroke
				(width 0.05)
				(type solid)
			)
			(layer "F.CrtYd")
		)
		(fp_line
			(start 0.8 -0.425)
			(end -0.652 -0.425)
			(stroke
				(width 0.15)
				(type solid)
			)
			(layer "F.Fab")
		)
		(fp_line
			(start 0.8 -0.425)
			(end 0.8 0.424)
			(stroke
				(width 0.15)
				(type solid)
			)
			(layer "F.Fab")
		)
		(fp_line
			(start -0.652 -0.425)
			(end -0.802 -0.276)
			(stroke
				(width 0.15)
				(type solid)
			)
			(layer "F.Fab")
		)
		(fp_line
			(start -0.802 -0.276)
			(end -0.802 0.424)
			(stroke
				(width 0.15)
				(type solid)
			)
			(layer "F.Fab")
		)
		(fp_line
			(start 0.8 0.424)
			(end -0.802 0.424)
			(stroke
				(width 0.15)
				(type solid)
			)
			(layer "F.Fab")
		)
		(fp_circle
			(center -0.9652 0.9652)
			(end -0.9144 0.9652)
			(stroke
				(width 0.15)
				(type solid)
			)
			(fill no)
			(layer "F.Fab")
		)
		(fp_text user "${REFERENCE}"
			(at -1.12 3.824 90)
			(layer "F.Fab")
			(effects
				(font
					(size 0.7 0.7)
					(thickness 0.15)
				)
				(justify left bottom)
			)
		)
		(fp_text user "Author: Antmicro"
			(at -1.12 6.224 90)
			(layer "F.Fab")
			(effects
				(font
					(size 0.7 0.7)
					(thickness 0.15)
				)
				(justify left bottom)
			)
		)
		(fp_text user "License: Apache-2.0"
			(at -1.12 5.024 90)
			(layer "F.Fab")
			(effects
				(font
					(size 0.7 0.7)
					(thickness 0.15)
				)
				(justify left bottom)
			)
		)
		(pad "1" smd rect
			(at -0.5 0.65 90)
			(size 0.4 0.51)
			(layers "F.Cu" "F.Mask" "F.Paste")
			(net 11 "+1V8")
			(pinfunction "G")
			(pintype "input")
		)
		(pad "2" smd rect
			(at 0.498 0.65 90)
			(size 0.4 0.51)
			(layers "F.Cu" "F.Mask" "F.Paste")
			(net 1235 "Net-(Q30-S)")
			(pinfunction "S")
			(pintype "passive")
		)
		(pad "3" smd rect
			(at 0 -0.652 90)
			(size 0.4 0.51)
			(layers "F.Cu" "F.Mask" "F.Paste")
			(net 1379 "Net-(Q30-D)")
			(pinfunction "D")
			(pintype "passive")
		)
	)
	(footprint "antmicro-footprints:C_0603_1608Metric_EIA"
		(layer "F.Cu")
		(at 147.954391 127.84 180)
		(descr "Capacitor SMD 0603, IPC-7351 Density Level A")
		(tags "Capacitor 0603")
		(property "Reference" "C305"
			(at -4.045609 0.34 0)
			(layer "F.SilkS")
			(effects
				(font
					(size 0.7 0.7)
					(thickness 0.15)
				)
				(justify right top)
			)
		)
		(property "Value" "C_22u_16V_0603"
			(at -1.42757 1.770288 0)
			(layer "F.Fab")
			(effects
				(font
					(size 0.7 0.7)
					(thickness 0.15)
				)
				(justify right top)
			)
		)
		(property "Datasheet" "https://product.samsungsem.com/mlcc/CL10A226MO7JZN.do"
			(at 0 0 0)
			(layer "F.Fab")
			(hide yes)
			(effects
				(font
					(size 1.27 1.27)
					(thickness 0.15)
				)
			)
		)
		(property "Description" "SMD Multilayer Ceramic Capacitor"
			(at 0 0 0)
			(layer "F.Fab")
			(hide yes)
			(effects
				(font
					(size 1.27 1.27)
					(thickness 0.15)
				)
			)
		)
		(property "Val" "22u"
			(at 0 0 180)
			(unlocked yes)
			(layer "F.Fab")
			(hide yes)
			(effects
				(font
					(size 1 1)
					(thickness 0.15)
				)
			)
		)
		(property "MPN" "CL10A226MO7JZNC"
			(at 0 0 180)
			(unlocked yes)
			(layer "F.Fab")
			(hide yes)
			(effects
				(font
					(size 1 1)
					(thickness 0.15)
				)
			)
		)
		(property "Manufacturer" "Samsung Electro-Mechanics"
			(at 0 0 180)
			(unlocked yes)
			(layer "F.Fab")
			(hide yes)
			(effects
				(font
					(size 1 1)
					(thickness 0.15)
				)
			)
		)
		(property "License" "Apache-2.0"
			(at 0 0 180)
			(unlocked yes)
			(layer "F.Fab")
			(hide yes)
			(effects
				(font
					(size 1 1)
					(thickness 0.15)
				)
			)
		)
		(property "Author" "Antmicro"
			(at 0 0 180)
			(unlocked yes)
			(layer "F.Fab")
			(hide yes)
			(effects
				(font
					(size 1 1)
					(thickness 0.15)
				)
			)
		)
		(property "Voltage" "16V"
			(at 0 0 180)
			(unlocked yes)
			(layer "F.Fab")
			(hide yes)
			(effects
				(font
					(size 1 1)
					(thickness 0.15)
				)
			)
		)
		(property "Dielectric" ""
			(at 0 0 180)
			(unlocked yes)
			(layer "F.Fab")
			(hide yes)
			(effects
				(font
					(size 1 1)
					(thickness 0.15)
				)
			)
		)
		(component_classes
			(class "DCDC_1V8")
		)
		(sheetname "/DCDC/")
		(sheetfile "dcdc.kicad_sch")
		(attr smd)
		(fp_line
			(start -0.15 0.55)
			(end 0.15 0.55)
			(stroke
				(width 0.15)
				(type solid)
			)
			(layer "F.SilkS")
		)
		(fp_line
			(start -0.15 -0.55)
			(end 0.15 -0.55)
			(stroke
				(width 0.15)
				(type solid)
			)
			(layer "F.SilkS")
		)
		(fp_rect
			(start -1.25 -0.65)
			(end 1.25 0.65)
			(stroke
				(width 0.05)
				(type solid)
			)
			(fill no)
			(layer "F.CrtYd")
		)
		(fp_rect
			(start -0.8 -0.45)
			(end 0.8 0.45)
			(stroke
				(width 0.15)
				(type solid)
			)
			(fill no)
			(layer "F.Fab")
		)
		(fp_text user "License: Apache-2.0"
			(at -1.682 5.895 0)
			(layer "F.Fab")
			(effects
				(font
					(size 0.7 0.7)
					(thickness 0.15)
				)
				(justify right top)
			)
		)
		(fp_text user "Author: Antmicro"
			(at -1.682 4.894 0)
			(layer "F.Fab")
			(effects
				(font
					(size 0.7 0.7)
					(thickness 0.15)
				)
				(justify right top)
			)
		)
		(fp_text user "${REFERENCE}"
			(at -1.682 3.895 0)
			(layer "F.Fab")
			(effects
				(font
					(size 0.7 0.7)
					(thickness 0.15)
				)
				(justify right top)
			)
		)
		(pad "1" smd roundrect
			(at -0.7 0 180)
			(size 0.8 1.1)
			(layers "F.Cu" "F.Mask" "F.Paste")
			(roundrect_rratio 0.2)
			(net 17 "/DCDC/1V8_OUT")
			(pintype "passive")
		)
		(pad "2" smd roundrect
			(at 0.7 0 180)
			(size 0.8 1.1)
			(layers "F.Cu" "F.Mask" "F.Paste")
			(roundrect_rratio 0.2)
			(net 1 "GND")
			(pintype "passive")
		)
	)
	(footprint "antmicro-footprints:C_0805_2012Metric"
		(layer "F.Cu")
		(at 174.98 69.11 90)
		(descr "Capacitor SMD 0805")
		(tags "capacitor SMD 0805")
		(property "Reference" "C269"
			(at 1.91 0.52 90)
			(layer "F.SilkS")
			(effects
				(font
					(size 0.7 0.7)
					(thickness 0.15)
				)
				(justify left bottom)
			)
		)
		(property "Value" "C_22u_25V_0805"
			(at -2.055717 1.963152 90)
			(layer "F.Fab")
			(effects
				(font
					(size 0.7 0.7)
					(thickness 0.15)
				)
				(justify left bottom)
			)
		)
		(property "Datasheet" "https://product.samsungsem.com/mlcc/CL21A226MAYNNN.do"
			(at 0 0 90)
			(layer "F.Fab")
			(hide yes)
			(effects
				(font
					(size 1.27 1.27)
					(thickness 0.15)
				)
			)
		)
		(property "Description" "SMT Multilayer Ceramic Capacitor, 22uF, +/-20%, 25V, X5R, 0805 [2012 Metric]"
			(at 0 0 90)
			(layer "F.Fab")
			(hide yes)
			(effects
				(font
					(size 1.27 1.27)
					(thickness 0.15)
				)
			)
		)
		(property "MPN" "CL21A226MAYNNNE"
			(at 0 0 90)
			(unlocked yes)
			(layer "F.Fab")
			(hide yes)
			(effects
				(font
					(size 1 1)
					(thickness 0.15)
				)
			)
		)
		(property "Manufacturer" "Samsung Electro-Mechanics"
			(at 0 0 90)
			(unlocked yes)
			(layer "F.Fab")
			(hide yes)
			(effects
				(font
					(size 1 1)
					(thickness 0.15)
				)
			)
		)
		(property "License" "Apache-2.0"
			(at 0 0 90)
			(unlocked yes)
			(layer "F.Fab")
			(hide yes)
			(effects
				(font
					(size 1 1)
					(thickness 0.15)
				)
			)
		)
		(property "Author" "Antmicro"
			(at 0 0 90)
			(unlocked yes)
			(layer "F.Fab")
			(hide yes)
			(effects
				(font
					(size 1 1)
					(thickness 0.15)
				)
			)
		)
		(property "Val" "22u"
			(at 0 0 90)
			(unlocked yes)
			(layer "F.Fab")
			(hide yes)
			(effects
				(font
					(size 1 1)
					(thickness 0.15)
				)
			)
		)
		(property "Voltage" "25V"
			(at 0 0 90)
			(unlocked yes)
			(layer "F.Fab")
			(hide yes)
			(effects
				(font
					(size 1 1)
					(thickness 0.15)
				)
			)
		)
		(property "Dielectric" "X5R"
			(at 0 0 90)
			(unlocked yes)
			(layer "F.Fab")
			(hide yes)
			(effects
				(font
					(size 1 1)
					(thickness 0.15)
				)
			)
		)
		(property "Public" "False"
			(at 0 0 90)
			(unlocked yes)
			(layer "F.Fab")
			(hide yes)
			(effects
				(font
					(size 1 1)
					(thickness 0.15)
				)
			)
		)
		(component_classes
			(class "DCDC_20V")
		)
		(sheetname "/DCDC/")
		(sheetfile "dcdc.kicad_sch")
		(attr smd)
		(fp_line
			(start -0.3 -0.7)
			(end 0.3 -0.7)
			(stroke
				(width 0.15)
				(type solid)
			)
			(layer "F.SilkS")
		)
		(fp_line
			(start -0.3 0.7)
			(end 0.3 0.7)
			(stroke
				(width 0.15)
				(type solid)
			)
			(layer "F.SilkS")
		)
		(fp_rect
			(start 1.95 -0.9)
			(end -1.95 0.9)
			(stroke
				(width 0.05)
				(type default)
			)
			(fill no)
			(layer "F.CrtYd")
		)
		(fp_rect
			(start -0.95 -0.675)
			(end 0.95 0.675)
			(stroke
				(width 0.15)
				(type solid)
			)
			(fill no)
			(layer "F.Fab")
		)
		(fp_text user "Author: Antmicro"
			(at -1.9 5.947 90)
			(layer "F.Fab")
			(effects
				(font
					(size 0.7 0.7)
					(thickness 0.15)
				)
				(justify left bottom)
			)
		)
		(fp_text user "License: Apache-2.0"
			(at -1.9 4.947 90)
			(layer "F.Fab")
			(effects
				(font
					(size 0.7 0.7)
					(thickness 0.15)
				)
				(justify left bottom)
			)
		)
		(fp_text user "${REFERENCE}"
			(at -1.9 3.947 90)
			(layer "F.Fab")
			(effects
				(font
					(size 0.7 0.7)
					(thickness 0.15)
				)
				(justify left bottom)
			)
		)
		(pad "1" smd roundrect
			(at -1.1 0 90)
			(size 1.2 1.3)
			(layers "F.Cu" "F.Mask" "F.Paste")
			(roundrect_rratio 0.25)
			(net 1 "GND")
			(pintype "passive")
		)
		(pad "2" smd roundrect
			(at 1.1 0 90)
			(size 1.2 1.3)
			(layers "F.Cu" "F.Mask" "F.Paste")
			(roundrect_rratio 0.25)
			(net 13 "VCC")
			(pintype "passive")
		)
	)
	(footprint "antmicro-footprints:R_0402_1005Metric"
		(layer "F.Cu")
		(at 156.6 121.4 180)
		(descr "Resistor SMD 0402")
		(tags "resistor SMD 0402")
		(property "Reference" "R356"
			(at -3.6 0.4 0)
			(layer "F.SilkS")
			(effects
				(font
					(size 0.7 0.7)
					(thickness 0.15)
				)
				(justify right top)
			)
		)
		(property "Value" "R_2k2_0402"
			(at -1.011843 1.772047 0)
			(layer "F.Fab")
			(effects
				(font
					(size 0.7 0.7)
					(thickness 0.15)
				)
				(justify right top)
			)
		)
		(property "Datasheet" "https://www.bourns.com/docs/product-datasheets/cr.pdf"
			(at 0 0 0)
			(layer "F.Fab")
			(hide yes)
			(effects
				(font
					(size 1.27 1.27)
					(thickness 0.15)
				)
			)
		)
		(property "Description" "SMD Chip Resistor, 2.2 kohm, ± 1%, 62.5 mW, 0402 [1005 Metric], Thick Film, General Purpose"
			(at 0 0 0)
			(layer "F.Fab")
			(hide yes)
			(effects
				(font
					(size 1.27 1.27)
					(thickness 0.15)
				)
			)
		)
		(property "MPN" "CR0402-FX-2201GLF"
			(at 0 0 180)
			(unlocked yes)
			(layer "F.Fab")
			(hide yes)
			(effects
				(font
					(size 1 1)
					(thickness 0.15)
				)
			)
		)
		(property "Manufacturer" "Bourns"
			(at 0 0 180)
			(unlocked yes)
			(layer "F.Fab")
			(hide yes)
			(effects
				(font
					(size 1 1)
					(thickness 0.15)
				)
			)
		)
		(property "License" "Apache-2.0"
			(at 0 0 180)
			(unlocked yes)
			(layer "F.Fab")
			(hide yes)
			(effects
				(font
					(size 1 1)
					(thickness 0.15)
				)
			)
		)
		(property "Author" "Antmicro"
			(at 0 0 180)
			(unlocked yes)
			(layer "F.Fab")
			(hide yes)
			(effects
				(font
					(size 1 1)
					(thickness 0.15)
				)
			)
		)
		(property "Val" "2k2"
			(at 0 0 180)
			(unlocked yes)
			(layer "F.Fab")
			(hide yes)
			(effects
				(font
					(size 1 1)
					(thickness 0.15)
				)
			)
		)
		(property "Tolerance" "1%"
			(at 0 0 180)
			(unlocked yes)
			(layer "F.Fab")
			(hide yes)
			(effects
				(font
					(size 1 1)
					(thickness 0.15)
				)
			)
		)
		(sheetname "/SoM_IO/")
		(sheetfile "som_io.kicad_sch")
		(attr smd exclude_from_pos_files exclude_from_bom dnp)
		(fp_rect
			(start -0.925 -0.47)
			(end 0.925 0.47)
			(stroke
				(width 0.05)
				(type default)
			)
			(fill no)
			(layer "F.CrtYd")
		)
		(fp_rect
			(start -0.5 -0.25)
			(end 0.5 0.25)
			(stroke
				(width 0.15)
				(type solid)
			)
			(fill no)
			(layer "F.Fab")
		)
		(fp_text user "Author: Antmicro"
			(at -0.95 4.169 0)
			(layer "F.Fab")
			(effects
				(font
					(size 0.7 0.7)
					(thickness 0.15)
				)
				(justify right top)
			)
		)
		(fp_text user "${REFERENCE}"
			(at -0.95 3.168 0)
			(layer "F.Fab")
			(effects
				(font
					(size 0.7 0.7)
					(thickness 0.15)
				)
				(justify right top)
			)
		)
		(fp_text user "License: Apache-2.0"
			(at -0.95 5.169 0)
			(layer "F.Fab")
			(effects
				(font
					(size 0.7 0.7)
					(thickness 0.15)
				)
				(justify right top)
			)
		)
		(pad "1" smd roundrect
			(at -0.48 0 180)
			(size 0.59 0.64)
			(layers "F.Cu" "F.Mask" "F.Paste")
			(roundrect_rratio 0.25)
			(net 11 "+1V8")
			(pintype "passive")
		)
		(pad "2" smd roundrect
			(at 0.48 0 180)
			(size 0.59 0.64)
			(layers "F.Cu" "F.Mask" "F.Paste")
			(roundrect_rratio 0.25)
			(net 331 "/SoM_IO/I2C0_SDA_1V8")
			(pintype "passive")
		)
	)
	(footprint "antmicro-footprints:R_0402_1005Metric"
		(layer "F.Cu")
		(at 141.1 135.05 180)
		(descr "Resistor SMD 0402")
		(tags "resistor SMD 0402")
		(property "Reference" "R59"
			(at -1.122484 -0.772697 0)
			(layer "F.SilkS")
			(effects
				(font
					(size 0.7 0.7)
					(thickness 0.15)
				)
				(justify right top)
			)
		)
		(property "Value" "R_470R_0402"
			(at -1.011843 1.772047 0)
			(layer "F.Fab")
			(effects
				(font
					(size 0.7 0.7)
					(thickness 0.15)
				)
				(justify right top)
			)
		)
		(property "Datasheet" "https://www.bourns.com/docs/product-datasheets/cr.pdf"
			(at 0 0 0)
			(layer "F.Fab")
			(hide yes)
			(effects
				(font
					(size 1.27 1.27)
					(thickness 0.15)
				)
			)
		)
		(property "Description" "SMD Chip Resistor, 470 ohm, ± 1%, 62.5 mW, 0402 [1005 Metric], Thick Film, General Purpose"
			(at 0 0 0)
			(layer "F.Fab")
			(hide yes)
			(effects
				(font
					(size 1.27 1.27)
					(thickness 0.15)
				)
			)
		)
		(property "MPN" "CR0402-FX-4700GLF"
			(at 0 0 180)
			(unlocked yes)
			(layer "F.Fab")
			(hide yes)
			(effects
				(font
					(size 1 1)
					(thickness 0.15)
				)
			)
		)
		(property "Manufacturer" "Bourns"
			(at 0 0 180)
			(unlocked yes)
			(layer "F.Fab")
			(hide yes)
			(effects
				(font
					(size 1 1)
					(thickness 0.15)
				)
			)
		)
		(property "License" "Apache-2.0"
			(at 0 0 180)
			(unlocked yes)
			(layer "F.Fab")
			(hide yes)
			(effects
				(font
					(size 1 1)
					(thickness 0.15)
				)
			)
		)
		(property "Author" "Antmicro"
			(at 0 0 180)
			(unlocked yes)
			(layer "F.Fab")
			(hide yes)
			(effects
				(font
					(size 1 1)
					(thickness 0.15)
				)
			)
		)
		(property "Val" "470R"
			(at 0 0 180)
			(unlocked yes)
			(layer "F.Fab")
			(hide yes)
			(effects
				(font
					(size 1 1)
					(thickness 0.15)
				)
			)
		)
		(property "Tolerance" "1%"
			(at 0 0 180)
			(unlocked yes)
			(layer "F.Fab")
			(hide yes)
			(effects
				(font
					(size 1 1)
					(thickness 0.15)
				)
			)
		)
		(sheetname "/SoM_Power/")
		(sheetfile "som_power.kicad_sch")
		(attr smd)
		(fp_rect
			(start -0.925 -0.47)
			(end 0.925 0.47)
			(stroke
				(width 0.05)
				(type default)
			)
			(fill no)
			(layer "F.CrtYd")
		)
		(fp_rect
			(start -0.5 -0.25)
			(end 0.5 0.25)
			(stroke
				(width 0.15)
				(type solid)
			)
			(fill no)
			(layer "F.Fab")
		)
		(fp_text user "License: Apache-2.0"
			(at -0.95 5.169 0)
			(layer "F.Fab")
			(effects
				(font
					(size 0.7 0.7)
					(thickness 0.15)
				)
				(justify right top)
			)
		)
		(fp_text user "${REFERENCE}"
			(at -0.95 3.168 0)
			(layer "F.Fab")
			(effects
				(font
					(size 0.7 0.7)
					(thickness 0.15)
				)
				(justify right top)
			)
		)
		(fp_text user "Author: Antmicro"
			(at -0.95 4.169 0)
			(layer "F.Fab")
			(effects
				(font
					(size 0.7 0.7)
					(thickness 0.15)
				)
				(justify right top)
			)
		)
		(pad "1" smd roundrect
			(at -0.48 0 180)
			(size 0.59 0.64)
			(layers "F.Cu" "F.Mask" "F.Paste")
			(roundrect_rratio 0.25)
			(net 886 "Net-(Q11-D)")
			(pintype "passive")
		)
		(pad "2" smd roundrect
			(at 0.48 0 180)
			(size 0.59 0.64)
			(layers "F.Cu" "F.Mask" "F.Paste")
			(roundrect_rratio 0.25)
			(net 2 "+3V3")
			(pintype "passive")
		)
	)
	(footprint "antmicro-footprints:C_0805_2012Metric"
		(layer "F.Cu")
		(at 169.53 73.32 -90)
		(descr "Capacitor SMD 0805")
		(tags "capacitor SMD 0805")
		(property "Reference" "C293"
			(at 1.78449 -1.468678 90)
			(layer "F.SilkS")
			(effects
				(font
					(size 0.7 0.7)
					(thickness 0.15)
				)
				(justify right top)
			)
		)
		(property "Value" "C_22u_25V_0805"
			(at -2.055717 1.963152 90)
			(layer "F.Fab")
			(effects
				(font
					(size 0.7 0.7)
					(thickness 0.15)
				)
				(justify right top)
			)
		)
		(property "Datasheet" "https://product.samsungsem.com/mlcc/CL21A226MAYNNN.do"
			(at 0 0 90)
			(layer "F.Fab")
			(hide yes)
			(effects
				(font
					(size 1.27 1.27)
					(thickness 0.15)
				)
			)
		)
		(property "Description" "SMT Multilayer Ceramic Capacitor, 22uF, +/-20%, 25V, X5R, 0805 [2012 Metric]"
			(at 0 0 90)
			(layer "F.Fab")
			(hide yes)
			(effects
				(font
					(size 1.27 1.27)
					(thickness 0.15)
				)
			)
		)
		(property "MPN" "CL21A226MAYNNNE"
			(at 0 0 270)
			(unlocked yes)
			(layer "F.Fab")
			(hide yes)
			(effects
				(font
					(size 1 1)
					(thickness 0.15)
				)
			)
		)
		(property "Manufacturer" "Samsung Electro-Mechanics"
			(at 0 0 270)
			(unlocked yes)
			(layer "F.Fab")
			(hide yes)
			(effects
				(font
					(size 1 1)
					(thickness 0.15)
				)
			)
		)
		(property "License" "Apache-2.0"
			(at 0 0 270)
			(unlocked yes)
			(layer "F.Fab")
			(hide yes)
			(effects
				(font
					(size 1 1)
					(thickness 0.15)
				)
			)
		)
		(property "Author" "Antmicro"
			(at 0 0 270)
			(unlocked yes)
			(layer "F.Fab")
			(hide yes)
			(effects
				(font
					(size 1 1)
					(thickness 0.15)
				)
			)
		)
		(property "Val" "22u"
			(at 0 0 270)
			(unlocked yes)
			(layer "F.Fab")
			(hide yes)
			(effects
				(font
					(size 1 1)
					(thickness 0.15)
				)
			)
		)
		(property "Voltage" "25V"
			(at 0 0 270)
			(unlocked yes)
			(layer "F.Fab")
			(hide yes)
			(effects
				(font
					(size 1 1)
					(thickness 0.15)
				)
			)
		)
		(property "Dielectric" "X5R"
			(at 0 0 270)
			(unlocked yes)
			(layer "F.Fab")
			(hide yes)
			(effects
				(font
					(size 1 1)
					(thickness 0.15)
				)
			)
		)
		(property "Public" "False"
			(at 0 0 270)
			(unlocked yes)
			(layer "F.Fab")
			(hide yes)
			(effects
				(font
					(size 1 1)
					(thickness 0.15)
				)
			)
		)
		(component_classes
			(class "DCDC_20V")
		)
		(sheetname "/DCDC/")
		(sheetfile "dcdc.kicad_sch")
		(attr smd)
		(fp_line
			(start -0.3 0.7)
			(end 0.3 0.7)
			(stroke
				(width 0.15)
				(type solid)
			)
			(layer "F.SilkS")
		)
		(fp_line
			(start -0.3 -0.7)
			(end 0.3 -0.7)
			(stroke
				(width 0.15)
				(type solid)
			)
			(layer "F.SilkS")
		)
		(fp_rect
			(start 1.95 -0.9)
			(end -1.95 0.9)
			(stroke
				(width 0.05)
				(type default)
			)
			(fill no)
			(layer "F.CrtYd")
		)
		(fp_rect
			(start -0.95 -0.675)
			(end 0.95 0.675)
			(stroke
				(width 0.15)
				(type solid)
			)
			(fill no)
			(layer "F.Fab")
		)
		(fp_text user "License: Apache-2.0"
			(at -1.9 4.947 90)
			(layer "F.Fab")
			(effects
				(font
					(size 0.7 0.7)
					(thickness 0.15)
				)
				(justify right top)
			)
		)
		(fp_text user "Author: Antmicro"
			(at -1.9 5.947 90)
			(layer "F.Fab")
			(effects
				(font
					(size 0.7 0.7)
					(thickness 0.15)
				)
				(justify right top)
			)
		)
		(fp_text user "${REFERENCE}"
			(at -1.9 3.947 90)
			(layer "F.Fab")
			(effects
				(font
					(size 0.7 0.7)
					(thickness 0.15)
				)
				(justify right top)
			)
		)
		(pad "1" smd roundrect
			(at -1.1 0 270)
			(size 1.2 1.3)
			(layers "F.Cu" "F.Mask" "F.Paste")
			(roundrect_rratio 0.25)
			(net 1 "GND")
			(pintype "passive")
		)
		(pad "2" smd roundrect
			(at 1.1 0 270)
			(size 1.2 1.3)
			(layers "F.Cu" "F.Mask" "F.Paste")
			(roundrect_rratio 0.25)
			(net 1105 "/DCDC/20V_OUT")
			(pintype "passive")
		)
	)
	(footprint "antmicro-footprints:C_0402_1005Metric"
		(layer "F.Cu")
		(at 219.564132 91.36)
		(descr "Capacitor SMD 0402")
		(tags "capacitor SMD 0402")
		(property "Reference" "C144"
			(at -1.71 -0.708 0)
			(layer "F.SilkS")
			(effects
				(font
					(size 0.7 0.7)
					(thickness 0.15)
				)
				(justify left bottom)
			)
		)
		(property "Value" "C_100n_0402"
			(at -1.022927 2.155213 0)
			(layer "F.Fab")
			(effects
				(font
					(size 0.7 0.7)
					(thickness 0.15)
				)
				(justify left bottom)
			)
		)
		(property "Datasheet" "https://www.murata.com/products/productdetail?partno=GRM155R61H104KE14%23"
			(at 0 0 0)
			(layer "F.Fab")
			(hide yes)
			(effects
				(font
					(size 1.27 1.27)
					(thickness 0.15)
				)
			)
		)
		(property "Description" "SMD Multilayer Ceramic Capacitor, 0.1 µF, 50 V, 0402 [1005 Metric], ± 10%, X5R, GRM Series"
			(at 0 0 0)
			(layer "F.Fab")
			(hide yes)
			(effects
				(font
					(size 1.27 1.27)
					(thickness 0.15)
				)
			)
		)
		(property "Manufacturer" "Murata"
			(at 0 0 0)
			(unlocked yes)
			(layer "F.Fab")
			(hide yes)
			(effects
				(font
					(size 1 1)
					(thickness 0.15)
				)
			)
		)
		(property "MPN" "GRM155R61H104KE14D"
			(at 0 0 0)
			(unlocked yes)
			(layer "F.Fab")
			(hide yes)
			(effects
				(font
					(size 1 1)
					(thickness 0.15)
				)
			)
		)
		(property "Val" "100n"
			(at 0 0 0)
			(unlocked yes)
			(layer "F.Fab")
			(hide yes)
			(effects
				(font
					(size 1 1)
					(thickness 0.15)
				)
			)
		)
		(property "License" "Apache-2.0"
			(at 0 0 0)
			(unlocked yes)
			(layer "F.Fab")
			(hide yes)
			(effects
				(font
					(size 1 1)
					(thickness 0.15)
				)
			)
		)
		(property "Author" "Antmicro"
			(at 0 0 0)
			(unlocked yes)
			(layer "F.Fab")
			(hide yes)
			(effects
				(font
					(size 1 1)
					(thickness 0.15)
				)
			)
		)
		(property "Voltage" "50V"
			(at 0 0 0)
			(unlocked yes)
			(layer "F.Fab")
			(hide yes)
			(effects
				(font
					(size 1 1)
					(thickness 0.15)
				)
			)
		)
		(property "Dielectric" "X5R"
			(at 0 0 0)
			(unlocked yes)
			(layer "F.Fab")
			(hide yes)
			(effects
				(font
					(size 1 1)
					(thickness 0.15)
				)
			)
		)
		(sheetname "/USB DP Alt mode/")
		(sheetfile "usb_dp.kicad_sch")
		(attr smd)
		(fp_rect
			(start -0.925 -0.47)
			(end 0.925 0.47)
			(stroke
				(width 0.05)
				(type default)
			)
			(fill no)
			(layer "F.CrtYd")
		)
		(fp_line
			(start -0.494 -0.25)
			(end 0.504 -0.25)
			(stroke
				(width 0.15)
				(type solid)
			)
			(layer "F.Fab")
		)
		(fp_line
			(start -0.494 0.248)
			(end -0.494 -0.25)
			(stroke
				(width 0.15)
				(type solid)
			)
			(layer "F.Fab")
		)
		(fp_line
			(start 0.504 -0.25)
			(end 0.504 0.248)
			(stroke
				(width 0.15)
				(type solid)
			)
			(layer "F.Fab")
		)
		(fp_line
			(start 0.504 0.248)
			(end -0.494 0.248)
			(stroke
				(width 0.15)
				(type solid)
			)
			(layer "F.Fab")
		)
		(fp_text user "Author: Antmicro"
			(at -0.939 3.399 0)
			(layer "F.Fab")
			(effects
				(font
					(size 0.7 0.7)
					(thickness 0.15)
				)
				(justify left bottom)
			)
		)
		(fp_text user "${REFERENCE}"
			(at -0.939 4.599 0)
			(layer "F.Fab")
			(effects
				(font
					(size 0.7 0.7)
					(thickness 0.15)
				)
				(justify left bottom)
			)
		)
		(fp_text user "License: Apache-2.0"
			(at -0.939 5.799 0)
			(layer "F.Fab")
			(effects
				(font
					(size 0.7 0.7)
					(thickness 0.15)
				)
				(justify left bottom)
			)
		)
		(pad "1" smd roundrect
			(at -0.48 0)
			(size 0.59 0.64)
			(layers "F.Cu" "F.Mask" "F.Paste")
			(roundrect_rratio 0.25)
			(net 370 "/USB DP Alt mode/USBC1_TX1_N")
			(pintype "passive")
		)
		(pad "2" smd roundrect
			(at 0.48 0)
			(size 0.59 0.64)
			(layers "F.Cu" "F.Mask" "F.Paste")
			(roundrect_rratio 0.25)
			(net 361 "/USB DP Alt mode/USBC1_CONN_TX1_N")
			(pintype "passive")
		)
	)
	(footprint "antmicro-footprints:R_0402_1005Metric"
		(layer "F.Cu")
		(at 66.75 85.88 -90)
		(descr "Resistor SMD 0402")
		(tags "resistor SMD 0402")
		(property "Reference" "R172"
			(at -3.7 0.45 90)
			(layer "F.SilkS")
			(effects
				(font
					(size 0.7 0.7)
					(thickness 0.15)
				)
				(justify right top)
			)
		)
		(property "Value" "R_4k7_0402"
			(at -1.011843 1.772047 90)
			(layer "F.Fab")
			(effects
				(font
					(size 0.7 0.7)
					(thickness 0.15)
				)
				(justify right top)
			)
		)
		(property "Datasheet" "https://www.bourns.com/docs/product-datasheets/cr.pdf"
			(at 0 0 90)
			(layer "F.Fab")
			(hide yes)
			(effects
				(font
					(size 1.27 1.27)
					(thickness 0.15)
				)
			)
		)
		(property "Description" "SMD Chip Resistor, 4.7 kohm, ± 1%, 62.5 mW, 0402 [1005 Metric], Thick Film, General Purpose"
			(at 0 0 90)
			(layer "F.Fab")
			(hide yes)
			(effects
				(font
					(size 1.27 1.27)
					(thickness 0.15)
				)
			)
		)
		(property "Manufacturer" "Bourns"
			(at 0 0 270)
			(unlocked yes)
			(layer "F.Fab")
			(hide yes)
			(effects
				(font
					(size 1 1)
					(thickness 0.15)
				)
			)
		)
		(property "MPN" "CR0402-FX-4701GLF"
			(at 0 0 270)
			(unlocked yes)
			(layer "F.Fab")
			(hide yes)
			(effects
				(font
					(size 1 1)
					(thickness 0.15)
				)
			)
		)
		(property "Val" "4k7"
			(at 0 0 270)
			(unlocked yes)
			(layer "F.Fab")
			(hide yes)
			(effects
				(font
					(size 1 1)
					(thickness 0.15)
				)
			)
		)
		(property "License" "Apache-2.0"
			(at 0 0 270)
			(unlocked yes)
			(layer "F.Fab")
			(hide yes)
			(effects
				(font
					(size 1 1)
					(thickness 0.15)
				)
			)
		)
		(property "Author" "Antmicro"
			(at 0 0 270)
			(unlocked yes)
			(layer "F.Fab")
			(hide yes)
			(effects
				(font
					(size 1 1)
					(thickness 0.15)
				)
			)
		)
		(property "Tolerance" "1%"
			(at 0 0 270)
			(unlocked yes)
			(layer "F.Fab")
			(hide yes)
			(effects
				(font
					(size 1 1)
					(thickness 0.15)
				)
			)
		)
		(sheetname "/CSI/")
		(sheetfile "csi.kicad_sch")
		(attr smd)
		(fp_rect
			(start -0.925 -0.47)
			(end 0.925 0.47)
			(stroke
				(width 0.05)
				(type default)
			)
			(fill no)
			(layer "F.CrtYd")
		)
		(fp_rect
			(start -0.5 -0.25)
			(end 0.5 0.25)
			(stroke
				(width 0.15)
				(type solid)
			)
			(fill no)
			(layer "F.Fab")
		)
		(fp_text user "${REFERENCE}"
			(at -0.95 3.168 90)
			(layer "F.Fab")
			(effects
				(font
					(size 0.7 0.7)
					(thickness 0.15)
				)
				(justify right top)
			)
		)
		(fp_text user "License: Apache-2.0"
			(at -0.95 5.169 90)
			(layer "F.Fab")
			(effects
				(font
					(size 0.7 0.7)
					(thickness 0.15)
				)
				(justify right top)
			)
		)
		(fp_text user "Author: Antmicro"
			(at -0.95 4.169 90)
			(layer "F.Fab")
			(effects
				(font
					(size 0.7 0.7)
					(thickness 0.15)
				)
				(justify right top)
			)
		)
		(pad "1" smd roundrect
			(at -0.48 0 270)
			(size 0.59 0.64)
			(layers "F.Cu" "F.Mask" "F.Paste")
			(roundrect_rratio 0.25)
			(net 1 "GND")
			(pintype "passive")
		)
		(pad "2" smd roundrect
			(at 0.48 0 270)
			(size 0.59 0.64)
			(layers "F.Cu" "F.Mask" "F.Paste")
			(roundrect_rratio 0.25)
			(net 995 "/CSI/CSIA_5V_ISET")
			(pintype "passive")
		)
	)
	(footprint "antmicro-footprints:R_0402_1005Metric"
		(layer "F.Cu")
		(at 156.72 114.2 180)
		(descr "Resistor SMD 0402")
		(tags "resistor SMD 0402")
		(property "Reference" "R361"
			(at -3.68 0.4 0)
			(layer "F.SilkS")
			(effects
				(font
					(size 0.7 0.7)
					(thickness 0.15)
				)
				(justify right top)
			)
		)
		(property "Value" "R_2k2_0402"
			(at -1.011843 1.772047 0)
			(layer "F.Fab")
			(effects
				(font
					(size 0.7 0.7)
					(thickness 0.15)
				)
				(justify right top)
			)
		)
		(property "Datasheet" "https://www.bourns.com/docs/product-datasheets/cr.pdf"
			(at 0 0 0)
			(layer "F.Fab")
			(hide yes)
			(effects
				(font
					(size 1.27 1.27)
					(thickness 0.15)
				)
			)
		)
		(property "Description" "SMD Chip Resistor, 2.2 kohm, ± 1%, 62.5 mW, 0402 [1005 Metric], Thick Film, General Purpose"
			(at 0 0 0)
			(layer "F.Fab")
			(hide yes)
			(effects
				(font
					(size 1.27 1.27)
					(thickness 0.15)
				)
			)
		)
		(property "MPN" "CR0402-FX-2201GLF"
			(at 0 0 180)
			(unlocked yes)
			(layer "F.Fab")
			(hide yes)
			(effects
				(font
					(size 1 1)
					(thickness 0.15)
				)
			)
		)
		(property "Manufacturer" "Bourns"
			(at 0 0 180)
			(unlocked yes)
			(layer "F.Fab")
			(hide yes)
			(effects
				(font
					(size 1 1)
					(thickness 0.15)
				)
			)
		)
		(property "License" "Apache-2.0"
			(at 0 0 180)
			(unlocked yes)
			(layer "F.Fab")
			(hide yes)
			(effects
				(font
					(size 1 1)
					(thickness 0.15)
				)
			)
		)
		(property "Author" "Antmicro"
			(at 0 0 180)
			(unlocked yes)
			(layer "F.Fab")
			(hide yes)
			(effects
				(font
					(size 1 1)
					(thickness 0.15)
				)
			)
		)
		(property "Val" "2k2"
			(at 0 0 180)
			(unlocked yes)
			(layer "F.Fab")
			(hide yes)
			(effects
				(font
					(size 1 1)
					(thickness 0.15)
				)
			)
		)
		(property "Tolerance" "1%"
			(at 0 0 180)
			(unlocked yes)
			(layer "F.Fab")
			(hide yes)
			(effects
				(font
					(size 1 1)
					(thickness 0.15)
				)
			)
		)
		(sheetname "/SoM_IO/")
		(sheetfile "som_io.kicad_sch")
		(attr smd)
		(fp_rect
			(start -0.925 -0.47)
			(end 0.925 0.47)
			(stroke
				(width 0.05)
				(type default)
			)
			(fill no)
			(layer "F.CrtYd")
		)
		(fp_rect
			(start -0.5 -0.25)
			(end 0.5 0.25)
			(stroke
				(width 0.15)
				(type solid)
			)
			(fill no)
			(layer "F.Fab")
		)
		(fp_text user "Author: Antmicro"
			(at -0.95 4.169 0)
			(layer "F.Fab")
			(effects
				(font
					(size 0.7 0.7)
					(thickness 0.15)
				)
				(justify right top)
			)
		)
		(fp_text user "License: Apache-2.0"
			(at -0.95 5.169 0)
			(layer "F.Fab")
			(effects
				(font
					(size 0.7 0.7)
					(thickness 0.15)
				)
				(justify right top)
			)
		)
		(fp_text user "${REFERENCE}"
			(at -0.95 3.168 0)
			(layer "F.Fab")
			(effects
				(font
					(size 0.7 0.7)
					(thickness 0.15)
				)
				(justify right top)
			)
		)
		(pad "1" smd roundrect
			(at -0.48 0 180)
			(size 0.59 0.64)
			(layers "F.Cu" "F.Mask" "F.Paste")
			(roundrect_rratio 0.25)
			(net 2 "+3V3")
			(pintype "passive")
		)
		(pad "2" smd roundrect
			(at 0.48 0 180)
			(size 0.59 0.64)
			(layers "F.Cu" "F.Mask" "F.Paste")
			(roundrect_rratio 0.25)
			(net 43 "/Peripherals/I2C_{CONN}.SDA")
			(pintype "passive")
		)
	)
	(footprint "antmicro-footprints:C_0805_2012Metric"
		(layer "F.Cu")
		(at 167.7 93.32 -90)
		(descr "Capacitor SMD 0805")
		(tags "capacitor SMD 0805")
		(property "Reference" "C300"
			(at 1.745 0.425 90)
			(layer "F.SilkS")
			(effects
				(font
					(size 0.7 0.7)
					(thickness 0.15)
				)
				(justify right top)
			)
		)
		(property "Value" "C_22u_25V_0805"
			(at -2.055717 1.963152 90)
			(layer "F.Fab")
			(effects
				(font
					(size 0.7 0.7)
					(thickness 0.15)
				)
				(justify right top)
			)
		)
		(property "Datasheet" "https://product.samsungsem.com/mlcc/CL21A226MAYNNN.do"
			(at 0 0 90)
			(layer "F.Fab")
			(hide yes)
			(effects
				(font
					(size 1.27 1.27)
					(thickness 0.15)
				)
			)
		)
		(property "Description" "SMT Multilayer Ceramic Capacitor, 22uF, +/-20%, 25V, X5R, 0805 [2012 Metric]"
			(at 0 0 90)
			(layer "F.Fab")
			(hide yes)
			(effects
				(font
					(size 1.27 1.27)
					(thickness 0.15)
				)
			)
		)
		(property "MPN" "CL21A226MAYNNNE"
			(at 0 0 270)
			(unlocked yes)
			(layer "F.Fab")
			(hide yes)
			(effects
				(font
					(size 1 1)
					(thickness 0.15)
				)
			)
		)
		(property "Manufacturer" "Samsung Electro-Mechanics"
			(at 0 0 270)
			(unlocked yes)
			(layer "F.Fab")
			(hide yes)
			(effects
				(font
					(size 1 1)
					(thickness 0.15)
				)
			)
		)
		(property "License" "Apache-2.0"
			(at 0 0 270)
			(unlocked yes)
			(layer "F.Fab")
			(hide yes)
			(effects
				(font
					(size 1 1)
					(thickness 0.15)
				)
			)
		)
		(property "Author" "Antmicro"
			(at 0 0 270)
			(unlocked yes)
			(layer "F.Fab")
			(hide yes)
			(effects
				(font
					(size 1 1)
					(thickness 0.15)
				)
			)
		)
		(property "Val" "22u"
			(at 0 0 270)
			(unlocked yes)
			(layer "F.Fab")
			(hide yes)
			(effects
				(font
					(size 1 1)
					(thickness 0.15)
				)
			)
		)
		(property "Voltage" "25V"
			(at 0 0 270)
			(unlocked yes)
			(layer "F.Fab")
			(hide yes)
			(effects
				(font
					(size 1 1)
					(thickness 0.15)
				)
			)
		)
		(property "Dielectric" "X5R"
			(at 0 0 270)
			(unlocked yes)
			(layer "F.Fab")
			(hide yes)
			(effects
				(font
					(size 1 1)
					(thickness 0.15)
				)
			)
		)
		(property "Public" "False"
			(at 0 0 270)
			(unlocked yes)
			(layer "F.Fab")
			(hide yes)
			(effects
				(font
					(size 1 1)
					(thickness 0.15)
				)
			)
		)
		(component_classes
			(class "DCDC_SOM")
		)
		(sheetname "/DCDC/")
		(sheetfile "dcdc.kicad_sch")
		(attr smd)
		(fp_line
			(start -0.3 0.7)
			(end 0.3 0.7)
			(stroke
				(width 0.15)
				(type solid)
			)
			(layer "F.SilkS")
		)
		(fp_line
			(start -0.3 -0.7)
			(end 0.3 -0.7)
			(stroke
				(width 0.15)
				(type solid)
			)
			(layer "F.SilkS")
		)
		(fp_rect
			(start 1.95 -0.9)
			(end -1.95 0.9)
			(stroke
				(width 0.05)
				(type default)
			)
			(fill no)
			(layer "F.CrtYd")
		)
		(fp_rect
			(start -0.95 -0.675)
			(end 0.95 0.675)
			(stroke
				(width 0.15)
				(type solid)
			)
			(fill no)
			(layer "F.Fab")
		)
		(fp_text user "${REFERENCE}"
			(at -1.9 3.947 90)
			(layer "F.Fab")
			(effects
				(font
					(size 0.7 0.7)
					(thickness 0.15)
				)
				(justify right top)
			)
		)
		(fp_text user "Author: Antmicro"
			(at -1.9 5.947 90)
			(layer "F.Fab")
			(effects
				(font
					(size 0.7 0.7)
					(thickness 0.15)
				)
				(justify right top)
			)
		)
		(fp_text user "License: Apache-2.0"
			(at -1.9 4.947 90)
			(layer "F.Fab")
			(effects
				(font
					(size 0.7 0.7)
					(thickness 0.15)
				)
				(justify right top)
			)
		)
		(pad "1" smd roundrect
			(at -1.1 0 270)
			(size 1.2 1.3)
			(layers "F.Cu" "F.Mask" "F.Paste")
			(roundrect_rratio 0.25)
			(net 1 "GND")
			(pintype "passive")
		)
		(pad "2" smd roundrect
			(at 1.1 0 270)
			(size 1.2 1.3)
			(layers "F.Cu" "F.Mask" "F.Paste")
			(roundrect_rratio 0.25)
			(net 903 "/DCDC/16V_OUT")
			(pintype "passive")
		)
	)
	(footprint "antmicro-footprints:C_0402_1005Metric"
		(layer "F.Cu")
		(at 203.6 133.7 90)
		(descr "Capacitor SMD 0402")
		(tags "capacitor SMD 0402")
		(property "Reference" "C86"
			(at -1.2 -0.5 90)
			(layer "F.SilkS")
			(effects
				(font
					(size 0.7 0.7)
					(thickness 0.15)
				)
				(justify left bottom)
			)
		)
		(property "Value" "C_100n_0402"
			(at -1.022927 2.155213 90)
			(layer "F.Fab")
			(effects
				(font
					(size 0.7 0.7)
					(thickness 0.15)
				)
				(justify left bottom)
			)
		)
		(property "Datasheet" "https://www.murata.com/products/productdetail?partno=GRM155R61H104KE14%23"
			(at 0 0 90)
			(layer "F.Fab")
			(hide yes)
			(effects
				(font
					(size 1.27 1.27)
					(thickness 0.15)
				)
			)
		)
		(property "Description" "SMD Multilayer Ceramic Capacitor, 0.1 µF, 50 V, 0402 [1005 Metric], ± 10%, X5R, GRM Series"
			(at 0 0 90)
			(layer "F.Fab")
			(hide yes)
			(effects
				(font
					(size 1.27 1.27)
					(thickness 0.15)
				)
			)
		)
		(property "MPN" "GRM155R61H104KE14D"
			(at 0 0 90)
			(unlocked yes)
			(layer "F.Fab")
			(hide yes)
			(effects
				(font
					(size 1 1)
					(thickness 0.15)
				)
			)
		)
		(property "Val" "100n"
			(at 0 0 90)
			(unlocked yes)
			(layer "F.Fab")
			(hide yes)
			(effects
				(font
					(size 1 1)
					(thickness 0.15)
				)
			)
		)
		(property "Voltage" "50V"
			(at 0 0 90)
			(unlocked yes)
			(layer "F.Fab")
			(hide yes)
			(effects
				(font
					(size 1 1)
					(thickness 0.15)
				)
			)
		)
		(property "Dielectric" "X5R"
			(at 0 0 90)
			(unlocked yes)
			(layer "F.Fab")
			(hide yes)
			(effects
				(font
					(size 1 1)
					(thickness 0.15)
				)
			)
		)
		(property "Manufacturer" "Murata"
			(at 0 0 90)
			(unlocked yes)
			(layer "F.Fab")
			(hide yes)
			(effects
				(font
					(size 1 1)
					(thickness 0.15)
				)
			)
		)
		(property "License" "Apache-2.0"
			(at 0 0 90)
			(unlocked yes)
			(layer "F.Fab")
			(hide yes)
			(effects
				(font
					(size 1 1)
					(thickness 0.15)
				)
			)
		)
		(property "Author" "Antmicro"
			(at 0 0 90)
			(unlocked yes)
			(layer "F.Fab")
			(hide yes)
			(effects
				(font
					(size 1 1)
					(thickness 0.15)
				)
			)
		)
		(sheetname "/USB Hub/")
		(sheetfile "usb_hub.kicad_sch")
		(attr smd)
		(fp_rect
			(start -0.925 -0.47)
			(end 0.925 0.47)
			(stroke
				(width 0.05)
				(type default)
			)
			(fill no)
			(layer "F.CrtYd")
		)
		(fp_line
			(start 0.504 -0.25)
			(end 0.504 0.248)
			(stroke
				(width 0.15)
				(type solid)
			)
			(layer "F.Fab")
		)
		(fp_line
			(start -0.494 -0.25)
			(end 0.504 -0.25)
			(stroke
				(width 0.15)
				(type solid)
			)
			(layer "F.Fab")
		)
		(fp_line
			(start 0.504 0.248)
			(end -0.494 0.248)
			(stroke
				(width 0.15)
				(type solid)
			)
			(layer "F.Fab")
		)
		(fp_line
			(start -0.494 0.248)
			(end -0.494 -0.25)
			(stroke
				(width 0.15)
				(type solid)
			)
			(layer "F.Fab")
		)
		(fp_text user "${REFERENCE}"
			(at -0.939 4.599 90)
			(layer "F.Fab")
			(effects
				(font
					(size 0.7 0.7)
					(thickness 0.15)
				)
				(justify left bottom)
			)
		)
		(fp_text user "License: Apache-2.0"
			(at -0.939 5.799 90)
			(layer "F.Fab")
			(effects
				(font
					(size 0.7 0.7)
					(thickness 0.15)
				)
				(justify left bottom)
			)
		)
		(fp_text user "Author: Antmicro"
			(at -0.939 3.399 90)
			(layer "F.Fab")
			(effects
				(font
					(size 0.7 0.7)
					(thickness 0.15)
				)
				(justify left bottom)
			)
		)
		(pad "1" smd roundrect
			(at -0.48 0 90)
			(size 0.59 0.64)
			(layers "F.Cu" "F.Mask" "F.Paste")
			(roundrect_rratio 0.25)
			(net 1 "GND")
			(pintype "passive")
		)
		(pad "2" smd roundrect
			(at 0.48 0 90)
			(size 0.59 0.64)
			(layers "F.Cu" "F.Mask" "F.Paste")
			(roundrect_rratio 0.25)
			(net 282 "+1V15")
			(pintype "passive")
		)
	)
	(footprint "antmicro-footprints:C_0402_1005Metric"
		(layer "F.Cu")
		(at 211.2 78)
		(descr "Capacitor SMD 0402")
		(tags "capacitor SMD 0402")
		(property "Reference" "C234"
			(at 1 0.5 0)
			(layer "F.SilkS")
			(effects
				(font
					(size 0.7 0.7)
					(thickness 0.15)
				)
				(justify left bottom)
			)
		)
		(property "Value" "C_100n_0402"
			(at -1.022927 2.155213 0)
			(layer "F.Fab")
			(effects
				(font
					(size 0.7 0.7)
					(thickness 0.15)
				)
				(justify left bottom)
			)
		)
		(property "Datasheet" "https://www.murata.com/products/productdetail?partno=GRM155R61H104KE14%23"
			(at 0 0 0)
			(layer "F.Fab")
			(hide yes)
			(effects
				(font
					(size 1.27 1.27)
					(thickness 0.15)
				)
			)
		)
		(property "Description" "SMD Multilayer Ceramic Capacitor, 0.1 µF, 50 V, 0402 [1005 Metric], ± 10%, X5R, GRM Series"
			(at 0 0 0)
			(layer "F.Fab")
			(hide yes)
			(effects
				(font
					(size 1.27 1.27)
					(thickness 0.15)
				)
			)
		)
		(property "MPN" "GRM155R61H104KE14D"
			(at 0 0 0)
			(unlocked yes)
			(layer "F.Fab")
			(hide yes)
			(effects
				(font
					(size 1 1)
					(thickness 0.15)
				)
			)
		)
		(property "Manufacturer" "Murata"
			(at 0 0 0)
			(unlocked yes)
			(layer "F.Fab")
			(hide yes)
			(effects
				(font
					(size 1 1)
					(thickness 0.15)
				)
			)
		)
		(property "Val" "100n"
			(at 0 0 0)
			(unlocked yes)
			(layer "F.Fab")
			(hide yes)
			(effects
				(font
					(size 1 1)
					(thickness 0.15)
				)
			)
		)
		(property "License" "Apache-2.0"
			(at 0 0 0)
			(unlocked yes)
			(layer "F.Fab")
			(hide yes)
			(effects
				(font
					(size 1 1)
					(thickness 0.15)
				)
			)
		)
		(property "Author" "Antmicro"
			(at 0 0 0)
			(unlocked yes)
			(layer "F.Fab")
			(hide yes)
			(effects
				(font
					(size 1 1)
					(thickness 0.15)
				)
			)
		)
		(property "Voltage" "50V"
			(at 0 0 0)
			(unlocked yes)
			(layer "F.Fab")
			(hide yes)
			(effects
				(font
					(size 1 1)
					(thickness 0.15)
				)
			)
		)
		(property "Dielectric" "X5R"
			(at 0 0 0)
			(unlocked yes)
			(layer "F.Fab")
			(hide yes)
			(effects
				(font
					(size 1 1)
					(thickness 0.15)
				)
			)
		)
		(sheetname "/USB Debug, PD/")
		(sheetfile "usb_debug_pd.kicad_sch")
		(attr smd)
		(fp_poly
			(pts
				(xy -0.925 -0.47) (xy -0.925 0.47) (xy 0.925 0.47) (xy 0.925 -0.47)
			)
			(stroke
				(width 0.05)
				(type default)
			)
			(fill no)
			(layer "F.CrtYd")
		)
		(fp_line
			(start -0.494 -0.25)
			(end 0.504 -0.25)
			(stroke
				(width 0.15)
				(type solid)
			)
			(layer "F.Fab")
		)
		(fp_line
			(start -0.494 0.248)
			(end -0.494 -0.25)
			(stroke
				(width 0.15)
				(type solid)
			)
			(layer "F.Fab")
		)
		(fp_line
			(start 0.504 -0.25)
			(end 0.504 0.248)
			(stroke
				(width 0.15)
				(type solid)
			)
			(layer "F.Fab")
		)
		(fp_line
			(start 0.504 0.248)
			(end -0.494 0.248)
			(stroke
				(width 0.15)
				(type solid)
			)
			(layer "F.Fab")
		)
		(fp_text user "${REFERENCE}"
			(at -0.939 4.599 0)
			(layer "F.Fab")
			(effects
				(font
					(size 0.7 0.7)
					(thickness 0.15)
				)
				(justify left bottom)
			)
		)
		(fp_text user "Author: Antmicro"
			(at -0.939 3.399 0)
			(layer "F.Fab")
			(effects
				(font
					(size 0.7 0.7)
					(thickness 0.15)
				)
				(justify left bottom)
			)
		)
		(fp_text user "License: Apache-2.0"
			(at -0.939 5.799 0)
			(layer "F.Fab")
			(effects
				(font
					(size 0.7 0.7)
					(thickness 0.15)
				)
				(justify left bottom)
			)
		)
		(pad "1" smd roundrect
			(at -0.48 0)
			(size 0.59 0.64)
			(layers "F.Cu" "F.Mask" "F.Paste")
			(roundrect_rratio 0.25)
			(net 334 "/USB Debug, PD/FTDI_3V3")
			(pintype "passive")
		)
		(pad "2" smd roundrect
			(at 0.48 0)
			(size 0.59 0.64)
			(layers "F.Cu" "F.Mask" "F.Paste")
			(roundrect_rratio 0.25)
			(net 1 "GND")
			(pintype "passive")
		)
	)
	(footprint "antmicro-footprints:C_0402_1005Metric"
		(layer "F.Cu")
		(at 178.2 87.42)
		(descr "Capacitor SMD 0402")
		(tags "capacitor SMD 0402")
		(property "Reference" "C246"
			(at -1.765532 -1.325 0)
			(layer "F.SilkS")
			(effects
				(font
					(size 0.7 0.7)
					(thickness 0.15)
				)
				(justify left bottom)
			)
		)
		(property "Value" "C_100n_0402"
			(at -1.022927 2.155213 0)
			(layer "F.Fab")
			(effects
				(font
					(size 0.7 0.7)
					(thickness 0.15)
				)
				(justify left bottom)
			)
		)
		(property "Datasheet" "https://www.murata.com/products/productdetail?partno=GRM155R61H104KE14%23"
			(at 0 0 0)
			(layer "F.Fab")
			(hide yes)
			(effects
				(font
					(size 1.27 1.27)
					(thickness 0.15)
				)
			)
		)
		(property "Description" "SMD Multilayer Ceramic Capacitor, 0.1 µF, 50 V, 0402 [1005 Metric], ± 10%, X5R, GRM Series"
			(at 0 0 0)
			(layer "F.Fab")
			(hide yes)
			(effects
				(font
					(size 1.27 1.27)
					(thickness 0.15)
				)
			)
		)
		(property "Manufacturer" "Murata"
			(at 0 0 0)
			(unlocked yes)
			(layer "F.Fab")
			(hide yes)
			(effects
				(font
					(size 1 1)
					(thickness 0.15)
				)
			)
		)
		(property "MPN" "GRM155R61H104KE14D"
			(at 0 0 0)
			(unlocked yes)
			(layer "F.Fab")
			(hide yes)
			(effects
				(font
					(size 1 1)
					(thickness 0.15)
				)
			)
		)
		(property "Val" "100n"
			(at 0 0 0)
			(unlocked yes)
			(layer "F.Fab")
			(hide yes)
			(effects
				(font
					(size 1 1)
					(thickness 0.15)
				)
			)
		)
		(property "License" "Apache-2.0"
			(at 0 0 0)
			(unlocked yes)
			(layer "F.Fab")
			(hide yes)
			(effects
				(font
					(size 1 1)
					(thickness 0.15)
				)
			)
		)
		(property "Author" "Antmicro"
			(at 0 0 0)
			(unlocked yes)
			(layer "F.Fab")
			(hide yes)
			(effects
				(font
					(size 1 1)
					(thickness 0.15)
				)
			)
		)
		(property "Voltage" "50V"
			(at 0 0 0)
			(unlocked yes)
			(layer "F.Fab")
			(hide yes)
			(effects
				(font
					(size 1 1)
					(thickness 0.15)
				)
			)
		)
		(property "Dielectric" "X5R"
			(at 0 0 0)
			(unlocked yes)
			(layer "F.Fab")
			(hide yes)
			(effects
				(font
					(size 1 1)
					(thickness 0.15)
				)
			)
		)
		(component_classes
			(class "DCDC_SOM")
		)
		(sheetname "/DCDC/")
		(sheetfile "dcdc.kicad_sch")
		(attr smd)
		(fp_rect
			(start -0.925 -0.47)
			(end 0.925 0.47)
			(stroke
				(width 0.05)
				(type default)
			)
			(fill no)
			(layer "F.CrtYd")
		)
		(fp_line
			(start -0.494 -0.25)
			(end 0.504 -0.25)
			(stroke
				(width 0.15)
				(type solid)
			)
			(layer "F.Fab")
		)
		(fp_line
			(start -0.494 0.248)
			(end -0.494 -0.25)
			(stroke
				(width 0.15)
				(type solid)
			)
			(layer "F.Fab")
		)
		(fp_line
			(start 0.504 -0.25)
			(end 0.504 0.248)
			(stroke
				(width 0.15)
				(type solid)
			)
			(layer "F.Fab")
		)
		(fp_line
			(start 0.504 0.248)
			(end -0.494 0.248)
			(stroke
				(width 0.15)
				(type solid)
			)
			(layer "F.Fab")
		)
		(fp_text user "${REFERENCE}"
			(at -0.939 4.599 0)
			(layer "F.Fab")
			(effects
				(font
					(size 0.7 0.7)
					(thickness 0.15)
				)
				(justify left bottom)
			)
		)
		(fp_text user "License: Apache-2.0"
			(at -0.939 5.799 0)
			(layer "F.Fab")
			(effects
				(font
					(size 0.7 0.7)
					(thickness 0.15)
				)
				(justify left bottom)
			)
		)
		(fp_text user "Author: Antmicro"
			(at -0.939 3.399 0)
			(layer "F.Fab")
			(effects
				(font
					(size 0.7 0.7)
					(thickness 0.15)
				)
				(justify left bottom)
			)
		)
		(pad "1" smd roundrect
			(at -0.48 0)
			(size 0.59 0.64)
			(layers "F.Cu" "F.Mask" "F.Paste")
			(roundrect_rratio 0.25)
			(net 902 "/DCDC/16V_PHASE")
			(pintype "passive")
		)
		(pad "2" smd roundrect
			(at 0.48 0)
			(size 0.59 0.64)
			(layers "F.Cu" "F.Mask" "F.Paste")
			(roundrect_rratio 0.25)
			(net 901 "/DCDC/16V_BOOT")
			(pintype "passive")
		)
	)
	(footprint "antmicro-footprints:R_0402_1005Metric"
		(layer "F.Cu")
		(at 168.81 63.49 90)
		(descr "Resistor SMD 0402")
		(tags "resistor SMD 0402")
		(property "Reference" "R231"
			(at -1.01 -1.61 90)
			(layer "F.SilkS")
			(effects
				(font
					(size 0.7 0.7)
					(thickness 0.15)
				)
				(justify left bottom)
			)
		)
		(property "Value" "R_200R_0402"
			(at -1.011843 1.772047 90)
			(layer "F.Fab")
			(effects
				(font
					(size 0.7 0.7)
					(thickness 0.15)
				)
				(justify left bottom)
			)
		)
		(property "Datasheet" "https://www.bourns.com/docs/product-datasheets/cr.pdf"
			(at 0 0 90)
			(layer "F.Fab")
			(hide yes)
			(effects
				(font
					(size 1.27 1.27)
					(thickness 0.15)
				)
			)
		)
		(property "Description" "SMD Chip Resistor, 200 ohm, ± 1%, 62.5 mW, 0402 [1005 Metric], Thick Film, General Purpose"
			(at 0 0 90)
			(layer "F.Fab")
			(hide yes)
			(effects
				(font
					(size 1.27 1.27)
					(thickness 0.15)
				)
			)
		)
		(property "Manufacturer" "Bourns"
			(at 0 0 90)
			(unlocked yes)
			(layer "F.Fab")
			(hide yes)
			(effects
				(font
					(size 1 1)
					(thickness 0.15)
				)
			)
		)
		(property "MPN" "CR0402-FX-2000GLF"
			(at 0 0 90)
			(unlocked yes)
			(layer "F.Fab")
			(hide yes)
			(effects
				(font
					(size 1 1)
					(thickness 0.15)
				)
			)
		)
		(property "Val" "200R"
			(at 0 0 90)
			(unlocked yes)
			(layer "F.Fab")
			(hide yes)
			(effects
				(font
					(size 1 1)
					(thickness 0.15)
				)
			)
		)
		(property "License" "Apache-2.0"
			(at 0 0 90)
			(unlocked yes)
			(layer "F.Fab")
			(hide yes)
			(effects
				(font
					(size 1 1)
					(thickness 0.15)
				)
			)
		)
		(property "Author" "Antmicro"
			(at 0 0 90)
			(unlocked yes)
			(layer "F.Fab")
			(hide yes)
			(effects
				(font
					(size 1 1)
					(thickness 0.15)
				)
			)
		)
		(property "Tolerance" "1%"
			(at 0 0 90)
			(unlocked yes)
			(layer "F.Fab")
			(hide yes)
			(effects
				(font
					(size 1 1)
					(thickness 0.15)
				)
			)
		)
		(sheetname "/Peripherals/")
		(sheetfile "peripherals.kicad_sch")
		(attr smd)
		(fp_rect
			(start -0.925 -0.47)
			(end 0.925 0.47)
			(stroke
				(width 0.05)
				(type default)
			)
			(fill no)
			(layer "F.CrtYd")
		)
		(fp_rect
			(start -0.5 -0.25)
			(end 0.5 0.25)
			(stroke
				(width 0.15)
				(type solid)
			)
			(fill no)
			(layer "F.Fab")
		)
		(fp_text user "License: Apache-2.0"
			(at -0.95 5.169 90)
			(layer "F.Fab")
			(effects
				(font
					(size 0.7 0.7)
					(thickness 0.15)
				)
				(justify left bottom)
			)
		)
		(fp_text user "${REFERENCE}"
			(at -0.95 3.168 90)
			(layer "F.Fab")
			(effects
				(font
					(size 0.7 0.7)
					(thickness 0.15)
				)
				(justify left bottom)
			)
		)
		(fp_text user "Author: Antmicro"
			(at -0.95 4.169 90)
			(layer "F.Fab")
			(effects
				(font
					(size 0.7 0.7)
					(thickness 0.15)
				)
				(justify left bottom)
			)
		)
		(pad "1" smd roundrect
			(at -0.48 0 90)
			(size 0.59 0.64)
			(layers "F.Cu" "F.Mask" "F.Paste")
			(roundrect_rratio 0.25)
			(net 36 "Net-(D35-A)")
			(pintype "passive")
		)
		(pad "2" smd roundrect
			(at 0.48 0 90)
			(size 0.59 0.64)
			(layers "F.Cu" "F.Mask" "F.Paste")
			(roundrect_rratio 0.25)
			(net 2 "+3V3")
			(pintype "passive")
		)
	)
	(footprint "antmicro-footprints:R_0402_1005Metric"
		(layer "F.Cu")
		(at 195.1 129.3 180)
		(descr "Resistor SMD 0402")
		(tags "resistor SMD 0402")
		(property "Reference" "R90"
			(at -1.1 -4.6 0)
			(layer "F.SilkS")
			(effects
				(font
					(size 0.7 0.7)
					(thickness 0.15)
				)
				(justify right top)
			)
		)
		(property "Value" "R_0R_0402"
			(at -1.011843 1.772047 0)
			(layer "F.Fab")
			(effects
				(font
					(size 0.7 0.7)
					(thickness 0.15)
				)
				(justify right top)
			)
		)
		(property "Datasheet" "https://industrial.panasonic.com/cdbs/www-data/pdf/RDA0000/AOA0000C301.pdf"
			(at 0 0 0)
			(layer "F.Fab")
			(hide yes)
			(effects
				(font
					(size 1.27 1.27)
					(thickness 0.15)
				)
			)
		)
		(property "Description" "SMD Chip Resistor, Jumper, 0 ohm, 100 mW, 0402 [1005 Metric], Thick Film, General Purpose"
			(at 0 0 0)
			(layer "F.Fab")
			(hide yes)
			(effects
				(font
					(size 1.27 1.27)
					(thickness 0.15)
				)
			)
		)
		(property "Manufacturer" "Panasonic"
			(at 0 0 180)
			(unlocked yes)
			(layer "F.Fab")
			(hide yes)
			(effects
				(font
					(size 1 1)
					(thickness 0.15)
				)
			)
		)
		(property "MPN" "ERJ2GE0R00X"
			(at 0 0 180)
			(unlocked yes)
			(layer "F.Fab")
			(hide yes)
			(effects
				(font
					(size 1 1)
					(thickness 0.15)
				)
			)
		)
		(property "Val" "0R"
			(at 0 0 180)
			(unlocked yes)
			(layer "F.Fab")
			(hide yes)
			(effects
				(font
					(size 1 1)
					(thickness 0.15)
				)
			)
		)
		(property "License" "Apache-2.0"
			(at 0 0 180)
			(unlocked yes)
			(layer "F.Fab")
			(hide yes)
			(effects
				(font
					(size 1 1)
					(thickness 0.15)
				)
			)
		)
		(property "Author" "Antmicro"
			(at 0 0 180)
			(unlocked yes)
			(layer "F.Fab")
			(hide yes)
			(effects
				(font
					(size 1 1)
					(thickness 0.15)
				)
			)
		)
		(property "Tolerance" "~"
			(at 0 0 180)
			(unlocked yes)
			(layer "F.Fab")
			(hide yes)
			(effects
				(font
					(size 1 1)
					(thickness 0.15)
				)
			)
		)
		(property "Current" "1A"
			(at 0 0 180)
			(unlocked yes)
			(layer "F.Fab")
			(hide yes)
			(effects
				(font
					(size 1 1)
					(thickness 0.15)
				)
			)
		)
		(sheetname "/USB Hub/")
		(sheetfile "usb_hub.kicad_sch")
		(attr smd exclude_from_pos_files exclude_from_bom dnp)
		(fp_rect
			(start -0.925 -0.47)
			(end 0.925 0.47)
			(stroke
				(width 0.05)
				(type default)
			)
			(fill no)
			(layer "F.CrtYd")
		)
		(fp_rect
			(start -0.5 -0.25)
			(end 0.5 0.25)
			(stroke
				(width 0.15)
				(type solid)
			)
			(fill no)
			(layer "F.Fab")
		)
		(fp_text user "${REFERENCE}"
			(at -0.95 3.168 0)
			(layer "F.Fab")
			(effects
				(font
					(size 0.7 0.7)
					(thickness 0.15)
				)
				(justify right top)
			)
		)
		(fp_text user "License: Apache-2.0"
			(at -0.95 5.169 0)
			(layer "F.Fab")
			(effects
				(font
					(size 0.7 0.7)
					(thickness 0.15)
				)
				(justify right top)
			)
		)
		(fp_text user "Author: Antmicro"
			(at -0.95 4.169 0)
			(layer "F.Fab")
			(effects
				(font
					(size 0.7 0.7)
					(thickness 0.15)
				)
				(justify right top)
			)
		)
		(pad "1" smd roundrect
			(at -0.48 0 180)
			(size 0.59 0.64)
			(layers "F.Cu" "F.Mask" "F.Paste")
			(roundrect_rratio 0.25)
			(net 930 "/USB Hub/HUB_SPI_CE_N")
			(pintype "passive")
		)
		(pad "2" smd roundrect
			(at 0.48 0 180)
			(size 0.59 0.64)
			(layers "F.Cu" "F.Mask" "F.Paste")
			(roundrect_rratio 0.25)
			(net 929 "/USB Debug, PD/SPI_{HUB_DEBUG}.~{CS0}")
			(pintype "passive")
		)
	)
	(footprint "antmicro-footprints:C_0805_2012Metric"
		(layer "F.Cu")
		(at 169.52 69.1 90)
		(descr "Capacitor SMD 0805")
		(tags "capacitor SMD 0805")
		(property "Reference" "C274"
			(at -1.41 -1.960532 90)
			(layer "F.SilkS")
			(effects
				(font
					(size 0.7 0.7)
					(thickness 0.15)
				)
				(justify left bottom)
			)
		)
		(property "Value" "C_22u_25V_0805"
			(at -2.055717 1.963152 90)
			(layer "F.Fab")
			(effects
				(font
					(size 0.7 0.7)
					(thickness 0.15)
				)
				(justify left bottom)
			)
		)
		(property "Datasheet" "https://product.samsungsem.com/mlcc/CL21A226MAYNNN.do"
			(at 0 0 90)
			(layer "F.Fab")
			(hide yes)
			(effects
				(font
					(size 1.27 1.27)
					(thickness 0.15)
				)
			)
		)
		(property "Description" "SMT Multilayer Ceramic Capacitor, 22uF, +/-20%, 25V, X5R, 0805 [2012 Metric]"
			(at 0 0 90)
			(layer "F.Fab")
			(hide yes)
			(effects
				(font
					(size 1.27 1.27)
					(thickness 0.15)
				)
			)
		)
		(property "MPN" "CL21A226MAYNNNE"
			(at 0 0 90)
			(unlocked yes)
			(layer "F.Fab")
			(hide yes)
			(effects
				(font
					(size 1 1)
					(thickness 0.15)
				)
			)
		)
		(property "Manufacturer" "Samsung Electro-Mechanics"
			(at 0 0 90)
			(unlocked yes)
			(layer "F.Fab")
			(hide yes)
			(effects
				(font
					(size 1 1)
					(thickness 0.15)
				)
			)
		)
		(property "License" "Apache-2.0"
			(at 0 0 90)
			(unlocked yes)
			(layer "F.Fab")
			(hide yes)
			(effects
				(font
					(size 1 1)
					(thickness 0.15)
				)
			)
		)
		(property "Author" "Antmicro"
			(at 0 0 90)
			(unlocked yes)
			(layer "F.Fab")
			(hide yes)
			(effects
				(font
					(size 1 1)
					(thickness 0.15)
				)
			)
		)
		(property "Val" "22u"
			(at 0 0 90)
			(unlocked yes)
			(layer "F.Fab")
			(hide yes)
			(effects
				(font
					(size 1 1)
					(thickness 0.15)
				)
			)
		)
		(property "Voltage" "25V"
			(at 0 0 90)
			(unlocked yes)
			(layer "F.Fab")
			(hide yes)
			(effects
				(font
					(size 1 1)
					(thickness 0.15)
				)
			)
		)
		(property "Dielectric" "X5R"
			(at 0 0 90)
			(unlocked yes)
			(layer "F.Fab")
			(hide yes)
			(effects
				(font
					(size 1 1)
					(thickness 0.15)
				)
			)
		)
		(property "Public" "False"
			(at 0 0 90)
			(unlocked yes)
			(layer "F.Fab")
			(hide yes)
			(effects
				(font
					(size 1 1)
					(thickness 0.15)
				)
			)
		)
		(component_classes
			(class "DCDC_20V")
		)
		(sheetname "/DCDC/")
		(sheetfile "dcdc.kicad_sch")
		(attr smd)
		(fp_line
			(start -0.3 -0.7)
			(end 0.3 -0.7)
			(stroke
				(width 0.15)
				(type solid)
			)
			(layer "F.SilkS")
		)
		(fp_line
			(start -0.3 0.7)
			(end 0.3 0.7)
			(stroke
				(width 0.15)
				(type solid)
			)
			(layer "F.SilkS")
		)
		(fp_rect
			(start 1.95 -0.9)
			(end -1.95 0.9)
			(stroke
				(width 0.05)
				(type default)
			)
			(fill no)
			(layer "F.CrtYd")
		)
		(fp_rect
			(start -0.95 -0.675)
			(end 0.95 0.675)
			(stroke
				(width 0.15)
				(type solid)
			)
			(fill no)
			(layer "F.Fab")
		)
		(fp_text user "License: Apache-2.0"
			(at -1.9 4.947 90)
			(layer "F.Fab")
			(effects
				(font
					(size 0.7 0.7)
					(thickness 0.15)
				)
				(justify left bottom)
			)
		)
		(fp_text user "${REFERENCE}"
			(at -1.9 3.947 90)
			(layer "F.Fab")
			(effects
				(font
					(size 0.7 0.7)
					(thickness 0.15)
				)
				(justify left bottom)
			)
		)
		(fp_text user "Author: Antmicro"
			(at -1.9 5.947 90)
			(layer "F.Fab")
			(effects
				(font
					(size 0.7 0.7)
					(thickness 0.15)
				)
				(justify left bottom)
			)
		)
		(pad "1" smd roundrect
			(at -1.1 0 90)
			(size 1.2 1.3)
			(layers "F.Cu" "F.Mask" "F.Paste")
			(roundrect_rratio 0.25)
			(net 1 "GND")
			(pintype "passive")
		)
		(pad "2" smd roundrect
			(at 1.1 0 90)
			(size 1.2 1.3)
			(layers "F.Cu" "F.Mask" "F.Paste")
			(roundrect_rratio 0.25)
			(net 13 "VCC")
			(pintype "passive")
		)
	)
	(footprint "antmicro-footprints:LED_0603_1608Metric_G"
		(layer "F.Cu")
		(at 179.75 55.35 -90)
		(descr "LED SMD 0603 Green")
		(tags "LED SMD 0603 Green")
		(property "Reference" "D10"
			(at -0.89 1.51 90)
			(layer "F.SilkS")
			(effects
				(font
					(size 0.7 0.7)
					(thickness 0.15)
				)
				(justify right top)
			)
		)
		(property "Value" "LED_G_0603_LTST-C190GKT"
			(at -0.001 1.599 90)
			(layer "F.Fab")
			(effects
				(font
					(size 0.7 0.7)
					(thickness 0.15)
				)
				(justify right top)
			)
		)
		(property "Datasheet" "https://media.digikey.com/pdf/Data%20Sheets/Lite-On%20PDFs/LTST-C190GKT.pdf"
			(at 0 0 90)
			(layer "F.Fab")
			(hide yes)
			(effects
				(font
					(size 1.27 1.27)
					(thickness 0.15)
				)
			)
		)
		(property "Description" "LED, Green, SMD, 0603, 20 mA, 2.1 V, 569 nm"
			(at 0 0 90)
			(layer "F.Fab")
			(hide yes)
			(effects
				(font
					(size 1.27 1.27)
					(thickness 0.15)
				)
			)
		)
		(property "MPN" "LTST-C190GKT"
			(at 0 0 270)
			(unlocked yes)
			(layer "F.Fab")
			(hide yes)
			(effects
				(font
					(size 1 1)
					(thickness 0.15)
				)
			)
		)
		(property "Manufacturer" "Lite-On"
			(at 0 0 270)
			(unlocked yes)
			(layer "F.Fab")
			(hide yes)
			(effects
				(font
					(size 1 1)
					(thickness 0.15)
				)
			)
		)
		(property "Author" "Antmicro"
			(at 0 0 270)
			(unlocked yes)
			(layer "F.Fab")
			(hide yes)
			(effects
				(font
					(size 1 1)
					(thickness 0.15)
				)
			)
		)
		(property "License" "Apache-2.0"
			(at 0 0 270)
			(unlocked yes)
			(layer "F.Fab")
			(hide yes)
			(effects
				(font
					(size 1 1)
					(thickness 0.15)
				)
			)
		)
		(property "Color" "Green"
			(at 0 0 270)
			(unlocked yes)
			(layer "F.Fab")
			(hide yes)
			(effects
				(font
					(size 1 1)
					(thickness 0.15)
				)
			)
		)
		(sheetname "/Power/")
		(sheetfile "power.kicad_sch")
		(attr smd)
		(fp_line
			(start 0.22 0.35)
			(end -0.22 0.35)
			(stroke
				(width 0.15)
				(type solid)
			)
			(layer "F.SilkS")
		)
		(fp_line
			(start -0.094672 0.201008)
			(end -0.094672 -0.198992)
			(stroke
				(width 0.1)
				(type solid)
			)
			(layer "F.SilkS")
		)
		(fp_line
			(start 0.105328 0.201008)
			(end -0.094672 0.001008)
			(stroke
				(width 0.1)
				(type solid)
			)
			(layer "F.SilkS")
		)
		(fp_line
			(start 0.105328 0.201008)
			(end 0.105328 -0.198992)
			(stroke
				(width 0.1)
				(type solid)
			)
			(layer "F.SilkS")
		)
		(fp_line
			(start -0.094672 0.001008)
			(end -0.24 0.001008)
			(stroke
				(width 0.1)
				(type solid)
			)
			(layer "F.SilkS")
		)
		(fp_line
			(start -0.094672 0.001008)
			(end 0.105328 -0.198992)
			(stroke
				(width 0.1)
				(type solid)
			)
			(layer "F.SilkS")
		)
		(fp_line
			(start 0.105328 0.001008)
			(end 0.24 0.001)
			(stroke
				(width 0.1)
				(type solid)
			)
			(layer "F.SilkS")
		)
		(fp_line
			(start -1.18 -0.319)
			(end -1.18 0.321)
			(stroke
				(width 0.15)
				(type solid)
			)
			(layer "F.SilkS")
		)
		(fp_line
			(start 0.22 -0.35)
			(end -0.22 -0.35)
			(stroke
				(width 0.15)
				(type solid)
			)
			(layer "F.SilkS")
		)
		(fp_rect
			(start 1.25 0.65)
			(end -1.25 -0.65)
			(stroke
				(width 0.05)
				(type solid)
			)
			(fill no)
			(layer "F.CrtYd")
		)
		(fp_line
			(start -0.199 0.2)
			(end -0.199 0.1)
			(stroke
				(width 0.15)
				(type solid)
			)
			(layer "F.Fab")
		)
		(fp_line
			(start 0.201 0.2)
			(end 0.201 0)
			(stroke
				(width 0.15)
				(type solid)
			)
			(layer "F.Fab")
		)
		(fp_line
			(start -0.199 0)
			(end -0.597 0)
			(stroke
				(width 0.15)
				(type solid)
			)
			(layer "F.Fab")
		)
		(fp_line
			(start -0.101 0)
			(end 0.201 0.2)
			(stroke
				(width 0.15)
				(type solid)
			)
			(layer "F.Fab")
		)
		(fp_line
			(start 0.201 0)
			(end 0.201 -0.202)
			(stroke
				(width 0.15)
				(type solid)
			)
			(layer "F.Fab")
		)
		(fp_line
			(start 0.599 0)
			(end 0.201 0)
			(stroke
				(width 0.15)
				(type solid)
			)
			(layer "F.Fab")
		)
		(fp_line
			(start -0.199 -0.202)
			(end -0.199 0.1)
			(stroke
				(width 0.15)
				(type solid)
			)
			(layer "F.Fab")
		)
		(fp_line
			(start 0.201 -0.202)
			(end -0.101 0)
			(stroke
				(width 0.15)
				(type solid)
			)
			(layer "F.Fab")
		)
		(fp_rect
			(start 0.848 0.4)
			(end -0.85 -0.402)
			(stroke
				(width 0.15)
				(type solid)
			)
			(fill no)
			(layer "F.Fab")
		)
		(fp_text user "${REFERENCE}"
			(at -1.4224 5.999 90)
			(layer "F.Fab")
			(effects
				(font
					(size 0.7 0.7)
					(thickness 0.15)
				)
				(justify right top)
			)
		)
		(fp_text user "Author: Antmicro"
			(at -1.4224 4.799 90)
			(layer "F.Fab")
			(effects
				(font
					(size 0.7 0.7)
					(thickness 0.15)
				)
				(justify right top)
			)
		)
		(fp_text user "License: Apache-2.0"
			(at -1.4224 3.599 90)
			(layer "F.Fab")
			(effects
				(font
					(size 0.7 0.7)
					(thickness 0.15)
				)
				(justify right top)
			)
		)
		(pad "1" smd roundrect
			(at -0.7 0 90)
			(size 0.8 1)
			(layers "F.Cu" "F.Mask" "F.Paste")
			(roundrect_rratio 0.2)
			(net 1 "GND")
			(pinfunction "C")
			(pintype "passive")
		)
		(pad "2" smd roundrect
			(at 0.7 0 90)
			(size 0.8 1)
			(layers "F.Cu" "F.Mask" "F.Paste")
			(roundrect_rratio 0.2)
			(net 529 "Net-(D10-A)")
			(pinfunction "A")
			(pintype "passive")
		)
	)
	(footprint "antmicro-footprints:C_0402_1005Metric"
		(layer "F.Cu")
		(at 179.375 107.916)
		(descr "Capacitor SMD 0402")
		(tags "capacitor SMD 0402")
		(property "Reference" "C59"
			(at -3.115 -0.03 0)
			(layer "F.SilkS")
			(effects
				(font
					(size 0.7 0.7)
					(thickness 0.15)
				)
				(justify left bottom)
			)
		)
		(property "Value" "C_100n_0402"
			(at -1.022927 2.155213 0)
			(layer "F.Fab")
			(effects
				(font
					(size 0.7 0.7)
					(thickness 0.15)
				)
				(justify left bottom)
			)
		)
		(property "Datasheet" "https://www.murata.com/products/productdetail?partno=GRM155R61H104KE14%23"
			(at 0 0 0)
			(layer "F.Fab")
			(hide yes)
			(effects
				(font
					(size 1.27 1.27)
					(thickness 0.15)
				)
			)
		)
		(property "Description" "SMD Multilayer Ceramic Capacitor, 0.1 µF, 50 V, 0402 [1005 Metric], ± 10%, X5R, GRM Series"
			(at 0 0 0)
			(layer "F.Fab")
			(hide yes)
			(effects
				(font
					(size 1.27 1.27)
					(thickness 0.15)
				)
			)
		)
		(property "Manufacturer" "Murata"
			(at 0 0 0)
			(unlocked yes)
			(layer "F.Fab")
			(hide yes)
			(effects
				(font
					(size 1 1)
					(thickness 0.15)
				)
			)
		)
		(property "MPN" "GRM155R61H104KE14D"
			(at 0 0 0)
			(unlocked yes)
			(layer "F.Fab")
			(hide yes)
			(effects
				(font
					(size 1 1)
					(thickness 0.15)
				)
			)
		)
		(property "Val" "100n"
			(at 0 0 0)
			(unlocked yes)
			(layer "F.Fab")
			(hide yes)
			(effects
				(font
					(size 1 1)
					(thickness 0.15)
				)
			)
		)
		(property "License" "Apache-2.0"
			(at 0 0 0)
			(unlocked yes)
			(layer "F.Fab")
			(hide yes)
			(effects
				(font
					(size 1 1)
					(thickness 0.15)
				)
			)
		)
		(property "Author" "Antmicro"
			(at 0 0 0)
			(unlocked yes)
			(layer "F.Fab")
			(hide yes)
			(effects
				(font
					(size 1 1)
					(thickness 0.15)
				)
			)
		)
		(property "Voltage" "50V"
			(at 0 0 0)
			(unlocked yes)
			(layer "F.Fab")
			(hide yes)
			(effects
				(font
					(size 1 1)
					(thickness 0.15)
				)
			)
		)
		(property "Dielectric" "X5R"
			(at 0 0 0)
			(unlocked yes)
			(layer "F.Fab")
			(hide yes)
			(effects
				(font
					(size 1 1)
					(thickness 0.15)
				)
			)
		)
		(sheetname "/DCDC/")
		(sheetfile "dcdc.kicad_sch")
		(attr smd)
		(fp_rect
			(start -0.925 -0.47)
			(end 0.925 0.47)
			(stroke
				(width 0.05)
				(type default)
			)
			(fill no)
			(layer "F.CrtYd")
		)
		(fp_line
			(start -0.494 -0.25)
			(end 0.504 -0.25)
			(stroke
				(width 0.15)
				(type solid)
			)
			(layer "F.Fab")
		)
		(fp_line
			(start -0.494 0.248)
			(end -0.494 -0.25)
			(stroke
				(width 0.15)
				(type solid)
			)
			(layer "F.Fab")
		)
		(fp_line
			(start 0.504 -0.25)
			(end 0.504 0.248)
			(stroke
				(width 0.15)
				(type solid)
			)
			(layer "F.Fab")
		)
		(fp_line
			(start 0.504 0.248)
			(end -0.494 0.248)
			(stroke
				(width 0.15)
				(type solid)
			)
			(layer "F.Fab")
		)
		(fp_text user "Author: Antmicro"
			(at -0.939 3.399 0)
			(layer "F.Fab")
			(effects
				(font
					(size 0.7 0.7)
					(thickness 0.15)
				)
				(justify left bottom)
			)
		)
		(fp_text user "License: Apache-2.0"
			(at -0.939 5.799 0)
			(layer "F.Fab")
			(effects
				(font
					(size 0.7 0.7)
					(thickness 0.15)
				)
				(justify left bottom)
			)
		)
		(fp_text user "${REFERENCE}"
			(at -0.939 4.599 0)
			(layer "F.Fab")
			(effects
				(font
					(size 0.7 0.7)
					(thickness 0.15)
				)
				(justify left bottom)
			)
		)
		(pad "1" smd roundrect
			(at -0.48 0)
			(size 0.59 0.64)
			(layers "F.Cu" "F.Mask" "F.Paste")
			(roundrect_rratio 0.25)
			(net 26 "/DCDC/5V_PHASE")
			(pintype "passive")
		)
		(pad "2" smd roundrect
			(at 0.48 0)
			(size 0.59 0.64)
			(layers "F.Cu" "F.Mask" "F.Paste")
			(roundrect_rratio 0.25)
			(net 25 "/DCDC/5V_BOOT")
			(pintype "passive")
		)
	)
	(footprint "antmicro-footprints:C_0402_1005Metric"
		(layer "F.Cu")
		(at 182.84 71.45 -90)
		(descr "Capacitor SMD 0402")
		(tags "capacitor SMD 0402")
		(property "Reference" "C280"
			(at -0.9 -0.75 90)
			(layer "F.SilkS")
			(effects
				(font
					(size 0.7 0.7)
					(thickness 0.15)
				)
				(justify right top)
			)
		)
		(property "Value" "C_4u7_25V_0402"
			(at -1.022927 2.155213 90)
			(layer "F.Fab")
			(effects
				(font
					(size 0.7 0.7)
					(thickness 0.15)
				)
				(justify right top)
			)
		)
		(property "Datasheet" "https://www.murata.com/products/productdetail?partno=GRM155C61E475ME15%23"
			(at 0 0 90)
			(layer "F.Fab")
			(hide yes)
			(effects
				(font
					(size 1.27 1.27)
					(thickness 0.15)
				)
			)
		)
		(property "Description" "SMD Multilayer Ceramic Capacitor"
			(at 0 0 90)
			(layer "F.Fab")
			(hide yes)
			(effects
				(font
					(size 1.27 1.27)
					(thickness 0.15)
				)
			)
		)
		(property "MPN" "GRM155C61E475ME15J"
			(at 0 0 270)
			(unlocked yes)
			(layer "F.Fab")
			(hide yes)
			(effects
				(font
					(size 1 1)
					(thickness 0.15)
				)
			)
		)
		(property "Manufacturer" "Murata"
			(at 0 0 270)
			(unlocked yes)
			(layer "F.Fab")
			(hide yes)
			(effects
				(font
					(size 1 1)
					(thickness 0.15)
				)
			)
		)
		(property "License" "Apache-2.0"
			(at 0 0 270)
			(unlocked yes)
			(layer "F.Fab")
			(hide yes)
			(effects
				(font
					(size 1 1)
					(thickness 0.15)
				)
			)
		)
		(property "Author" "Antmicro"
			(at 0 0 270)
			(unlocked yes)
			(layer "F.Fab")
			(hide yes)
			(effects
				(font
					(size 1 1)
					(thickness 0.15)
				)
			)
		)
		(property "Val" "4u7"
			(at 0 0 270)
			(unlocked yes)
			(layer "F.Fab")
			(hide yes)
			(effects
				(font
					(size 1 1)
					(thickness 0.15)
				)
			)
		)
		(property "Voltage" "25V"
			(at 0 0 270)
			(unlocked yes)
			(layer "F.Fab")
			(hide yes)
			(effects
				(font
					(size 1 1)
					(thickness 0.15)
				)
			)
		)
		(property "Dielectric" "X5S"
			(at 0 0 270)
			(unlocked yes)
			(layer "F.Fab")
			(hide yes)
			(effects
				(font
					(size 1 1)
					(thickness 0.15)
				)
			)
		)
		(component_classes
			(class "DCDC_20V")
		)
		(sheetname "/DCDC/")
		(sheetfile "dcdc.kicad_sch")
		(attr smd)
		(fp_rect
			(start -0.925 -0.47)
			(end 0.925 0.47)
			(stroke
				(width 0.05)
				(type default)
			)
			(fill no)
			(layer "F.CrtYd")
		)
		(fp_line
			(start -0.494 0.248)
			(end -0.494 -0.25)
			(stroke
				(width 0.15)
				(type solid)
			)
			(layer "F.Fab")
		)
		(fp_line
			(start 0.504 0.248)
			(end -0.494 0.248)
			(stroke
				(width 0.15)
				(type solid)
			)
			(layer "F.Fab")
		)
		(fp_line
			(start -0.494 -0.25)
			(end 0.504 -0.25)
			(stroke
				(width 0.15)
				(type solid)
			)
			(layer "F.Fab")
		)
		(fp_line
			(start 0.504 -0.25)
			(end 0.504 0.248)
			(stroke
				(width 0.15)
				(type solid)
			)
			(layer "F.Fab")
		)
		(fp_text user "${REFERENCE}"
			(at -0.939 4.599 90)
			(layer "F.Fab")
			(effects
				(font
					(size 0.7 0.7)
					(thickness 0.15)
				)
				(justify right top)
			)
		)
		(fp_text user "Author: Antmicro"
			(at -0.939 3.399 90)
			(layer "F.Fab")
			(effects
				(font
					(size 0.7 0.7)
					(thickness 0.15)
				)
				(justify right top)
			)
		)
		(fp_text user "License: Apache-2.0"
			(at -0.939 5.799 90)
			(layer "F.Fab")
			(effects
				(font
					(size 0.7 0.7)
					(thickness 0.15)
				)
				(justify right top)
			)
		)
		(pad "1" smd roundrect
			(at -0.48 0 270)
			(size 0.59 0.64)
			(layers "F.Cu" "F.Mask" "F.Paste")
			(roundrect_rratio 0.25)
			(net 1 "GND")
			(pintype "passive")
		)
		(pad "2" smd roundrect
			(at 0.48 0 270)
			(size 0.59 0.64)
			(layers "F.Cu" "F.Mask" "F.Paste")
			(roundrect_rratio 0.25)
			(net 1081 "/DCDC/20V_VDRV")
			(pintype "passive")
		)
	)
	(footprint "antmicro-footprints:C_0402_1005Metric"
		(layer "F.Cu")
		(at 219.564132 87.75)
		(descr "Capacitor SMD 0402")
		(tags "capacitor SMD 0402")
		(property "Reference" "C145"
			(at -1.764132 1.45 0)
			(layer "F.SilkS")
			(effects
				(font
					(size 0.7 0.7)
					(thickness 0.15)
				)
				(justify left bottom)
			)
		)
		(property "Value" "C_100n_0402"
			(at -1.022927 2.155213 0)
			(layer "F.Fab")
			(effects
				(font
					(size 0.7 0.7)
					(thickness 0.15)
				)
				(justify left bottom)
			)
		)
		(property "Datasheet" "https://www.murata.com/products/productdetail?partno=GRM155R61H104KE14%23"
			(at 0 0 0)
			(layer "F.Fab")
			(hide yes)
			(effects
				(font
					(size 1.27 1.27)
					(thickness 0.15)
				)
			)
		)
		(property "Description" "SMD Multilayer Ceramic Capacitor, 0.1 µF, 50 V, 0402 [1005 Metric], ± 10%, X5R, GRM Series"
			(at 0 0 0)
			(layer "F.Fab")
			(hide yes)
			(effects
				(font
					(size 1.27 1.27)
					(thickness 0.15)
				)
			)
		)
		(property "Manufacturer" "Murata"
			(at 0 0 0)
			(unlocked yes)
			(layer "F.Fab")
			(hide yes)
			(effects
				(font
					(size 1 1)
					(thickness 0.15)
				)
			)
		)
		(property "MPN" "GRM155R61H104KE14D"
			(at 0 0 0)
			(unlocked yes)
			(layer "F.Fab")
			(hide yes)
			(effects
				(font
					(size 1 1)
					(thickness 0.15)
				)
			)
		)
		(property "Val" "100n"
			(at 0 0 0)
			(unlocked yes)
			(layer "F.Fab")
			(hide yes)
			(effects
				(font
					(size 1 1)
					(thickness 0.15)
				)
			)
		)
		(property "License" "Apache-2.0"
			(at 0 0 0)
			(unlocked yes)
			(layer "F.Fab")
			(hide yes)
			(effects
				(font
					(size 1 1)
					(thickness 0.15)
				)
			)
		)
		(property "Author" "Antmicro"
			(at 0 0 0)
			(unlocked yes)
			(layer "F.Fab")
			(hide yes)
			(effects
				(font
					(size 1 1)
					(thickness 0.15)
				)
			)
		)
		(property "Voltage" "50V"
			(at 0 0 0)
			(unlocked yes)
			(layer "F.Fab")
			(hide yes)
			(effects
				(font
					(size 1 1)
					(thickness 0.15)
				)
			)
		)
		(property "Dielectric" "X5R"
			(at 0 0 0)
			(unlocked yes)
			(layer "F.Fab")
			(hide yes)
			(effects
				(font
					(size 1 1)
					(thickness 0.15)
				)
			)
		)
		(sheetname "/USB DP Alt mode/")
		(sheetfile "usb_dp.kicad_sch")
		(attr smd)
		(fp_rect
			(start -0.925 -0.47)
			(end 0.925 0.47)
			(stroke
				(width 0.05)
				(type default)
			)
			(fill no)
			(layer "F.CrtYd")
		)
		(fp_line
			(start -0.494 -0.25)
			(end 0.504 -0.25)
			(stroke
				(width 0.15)
				(type solid)
			)
			(layer "F.Fab")
		)
		(fp_line
			(start -0.494 0.248)
			(end -0.494 -0.25)
			(stroke
				(width 0.15)
				(type solid)
			)
			(layer "F.Fab")
		)
		(fp_line
			(start 0.504 -0.25)
			(end 0.504 0.248)
			(stroke
				(width 0.15)
				(type solid)
			)
			(layer "F.Fab")
		)
		(fp_line
			(start 0.504 0.248)
			(end -0.494 0.248)
			(stroke
				(width 0.15)
				(type solid)
			)
			(layer "F.Fab")
		)
		(fp_text user "License: Apache-2.0"
			(at -0.939 5.799 0)
			(layer "F.Fab")
			(effects
				(font
					(size 0.7 0.7)
					(thickness 0.15)
				)
				(justify left bottom)
			)
		)
		(fp_text user "Author: Antmicro"
			(at -0.939 3.399 0)
			(layer "F.Fab")
			(effects
				(font
					(size 0.7 0.7)
					(thickness 0.15)
				)
				(justify left bottom)
			)
		)
		(fp_text user "${REFERENCE}"
			(at -0.939 4.599 0)
			(layer "F.Fab")
			(effects
				(font
					(size 0.7 0.7)
					(thickness 0.15)
				)
				(justify left bottom)
			)
		)
		(pad "1" smd roundrect
			(at -0.48 0)
			(size 0.59 0.64)
			(layers "F.Cu" "F.Mask" "F.Paste")
			(roundrect_rratio 0.25)
			(net 372 "/USB DP Alt mode/USBC1_TX2_N")
			(pintype "passive")
		)
		(pad "2" smd roundrect
			(at 0.48 0)
			(size 0.59 0.64)
			(layers "F.Cu" "F.Mask" "F.Paste")
			(roundrect_rratio 0.25)
			(net 374 "/USB DP Alt mode/USBC1_CONN_TX2_N")
			(pintype "passive")
		)
	)
	(footprint "antmicro-footprints:C_0402_1005Metric"
		(layer "F.Cu")
		(at 184.05 110.15 -90)
		(descr "Capacitor SMD 0402")
		(tags "capacitor SMD 0402")
		(property "Reference" "C52"
			(at -1.527 -0.522 90)
			(layer "F.SilkS")
			(effects
				(font
					(size 0.7 0.7)
					(thickness 0.15)
				)
				(justify right top)
			)
		)
		(property "Value" "C_1u_0402"
			(at -1.022927 2.155213 90)
			(layer "F.Fab")
			(effects
				(font
					(size 0.7 0.7)
					(thickness 0.15)
				)
				(justify right top)
			)
		)
		(property "Datasheet" "https://product.tdk.com/en/search/capacitor/ceramic/mlcc/info?part_no=C1005X6S1A105K050BC"
			(at 0 0 90)
			(layer "F.Fab")
			(hide yes)
			(effects
				(font
					(size 1.27 1.27)
					(thickness 0.15)
				)
			)
		)
		(property "Description" "SMD Multilayer Ceramic Capacitor, 1 µF, 10 V, 0402 [1005 Metric], ± 10%, X6S, C"
			(at 0 0 90)
			(layer "F.Fab")
			(hide yes)
			(effects
				(font
					(size 1.27 1.27)
					(thickness 0.15)
				)
			)
		)
		(property "Manufacturer" "TDK"
			(at 0 0 270)
			(unlocked yes)
			(layer "F.Fab")
			(hide yes)
			(effects
				(font
					(size 1 1)
					(thickness 0.15)
				)
			)
		)
		(property "MPN" "C1005X6S1A105K050BC"
			(at 0 0 270)
			(unlocked yes)
			(layer "F.Fab")
			(hide yes)
			(effects
				(font
					(size 1 1)
					(thickness 0.15)
				)
			)
		)
		(property "Val" "1u"
			(at 0 0 270)
			(unlocked yes)
			(layer "F.Fab")
			(hide yes)
			(effects
				(font
					(size 1 1)
					(thickness 0.15)
				)
			)
		)
		(property "License" "Apache-2.0"
			(at 0 0 270)
			(unlocked yes)
			(layer "F.Fab")
			(hide yes)
			(effects
				(font
					(size 1 1)
					(thickness 0.15)
				)
			)
		)
		(property "Author" "Antmicro"
			(at 0 0 270)
			(unlocked yes)
			(layer "F.Fab")
			(hide yes)
			(effects
				(font
					(size 1 1)
					(thickness 0.15)
				)
			)
		)
		(property "Voltage" ""
			(at 0 0 270)
			(unlocked yes)
			(layer "F.Fab")
			(hide yes)
			(effects
				(font
					(size 1 1)
					(thickness 0.15)
				)
			)
		)
		(property "Dielectric" ""
			(at 0 0 270)
			(unlocked yes)
			(layer "F.Fab")
			(hide yes)
			(effects
				(font
					(size 1 1)
					(thickness 0.15)
				)
			)
		)
		(sheetname "/DCDC/")
		(sheetfile "dcdc.kicad_sch")
		(attr smd)
		(fp_rect
			(start -0.925 -0.47)
			(end 0.925 0.47)
			(stroke
				(width 0.05)
				(type default)
			)
			(fill no)
			(layer "F.CrtYd")
		)
		(fp_line
			(start -0.494 0.248)
			(end -0.494 -0.25)
			(stroke
				(width 0.15)
				(type solid)
			)
			(layer "F.Fab")
		)
		(fp_line
			(start 0.504 0.248)
			(end -0.494 0.248)
			(stroke
				(width 0.15)
				(type solid)
			)
			(layer "F.Fab")
		)
		(fp_line
			(start -0.494 -0.25)
			(end 0.504 -0.25)
			(stroke
				(width 0.15)
				(type solid)
			)
			(layer "F.Fab")
		)
		(fp_line
			(start 0.504 -0.25)
			(end 0.504 0.248)
			(stroke
				(width 0.15)
				(type solid)
			)
			(layer "F.Fab")
		)
		(fp_text user "License: Apache-2.0"
			(at -0.939 5.799 90)
			(layer "F.Fab")
			(effects
				(font
					(size 0.7 0.7)
					(thickness 0.15)
				)
				(justify right top)
			)
		)
		(fp_text user "Author: Antmicro"
			(at -0.939 3.399 90)
			(layer "F.Fab")
			(effects
				(font
					(size 0.7 0.7)
					(thickness 0.15)
				)
				(justify right top)
			)
		)
		(fp_text user "${REFERENCE}"
			(at -0.939 4.599 90)
			(layer "F.Fab")
			(effects
				(font
					(size 0.7 0.7)
					(thickness 0.15)
				)
				(justify right top)
			)
		)
		(pad "1" smd roundrect
			(at -0.48 0 270)
			(size 0.59 0.64)
			(layers "F.Cu" "F.Mask" "F.Paste")
			(roundrect_rratio 0.25)
			(net 1 "GND")
			(pintype "passive")
		)
		(pad "2" smd roundrect
			(at 0.48 0 270)
			(size 0.59 0.64)
			(layers "F.Cu" "F.Mask" "F.Paste")
			(roundrect_rratio 0.25)
			(net 18 "/DCDC/5V_VDD")
			(pintype "passive")
		)
	)
	(footprint "antmicro-footprints:C_0805_2012Metric"
		(layer "F.Cu")
		(at 175 79.81 90)
		(descr "Capacitor SMD 0805")
		(tags "capacitor SMD 0805")
		(property "Reference" "C302"
			(at -4.67 0.4 90)
			(layer "F.SilkS")
			(effects
				(font
					(size 0.7 0.7)
					(thickness 0.15)
				)
				(justify left bottom)
			)
		)
		(property "Value" "C_22u_25V_0805"
			(at -2.055717 1.963152 90)
			(layer "F.Fab")
			(effects
				(font
					(size 0.7 0.7)
					(thickness 0.15)
				)
				(justify left bottom)
			)
		)
		(property "Datasheet" "https://product.samsungsem.com/mlcc/CL21A226MAYNNN.do"
			(at 0 0 90)
			(layer "F.Fab")
			(hide yes)
			(effects
				(font
					(size 1.27 1.27)
					(thickness 0.15)
				)
			)
		)
		(property "Description" "SMT Multilayer Ceramic Capacitor, 22uF, +/-20%, 25V, X5R, 0805 [2012 Metric]"
			(at 0 0 90)
			(layer "F.Fab")
			(hide yes)
			(effects
				(font
					(size 1.27 1.27)
					(thickness 0.15)
				)
			)
		)
		(property "MPN" "CL21A226MAYNNNE"
			(at 0 0 90)
			(unlocked yes)
			(layer "F.Fab")
			(hide yes)
			(effects
				(font
					(size 1 1)
					(thickness 0.15)
				)
			)
		)
		(property "Manufacturer" "Samsung Electro-Mechanics"
			(at 0 0 90)
			(unlocked yes)
			(layer "F.Fab")
			(hide yes)
			(effects
				(font
					(size 1 1)
					(thickness 0.15)
				)
			)
		)
		(property "License" "Apache-2.0"
			(at 0 0 90)
			(unlocked yes)
			(layer "F.Fab")
			(hide yes)
			(effects
				(font
					(size 1 1)
					(thickness 0.15)
				)
			)
		)
		(property "Author" "Antmicro"
			(at 0 0 90)
			(unlocked yes)
			(layer "F.Fab")
			(hide yes)
			(effects
				(font
					(size 1 1)
					(thickness 0.15)
				)
			)
		)
		(property "Val" "22u"
			(at 0 0 90)
			(unlocked yes)
			(layer "F.Fab")
			(hide yes)
			(effects
				(font
					(size 1 1)
					(thickness 0.15)
				)
			)
		)
		(property "Voltage" "25V"
			(at 0 0 90)
			(unlocked yes)
			(layer "F.Fab")
			(hide yes)
			(effects
				(font
					(size 1 1)
					(thickness 0.15)
				)
			)
		)
		(property "Dielectric" "X5R"
			(at 0 0 90)
			(unlocked yes)
			(layer "F.Fab")
			(hide yes)
			(effects
				(font
					(size 1 1)
					(thickness 0.15)
				)
			)
		)
		(property "Public" "False"
			(at 0 0 90)
			(unlocked yes)
			(layer "F.Fab")
			(hide yes)
			(effects
				(font
					(size 1 1)
					(thickness 0.15)
				)
			)
		)
		(component_classes
			(class "DCDC_20V")
		)
		(sheetname "/DCDC/")
		(sheetfile "dcdc.kicad_sch")
		(attr smd)
		(fp_line
			(start -0.3 -0.7)
			(end 0.3 -0.7)
			(stroke
				(width 0.15)
				(type solid)
			)
			(layer "F.SilkS")
		)
		(fp_line
			(start -0.3 0.7)
			(end 0.3 0.7)
			(stroke
				(width 0.15)
				(type solid)
			)
			(layer "F.SilkS")
		)
		(fp_rect
			(start 1.95 -0.9)
			(end -1.95 0.9)
			(stroke
				(width 0.05)
				(type default)
			)
			(fill no)
			(layer "F.CrtYd")
		)
		(fp_rect
			(start -0.95 -0.675)
			(end 0.95 0.675)
			(stroke
				(width 0.15)
				(type solid)
			)
			(fill no)
			(layer "F.Fab")
		)
		(fp_text user "${REFERENCE}"
			(at -1.9 3.947 90)
			(layer "F.Fab")
			(effects
				(font
					(size 0.7 0.7)
					(thickness 0.15)
				)
				(justify left bottom)
			)
		)
		(fp_text user "License: Apache-2.0"
			(at -1.9 4.947 90)
			(layer "F.Fab")
			(effects
				(font
					(size 0.7 0.7)
					(thickness 0.15)
				)
				(justify left bottom)
			)
		)
		(fp_text user "Author: Antmicro"
			(at -1.9 5.947 90)
			(layer "F.Fab")
			(effects
				(font
					(size 0.7 0.7)
					(thickness 0.15)
				)
				(justify left bottom)
			)
		)
		(pad "1" smd roundrect
			(at -1.1 0 90)
			(size 1.2 1.3)
			(layers "F.Cu" "F.Mask" "F.Paste")
			(roundrect_rratio 0.25)
			(net 1 "GND")
			(pintype "passive")
		)
		(pad "2" smd roundrect
			(at 1.1 0 90)
			(size 1.2 1.3)
			(layers "F.Cu" "F.Mask" "F.Paste")
			(roundrect_rratio 0.25)
			(net 1105 "/DCDC/20V_OUT")
			(pintype "passive")
		)
	)
	(footprint "antmicro-footprints:Conn_Molex_PicoBlade_1x4_0533980471"
		(locked yes)
		(layer "F.Cu")
		(at 163.830532 144.9 -90)
		(descr "Molex PicoBlade series connector, 53398-0471")
		(tags "connector Molex PicoBlade side entry")
		(property "Reference" "J15"
			(at -6.8 -0.969468 180)
			(layer "F.SilkS")
			(effects
				(font
					(size 0.7 0.7)
					(thickness 0.15)
				)
				(justify right top)
			)
		)
		(property "Value" "Molex_PicoBlade_1x4_0533980471"
			(at -5.8 3.7 90)
			(layer "F.Fab")
			(effects
				(font
					(size 0.7 0.7)
					(thickness 0.15)
				)
				(justify right top)
			)
		)
		(property "Datasheet" "https://www.molex.com/molex/products/part-detail/pcb_headers/0533980471"
			(at 0 0 90)
			(layer "F.Fab")
			(hide yes)
			(effects
				(font
					(size 1.27 1.27)
					(thickness 0.15)
				)
			)
		)
		(property "Description" "Pin Header, Vertical, Signal, 1.25 mm, 1 Rows, 4 Contacts, Surface Mount Straight"
			(at 0 0 90)
			(layer "F.Fab")
			(hide yes)
			(effects
				(font
					(size 1.27 1.27)
					(thickness 0.15)
				)
			)
		)
		(property "MPN" "0533980471"
			(at 0 0 270)
			(unlocked yes)
			(layer "F.Fab")
			(hide yes)
			(effects
				(font
					(size 1 1)
					(thickness 0.15)
				)
			)
		)
		(property "Manufacturer" "Molex"
			(at 0 0 270)
			(unlocked yes)
			(layer "F.Fab")
			(hide yes)
			(effects
				(font
					(size 1 1)
					(thickness 0.15)
				)
			)
		)
		(property "Author" "Antmicro"
			(at 0 0 270)
			(unlocked yes)
			(layer "F.Fab")
			(hide yes)
			(effects
				(font
					(size 1 1)
					(thickness 0.15)
				)
			)
		)
		(property "License" "Apache-2.0"
			(at 0 0 270)
			(unlocked yes)
			(layer "F.Fab")
			(hide yes)
			(effects
				(font
					(size 1 1)
					(thickness 0.15)
				)
			)
		)
		(sheetname "/Peripherals/")
		(sheetfile "peripherals.kicad_sch")
		(attr smd)
		(fp_line
			(start -3.117 2.209)
			(end 3.115 2.209)
			(stroke
				(width 0.15)
				(type solid)
			)
			(layer "F.SilkS")
		)
		(fp_line
			(start -3.485 -0.76)
			(end -3.485 -1.71)
			(stroke
				(width 0.15)
				(type solid)
			)
			(layer "F.SilkS")
		)
		(fp_line
			(start 3.483 -0.76)
			(end 3.483 -1.71)
			(stroke
				(width 0.15)
				(type solid)
			)
			(layer "F.SilkS")
		)
		(fp_line
			(start -3.485 -1.71)
			(end -2.536 -1.71)
			(stroke
				(width 0.15)
				(type solid)
			)
			(layer "F.SilkS")
		)
		(fp_line
			(start -2.536 -1.71)
			(end -2.536 -2.4)
			(stroke
				(width 0.15)
				(type solid)
			)
			(layer "F.SilkS")
		)
		(fp_line
			(start 3.483 -1.71)
			(end 2.535 -1.71)
			(stroke
				(width 0.15)
				(type solid)
			)
			(layer "F.SilkS")
		)
		(fp_rect
			(start -5.677 -2.601)
			(end 5.675 2.7)
			(stroke
				(width 0.05)
				(type solid)
			)
			(fill no)
			(layer "F.CrtYd")
		)
		(fp_line
			(start -4.875 2.1)
			(end -5.077 1.898)
			(stroke
				(width 0.15)
				(type solid)
			)
			(layer "F.Fab")
		)
		(fp_line
			(start -3.375 2.1)
			(end -4.875 2.1)
			(stroke
				(width 0.15)
				(type solid)
			)
			(layer "F.Fab")
		)
		(fp_line
			(start -3.375 2.1)
			(end 3.374 2.1)
			(stroke
				(width 0.15)
				(type solid)
			)
			(layer "F.Fab")
		)
		(fp_line
			(start 3.374 2.1)
			(end 4.873 2.1)
			(stroke
				(width 0.15)
				(type solid)
			)
			(layer "F.Fab")
		)
		(fp_line
			(start 4.873 2.1)
			(end 5.075 1.898)
			(stroke
				(width 0.15)
				(type solid)
			)
			(layer "F.Fab")
		)
		(fp_line
			(start -5.077 1.898)
			(end -5.077 0.099)
			(stroke
				(width 0.15)
				(type solid)
			)
			(layer "F.Fab")
		)
		(fp_line
			(start 5.075 1.898)
			(end 5.075 0.099)
			(stroke
				(width 0.15)
				(type solid)
			)
			(layer "F.Fab")
		)
		(fp_line
			(start -2.025 1.175)
			(end -1.726 1.175)
			(stroke
				(width 0.15)
				(type solid)
			)
			(layer "F.Fab")
		)
		(fp_line
			(start -1.726 1.175)
			(end -1.726 0.575)
			(stroke
				(width 0.15)
				(type solid)
			)
			(layer "F.Fab")
		)
		(fp_line
			(start -0.777 1.175)
			(end -0.476 1.175)
			(stroke
				(width 0.15)
				(type solid)
			)
			(layer "F.Fab")
		)
		(fp_line
			(start -0.476 1.175)
			(end -0.476 0.575)
			(stroke
				(width 0.15)
				(type solid)
			)
			(layer "F.Fab")
		)
		(fp_line
			(start 0.474 1.175)
			(end 0.775 1.175)
			(stroke
				(width 0.15)
				(type solid)
			)
			(layer "F.Fab")
		)
		(fp_line
			(start 0.775 1.175)
			(end 0.775 0.575)
			(stroke
				(width 0.15)
				(type solid)
			)
			(layer "F.Fab")
		)
		(fp_line
			(start 1.725 1.175)
			(end 2.023 1.175)
			(stroke
				(width 0.15)
				(type solid)
			)
			(layer "F.Fab")
		)
		(fp_line
			(start 2.023 1.175)
			(end 2.023 0.575)
			(stroke
				(width 0.15)
				(type solid)
			)
			(layer "F.Fab")
		)
		(fp_line
			(start -2.025 0.575)
			(end -2.025 1.175)
			(stroke
				(width 0.15)
				(type solid)
			)
			(layer "F.Fab")
		)
		(fp_line
			(start -1.726 0.575)
			(end -2.025 0.575)
			(stroke
				(width 0.15)
				(type solid)
			)
			(layer "F.Fab")
		)
		(fp_line
			(start -0.777 0.575)
			(end -0.777 1.175)
			(stroke
				(width 0.15)
				(type solid)
			)
			(layer "F.Fab")
		)
		(fp_line
			(start -0.476 0.575)
			(end -0.777 0.575)
			(stroke
				(width 0.15)
				(type solid)
			)
			(layer "F.Fab")
		)
		(fp_line
			(start 0.474 0.575)
			(end 0.474 1.175)
			(stroke
				(width 0.15)
				(type solid)
			)
			(layer "F.Fab")
		)
		(fp_line
			(start 0.775 0.575)
			(end 0.474 0.575)
			(stroke
				(width 0.15)
				(type solid)
			)
			(layer "F.Fab")
		)
		(fp_line
			(start 1.725 0.575)
			(end 1.725 1.175)
			(stroke
				(width 0.15)
				(type solid)
			)
			(layer "F.Fab")
		)
		(fp_line
			(start 2.023 0.575)
			(end 1.725 0.575)
			(stroke
				(width 0.15)
				(type solid)
			)
			(layer "F.Fab")
		)
		(fp_line
			(start -5.077 0.099)
			(end -4.875 -0.101)
			(stroke
				(width 0.15)
				(type solid)
			)
			(layer "F.Fab")
		)
		(fp_line
			(start 5.075 0.099)
			(end 4.873 -0.101)
			(stroke
				(width 0.15)
				(type solid)
			)
			(layer "F.Fab")
		)
		(fp_line
			(start -4.875 -0.101)
			(end -4.875 -0.701)
			(stroke
				(width 0.15)
				(type solid)
			)
			(layer "F.Fab")
		)
		(fp_line
			(start 4.873 -0.101)
			(end 4.873 -0.701)
			(stroke
				(width 0.15)
				(type solid)
			)
			(layer "F.Fab")
		)
		(fp_line
			(start -4.875 -0.701)
			(end -3.375 -0.701)
			(stroke
				(width 0.15)
				(type solid)
			)
			(layer "F.Fab")
		)
		(fp_line
			(start 4.873 -0.701)
			(end 3.374 -0.701)
			(stroke
				(width 0.15)
				(type solid)
			)
			(layer "F.Fab")
		)
		(fp_line
			(start -1.875 -0.893)
			(end -1.375 -1.601)
			(stroke
				(width 0.15)
				(type solid)
			)
			(layer "F.Fab")
		)
		(fp_line
			(start -3.375 -1.601)
			(end -3.375 2.1)
			(stroke
				(width 0.15)
				(type solid)
			)
			(layer "F.Fab")
		)
		(fp_line
			(start -3.375 -1.601)
			(end 3.374 -1.601)
			(stroke
				(width 0.15)
				(type solid)
			)
			(layer "F.Fab")
		)
		(fp_line
			(start -2.375 -1.601)
			(end -1.875 -0.893)
			(stroke
				(width 0.15)
				(type solid)
			)
			(layer "F.Fab")
		)
		(fp_line
			(start 3.374 -1.601)
			(end 3.374 2.1)
			(stroke
				(width 0.15)
				(type solid)
			)
			(layer "F.Fab")
		)
		(fp_text user "${REFERENCE}"
			(at -5.8 5.2 90)
			(layer "F.Fab")
			(effects
				(font
					(size 0.7 0.7)
					(thickness 0.15)
				)
				(justify right top)
			)
		)
		(fp_text user "Author: Antmicro"
			(at -5.8 6.6 90)
			(layer "F.Fab")
			(effects
				(font
					(size 0.7 0.7)
					(thickness 0.15)
				)
				(justify right top)
			)
		)
		(fp_text user "License: Apache-2.0"
			(at -5.8 8 90)
			(layer "F.Fab")
			(effects
				(font
					(size 0.7 0.7)
					(thickness 0.15)
				)
				(justify right top)
			)
		)
		(pad "1" smd roundrect
			(at -1.875 -1.75 270)
			(size 0.8 1.3)
			(layers "F.Cu" "F.Mask" "F.Paste")
			(roundrect_rratio 0.25)
			(net 1 "GND")
			(pinfunction "1")
			(pintype "passive")
		)
		(pad "2" smd roundrect
			(at -0.625 -1.75 270)
			(size 0.8 1.3)
			(layers "F.Cu" "F.Mask" "F.Paste")
			(roundrect_rratio 0.25)
			(net 1043 "/Peripherals/FAN_VDD")
			(pinfunction "2")
			(pintype "passive")
		)
		(pad "3" smd roundrect
			(at 0.623 -1.75 270)
			(size 0.8 1.3)
			(layers "F.Cu" "F.Mask" "F.Paste")
			(roundrect_rratio 0.25)
			(net 279 "/Peripherals/FAN_TACH_5V")
			(pinfunction "3")
			(pintype "passive")
		)
		(pad "4" smd roundrect
			(at 1.874 -1.75 270)
			(size 0.8 1.3)
			(layers "F.Cu" "F.Mask" "F.Paste")
			(roundrect_rratio 0.25)
			(net 281 "/Peripherals/FAN_PWM_5V")
			(pinfunction "4")
			(pintype "passive")
		)
		(pad "MP1" smd roundrect
			(at -4.425 0.998 270)
			(size 2.1 3)
			(layers "F.Cu" "F.Mask" "F.Paste")
			(roundrect_rratio 0.119048)
			(net 1 "GND")
			(pinfunction "MP1")
			(pintype "passive")
		)
		(pad "MP2" smd roundrect
			(at 4.424 0.998 270)
			(size 2.1 3)
			(layers "F.Cu" "F.Mask" "F.Paste")
			(roundrect_rratio 0.119048)
			(net 1 "GND")
			(pinfunction "MP2")
			(pintype "passive")
		)
	)
	(footprint "antmicro-footprints:R_0402_1005Metric"
		(layer "F.Cu")
		(at 213.8 120.1 -90)
		(descr "Resistor SMD 0402")
		(tags "resistor SMD 0402")
		(property "Reference" "R91"
			(at -3.055 0.38 90)
			(layer "F.SilkS")
			(effects
				(font
					(size 0.7 0.7)
					(thickness 0.15)
				)
				(justify right top)
			)
		)
		(property "Value" "R_200k_0402"
			(at -1.011843 1.772046 90)
			(layer "F.Fab")
			(effects
				(font
					(size 0.7 0.7)
					(thickness 0.15)
				)
				(justify right top)
			)
		)
		(property "Datasheet" "https://www.bourns.com/docs/product-datasheets/cr.pdf"
			(at 0 0 90)
			(layer "F.Fab")
			(hide yes)
			(effects
				(font
					(size 1.27 1.27)
					(thickness 0.15)
				)
			)
		)
		(property "Description" "SMD Chip Resistor, 200 kohm, ± 1%, 62.5 mW, 0402 [1005 Metric], Thick Film, General Purpose"
			(at 0 0 90)
			(layer "F.Fab")
			(hide yes)
			(effects
				(font
					(size 1.27 1.27)
					(thickness 0.15)
				)
			)
		)
		(property "MPN" "CR0402-FX-2003GLF"
			(at 0 0 270)
			(unlocked yes)
			(layer "F.Fab")
			(hide yes)
			(effects
				(font
					(size 1 1)
					(thickness 0.15)
				)
			)
		)
		(property "Manufacturer" "Bourns"
			(at 0 0 270)
			(unlocked yes)
			(layer "F.Fab")
			(hide yes)
			(effects
				(font
					(size 1 1)
					(thickness 0.15)
				)
			)
		)
		(property "License" "Apache-2.0"
			(at 0 0 270)
			(unlocked yes)
			(layer "F.Fab")
			(hide yes)
			(effects
				(font
					(size 1 1)
					(thickness 0.15)
				)
			)
		)
		(property "Author" "Antmicro"
			(at 0 0 270)
			(unlocked yes)
			(layer "F.Fab")
			(hide yes)
			(effects
				(font
					(size 1 1)
					(thickness 0.15)
				)
			)
		)
		(property "Val" "200k"
			(at 0 0 270)
			(unlocked yes)
			(layer "F.Fab")
			(hide yes)
			(effects
				(font
					(size 1 1)
					(thickness 0.15)
				)
			)
		)
		(property "Tolerance" "1%"
			(at 0 0 270)
			(unlocked yes)
			(layer "F.Fab")
			(hide yes)
			(effects
				(font
					(size 1 1)
					(thickness 0.15)
				)
			)
		)
		(sheetname "/USB Hub/")
		(sheetfile "usb_hub.kicad_sch")
		(attr smd)
		(fp_poly
			(pts
				(xy -0.925 -0.47) (xy 0.925 -0.47) (xy 0.925 0.47) (xy -0.925 0.47)
			)
			(stroke
				(width 0.05)
				(type default)
			)
			(fill no)
			(layer "F.CrtYd")
		)
		(fp_poly
			(pts
				(xy -0.5 -0.25) (xy 0.5 -0.25) (xy 0.5 0.25) (xy -0.5 0.25)
			)
			(stroke
				(width 0.15)
				(type solid)
			)
			(fill no)
			(layer "F.Fab")
		)
		(fp_text user "Author: Antmicro"
			(at -0.95 4.169 90)
			(layer "F.Fab")
			(effects
				(font
					(size 0.7 0.7)
					(thickness 0.15)
				)
				(justify right top)
			)
		)
		(fp_text user "License: Apache-2.0"
			(at -0.949999 5.169 90)
			(layer "F.Fab")
			(effects
				(font
					(size 0.7 0.7)
					(thickness 0.15)
				)
				(justify right top)
			)
		)
		(fp_text user "${REFERENCE}"
			(at -0.95 3.168 90)
			(layer "F.Fab")
			(effects
				(font
					(size 0.7 0.7)
					(thickness 0.15)
				)
				(justify right top)
			)
		)
		(pad "1" smd roundrect
			(at -0.48 0 270)
			(size 0.59 0.64)
			(layers "F.Cu" "F.Mask" "F.Paste")
			(roundrect_rratio 0.25)
			(net 1 "GND")
			(pintype "passive")
		)
		(pad "2" smd roundrect
			(at 0.48 0 270)
			(size 0.59 0.64)
			(layers "F.Cu" "F.Mask" "F.Paste")
			(roundrect_rratio 0.25)
			(net 931 "/USB Hub/CFG_STRAP3")
			(pintype "passive")
		)
	)
	(footprint "antmicro-footprints:C_0402_1005Metric"
		(layer "F.Cu")
		(at 219.124 105.2 180)
		(descr "Capacitor SMD 0402")
		(tags "capacitor SMD 0402")
		(property "Reference" "C107"
			(at -1.18 -0.76 0)
			(layer "F.SilkS")
			(effects
				(font
					(size 0.7 0.7)
					(thickness 0.15)
				)
				(justify right top)
			)
		)
		(property "Value" "C_100n_0402"
			(at -1.022927 2.155213 0)
			(layer "F.Fab")
			(effects
				(font
					(size 0.7 0.7)
					(thickness 0.15)
				)
				(justify right top)
			)
		)
		(property "Datasheet" "https://www.murata.com/products/productdetail?partno=GRM155R61H104KE14%23"
			(at 0 0 0)
			(layer "F.Fab")
			(hide yes)
			(effects
				(font
					(size 1.27 1.27)
					(thickness 0.15)
				)
			)
		)
		(property "Description" "SMD Multilayer Ceramic Capacitor, 0.1 µF, 50 V, 0402 [1005 Metric], ± 10%, X5R, GRM Series"
			(at 0 0 0)
			(layer "F.Fab")
			(hide yes)
			(effects
				(font
					(size 1.27 1.27)
					(thickness 0.15)
				)
			)
		)
		(property "Manufacturer" "Murata"
			(at 0 0 180)
			(unlocked yes)
			(layer "F.Fab")
			(hide yes)
			(effects
				(font
					(size 1 1)
					(thickness 0.15)
				)
			)
		)
		(property "MPN" "GRM155R61H104KE14D"
			(at 0 0 180)
			(unlocked yes)
			(layer "F.Fab")
			(hide yes)
			(effects
				(font
					(size 1 1)
					(thickness 0.15)
				)
			)
		)
		(property "Val" "100n"
			(at 0 0 180)
			(unlocked yes)
			(layer "F.Fab")
			(hide yes)
			(effects
				(font
					(size 1 1)
					(thickness 0.15)
				)
			)
		)
		(property "License" "Apache-2.0"
			(at 0 0 180)
			(unlocked yes)
			(layer "F.Fab")
			(hide yes)
			(effects
				(font
					(size 1 1)
					(thickness 0.15)
				)
			)
		)
		(property "Author" "Antmicro"
			(at 0 0 180)
			(unlocked yes)
			(layer "F.Fab")
			(hide yes)
			(effects
				(font
					(size 1 1)
					(thickness 0.15)
				)
			)
		)
		(property "Voltage" "50V"
			(at 0 0 180)
			(unlocked yes)
			(layer "F.Fab")
			(hide yes)
			(effects
				(font
					(size 1 1)
					(thickness 0.15)
				)
			)
		)
		(property "Dielectric" "X5R"
			(at 0 0 180)
			(unlocked yes)
			(layer "F.Fab")
			(hide yes)
			(effects
				(font
					(size 1 1)
					(thickness 0.15)
				)
			)
		)
		(sheetname "/Recovery USB/")
		(sheetfile "recovery_usb.kicad_sch")
		(attr smd)
		(fp_rect
			(start -0.925 -0.47)
			(end 0.925 0.47)
			(stroke
				(width 0.05)
				(type default)
			)
			(fill no)
			(layer "F.CrtYd")
		)
		(fp_line
			(start 0.504 0.248)
			(end -0.494 0.248)
			(stroke
				(width 0.15)
				(type solid)
			)
			(layer "F.Fab")
		)
		(fp_line
			(start 0.504 -0.25)
			(end 0.504 0.248)
			(stroke
				(width 0.15)
				(type solid)
			)
			(layer "F.Fab")
		)
		(fp_line
			(start -0.494 0.248)
			(end -0.494 -0.25)
			(stroke
				(width 0.15)
				(type solid)
			)
			(layer "F.Fab")
		)
		(fp_line
			(start -0.494 -0.25)
			(end 0.504 -0.25)
			(stroke
				(width 0.15)
				(type solid)
			)
			(layer "F.Fab")
		)
		(fp_text user "Author: Antmicro"
			(at -0.939 3.399 0)
			(layer "F.Fab")
			(effects
				(font
					(size 0.7 0.7)
					(thickness 0.15)
				)
				(justify right top)
			)
		)
		(fp_text user "License: Apache-2.0"
			(at -0.939 5.799 0)
			(layer "F.Fab")
			(effects
				(font
					(size 0.7 0.7)
					(thickness 0.15)
				)
				(justify right top)
			)
		)
		(fp_text user "${REFERENCE}"
			(at -0.939 4.599 0)
			(layer "F.Fab")
			(effects
				(font
					(size 0.7 0.7)
					(thickness 0.15)
				)
				(justify right top)
			)
		)
		(pad "1" smd roundrect
			(at -0.48 0 180)
			(size 0.59 0.64)
			(layers "F.Cu" "F.Mask" "F.Paste")
			(roundrect_rratio 0.25)
			(net 215 "/Recovery USB/USBC2_CONN_TX1_N")
			(pintype "passive")
		)
		(pad "2" smd roundrect
			(at 0.48 0 180)
			(size 0.59 0.64)
			(layers "F.Cu" "F.Mask" "F.Paste")
			(roundrect_rratio 0.25)
			(net 234 "/Recovery USB/USBC2_TX1_N")
			(pintype "passive")
		)
	)
	(footprint "antmicro-footprints:C_0603_1608Metric_EIA"
		(layer "F.Cu")
		(at 192.47 126.88)
		(descr "Capacitor SMD 0603, IPC-7351 Density Level A")
		(tags "Capacitor 0603")
		(property "Reference" "C310"
			(at -1.47 8.32 0)
			(layer "F.SilkS")
			(effects
				(font
					(size 0.7 0.7)
					(thickness 0.15)
				)
				(justify left bottom)
			)
		)
		(property "Value" "C_22u_16V_0603"
			(at -1.42757 1.770288 0)
			(layer "F.Fab")
			(effects
				(font
					(size 0.7 0.7)
					(thickness 0.15)
				)
				(justify left bottom)
			)
		)
		(property "Datasheet" "https://product.samsungsem.com/mlcc/CL10A226MO7JZN.do"
			(at 0 0 0)
			(layer "F.Fab")
			(hide yes)
			(effects
				(font
					(size 1.27 1.27)
					(thickness 0.15)
				)
			)
		)
		(property "Description" "SMD Multilayer Ceramic Capacitor"
			(at 0 0 0)
			(layer "F.Fab")
			(hide yes)
			(effects
				(font
					(size 1.27 1.27)
					(thickness 0.15)
				)
			)
		)
		(property "MPN" "CL10A226MO7JZNC"
			(at 0 0 0)
			(unlocked yes)
			(layer "F.Fab")
			(hide yes)
			(effects
				(font
					(size 1 1)
					(thickness 0.15)
				)
			)
		)
		(property "Manufacturer" "Samsung Electro-Mechanics"
			(at 0 0 0)
			(unlocked yes)
			(layer "F.Fab")
			(hide yes)
			(effects
				(font
					(size 1 1)
					(thickness 0.15)
				)
			)
		)
		(property "License" "Apache-2.0"
			(at 0 0 0)
			(unlocked yes)
			(layer "F.Fab")
			(hide yes)
			(effects
				(font
					(size 1 1)
					(thickness 0.15)
				)
			)
		)
		(property "Author" "Antmicro"
			(at 0 0 0)
			(unlocked yes)
			(layer "F.Fab")
			(hide yes)
			(effects
				(font
					(size 1 1)
					(thickness 0.15)
				)
			)
		)
		(property "Val" "22u"
			(at 0 0 0)
			(unlocked yes)
			(layer "F.Fab")
			(hide yes)
			(effects
				(font
					(size 1 1)
					(thickness 0.15)
				)
			)
		)
		(property "Voltage" "16V"
			(at 0 0 0)
			(unlocked yes)
			(layer "F.Fab")
			(hide yes)
			(effects
				(font
					(size 1 1)
					(thickness 0.15)
				)
			)
		)
		(property "Dielectric" ""
			(at 0 0 0)
			(unlocked yes)
			(layer "F.Fab")
			(hide yes)
			(effects
				(font
					(size 1 1)
					(thickness 0.15)
				)
			)
		)
		(component_classes
			(class "DCDC_1V15")
		)
		(sheetname "/DCDC/")
		(sheetfile "dcdc.kicad_sch")
		(attr smd)
		(fp_line
			(start -0.15 -0.55)
			(end 0.15 -0.55)
			(stroke
				(width 0.15)
				(type solid)
			)
			(layer "F.SilkS")
		)
		(fp_line
			(start -0.15 0.55)
			(end 0.15 0.55)
			(stroke
				(width 0.15)
				(type solid)
			)
			(layer "F.SilkS")
		)
		(fp_rect
			(start -1.25 -0.65)
			(end 1.25 0.65)
			(stroke
				(width 0.05)
				(type solid)
			)
			(fill no)
			(layer "F.CrtYd")
		)
		(fp_rect
			(start -0.8 -0.45)
			(end 0.8 0.45)
			(stroke
				(width 0.15)
				(type solid)
			)
			(fill no)
			(layer "F.Fab")
		)
		(fp_text user "Author: Antmicro"
			(at -1.682 4.894 0)
			(layer "F.Fab")
			(effects
				(font
					(size 0.7 0.7)
					(thickness 0.15)
				)
				(justify left bottom)
			)
		)
		(fp_text user "License: Apache-2.0"
			(at -1.682 5.895 0)
			(layer "F.Fab")
			(effects
				(font
					(size 0.7 0.7)
					(thickness 0.15)
				)
				(justify left bottom)
			)
		)
		(fp_text user "${REFERENCE}"
			(at -1.682 3.895 0)
			(layer "F.Fab")
			(effects
				(font
					(size 0.7 0.7)
					(thickness 0.15)
				)
				(justify left bottom)
			)
		)
		(pad "1" smd roundrect
			(at -0.7 0)
			(size 0.8 1.1)
			(layers "F.Cu" "F.Mask" "F.Paste")
			(roundrect_rratio 0.2)
			(net 1 "GND")
			(pintype "passive")
		)
		(pad "2" smd roundrect
			(at 0.7 0)
			(size 0.8 1.1)
			(layers "F.Cu" "F.Mask" "F.Paste")
			(roundrect_rratio 0.2)
			(net 280 "/DCDC/1V15_OUT")
			(pintype "passive")
		)
	)
	(footprint "antmicro-footprints:C_0805_2012Metric"
		(layer "F.Cu")
		(at 147.5 91)
		(descr "Capacitor SMD 0805")
		(tags "capacitor SMD 0805")
		(property "Reference" "C26"
			(at -2.3 -0.3 180)
			(layer "F.SilkS")
			(effects
				(font
					(size 0.7 0.7)
					(thickness 0.15)
				)
				(justify right top)
			)
		)
		(property "Value" "C_22u_25V_0805"
			(at -2.055717 1.963153 180)
			(layer "F.Fab")
			(effects
				(font
					(size 0.7 0.7)
					(thickness 0.15)
				)
				(justify right top)
			)
		)
		(property "Datasheet" "https://product.samsungsem.com/mlcc/CL21A226MAYNNN.do"
			(at 0 0 180)
			(layer "F.Fab")
			(hide yes)
			(effects
				(font
					(size 1.27 1.27)
					(thickness 0.15)
				)
			)
		)
		(property "Description" "SMT Multilayer Ceramic Capacitor, 22uF, +/-20%, 25V, X5R, 0805 [2012 Metric]"
			(at 0 0 180)
			(layer "F.Fab")
			(hide yes)
			(effects
				(font
					(size 1.27 1.27)
					(thickness 0.15)
				)
			)
		)
		(property "MPN" "CL21A226MAYNNNE"
			(at 0 0 0)
			(unlocked yes)
			(layer "F.Fab")
			(hide yes)
			(effects
				(font
					(size 1 1)
					(thickness 0.15)
				)
			)
		)
		(property "Manufacturer" "Samsung Electro-Mechanics"
			(at 0 0 0)
			(unlocked yes)
			(layer "F.Fab")
			(hide yes)
			(effects
				(font
					(size 1 1)
					(thickness 0.15)
				)
			)
		)
		(property "License" "Apache-2.0"
			(at 0 0 0)
			(unlocked yes)
			(layer "F.Fab")
			(hide yes)
			(effects
				(font
					(size 1 1)
					(thickness 0.15)
				)
			)
		)
		(property "Author" "Antmicro"
			(at 0 0 0)
			(unlocked yes)
			(layer "F.Fab")
			(hide yes)
			(effects
				(font
					(size 1 1)
					(thickness 0.15)
				)
			)
		)
		(property "Val" "22u"
			(at 0 0 0)
			(unlocked yes)
			(layer "F.Fab")
			(hide yes)
			(effects
				(font
					(size 1 1)
					(thickness 0.15)
				)
			)
		)
		(property "Voltage" "25V"
			(at 0 0 0)
			(unlocked yes)
			(layer "F.Fab")
			(hide yes)
			(effects
				(font
					(size 1 1)
					(thickness 0.15)
				)
			)
		)
		(property "Dielectric" "X5R"
			(at 0 0 0)
			(unlocked yes)
			(layer "F.Fab")
			(hide yes)
			(effects
				(font
					(size 1 1)
					(thickness 0.15)
				)
			)
		)
		(property "Public" "False"
			(at 0 0 0)
			(unlocked yes)
			(layer "F.Fab")
			(hide yes)
			(effects
				(font
					(size 1 1)
					(thickness 0.15)
				)
			)
		)
		(sheetname "/SoM_Power/")
		(sheetfile "som_power.kicad_sch")
		(attr smd)
		(fp_line
			(start -0.3 -0.7)
			(end 0.3 -0.7)
			(stroke
				(width 0.15)
				(type solid)
			)
			(layer "F.SilkS")
		)
		(fp_line
			(start -0.3 0.7)
			(end 0.3 0.7)
			(stroke
				(width 0.15)
				(type solid)
			)
			(layer "F.SilkS")
		)
		(fp_poly
			(pts
				(xy 1.95 -0.9) (xy -1.95 -0.9) (xy -1.95 0.9) (xy 1.95 0.9)
			)
			(stroke
				(width 0.05)
				(type default)
			)
			(fill no)
			(layer "F.CrtYd")
		)
		(fp_poly
			(pts
				(xy -0.95 -0.675001) (xy 0.95 -0.675001) (xy 0.95 0.675001) (xy -0.95 0.675001)
			)
			(stroke
				(width 0.15)
				(type solid)
			)
			(fill no)
			(layer "F.Fab")
		)
		(fp_text user "${REFERENCE}"
			(at -1.899999 3.947 180)
			(layer "F.Fab")
			(effects
				(font
					(size 0.7 0.7)
					(thickness 0.15)
				)
				(justify right top)
			)
		)
		(fp_text user "License: Apache-2.0"
			(at -1.9 4.947 180)
			(layer "F.Fab")
			(effects
				(font
					(size 0.7 0.7)
					(thickness 0.15)
				)
				(justify right top)
			)
		)
		(fp_text user "Author: Antmicro"
			(at -1.9 5.947 180)
			(layer "F.Fab")
			(effects
				(font
					(size 0.7 0.7)
					(thickness 0.15)
				)
				(justify right top)
			)
		)
		(pad "1" smd roundrect
			(at -1.099999 0)
			(size 1.2 1.3)
			(layers "F.Cu" "F.Mask" "F.Paste")
			(roundrect_rratio 0.25)
			(net 1 "GND")
			(pintype "passive")
		)
		(pad "2" smd roundrect
			(at 1.099999 0)
			(size 1.2 1.3)
			(layers "F.Cu" "F.Mask" "F.Paste")
			(roundrect_rratio 0.25)
			(net 12 "SYS_VIN_HV")
			(pintype "passive")
		)
	)
	(footprint "antmicro-footprints:C_0402_1005Metric"
		(layer "F.Cu")
		(at 212.8 120.1 -90)
		(descr "Capacitor SMD 0402")
		(tags "capacitor SMD 0402")
		(property "Reference" "C90"
			(at -3 0.3 90)
			(layer "F.SilkS")
			(effects
				(font
					(size 0.7 0.7)
					(thickness 0.15)
				)
				(justify right top)
			)
		)
		(property "Value" "C_100n_0402"
			(at -1.022927 2.155213 90)
			(layer "F.Fab")
			(effects
				(font
					(size 0.7 0.7)
					(thickness 0.15)
				)
				(justify right top)
			)
		)
		(property "Datasheet" "https://www.murata.com/products/productdetail?partno=GRM155R61H104KE14%23"
			(at 0 0 90)
			(layer "F.Fab")
			(hide yes)
			(effects
				(font
					(size 1.27 1.27)
					(thickness 0.15)
				)
			)
		)
		(property "Description" "SMD Multilayer Ceramic Capacitor, 0.1 µF, 50 V, 0402 [1005 Metric], ± 10%, X5R, GRM Series"
			(at 0 0 90)
			(layer "F.Fab")
			(hide yes)
			(effects
				(font
					(size 1.27 1.27)
					(thickness 0.15)
				)
			)
		)
		(property "MPN" "GRM155R61H104KE14D"
			(at 0 0 270)
			(unlocked yes)
			(layer "F.Fab")
			(hide yes)
			(effects
				(font
					(size 1 1)
					(thickness 0.15)
				)
			)
		)
		(property "Val" "100n"
			(at 0 0 270)
			(unlocked yes)
			(layer "F.Fab")
			(hide yes)
			(effects
				(font
					(size 1 1)
					(thickness 0.15)
				)
			)
		)
		(property "Voltage" "50V"
			(at 0 0 270)
			(unlocked yes)
			(layer "F.Fab")
			(hide yes)
			(effects
				(font
					(size 1 1)
					(thickness 0.15)
				)
			)
		)
		(property "Dielectric" "X5R"
			(at 0 0 270)
			(unlocked yes)
			(layer "F.Fab")
			(hide yes)
			(effects
				(font
					(size 1 1)
					(thickness 0.15)
				)
			)
		)
		(property "Manufacturer" "Murata"
			(at 0 0 270)
			(unlocked yes)
			(layer "F.Fab")
			(hide yes)
			(effects
				(font
					(size 1 1)
					(thickness 0.15)
				)
			)
		)
		(property "License" "Apache-2.0"
			(at 0 0 270)
			(unlocked yes)
			(layer "F.Fab")
			(hide yes)
			(effects
				(font
					(size 1 1)
					(thickness 0.15)
				)
			)
		)
		(property "Author" "Antmicro"
			(at 0 0 270)
			(unlocked yes)
			(layer "F.Fab")
			(hide yes)
			(effects
				(font
					(size 1 1)
					(thickness 0.15)
				)
			)
		)
		(sheetname "/USB Hub/")
		(sheetfile "usb_hub.kicad_sch")
		(attr smd)
		(fp_poly
			(pts
				(xy -0.925 -0.47) (xy -0.925 0.47) (xy 0.925 0.47) (xy 0.925 -0.47)
			)
			(stroke
				(width 0.05)
				(type default)
			)
			(fill no)
			(layer "F.CrtYd")
		)
		(fp_line
			(start -0.494 0.248)
			(end -0.494 -0.25)
			(stroke
				(width 0.15)
				(type solid)
			)
			(layer "F.Fab")
		)
		(fp_line
			(start 0.504 0.248)
			(end -0.494 0.248)
			(stroke
				(width 0.15)
				(type solid)
			)
			(layer "F.Fab")
		)
		(fp_line
			(start -0.494 -0.25)
			(end 0.504 -0.25)
			(stroke
				(width 0.15)
				(type solid)
			)
			(layer "F.Fab")
		)
		(fp_line
			(start 0.504 -0.25)
			(end 0.504 0.248)
			(stroke
				(width 0.15)
				(type solid)
			)
			(layer "F.Fab")
		)
		(fp_text user "Author: Antmicro"
			(at -0.939 3.399 90)
			(layer "F.Fab")
			(effects
				(font
					(size 0.7 0.7)
					(thickness 0.15)
				)
				(justify right top)
			)
		)
		(fp_text user "${REFERENCE}"
			(at -0.939 4.599 90)
			(layer "F.Fab")
			(effects
				(font
					(size 0.7 0.7)
					(thickness 0.15)
				)
				(justify right top)
			)
		)
		(fp_text user "License: Apache-2.0"
			(at -0.939 5.799 90)
			(layer "F.Fab")
			(effects
				(font
					(size 0.7 0.7)
					(thickness 0.15)
				)
				(justify right top)
			)
		)
		(pad "1" smd roundrect
			(at -0.48 0 270)
			(size 0.59 0.64)
			(layers "F.Cu" "F.Mask" "F.Paste")
			(roundrect_rratio 0.25)
			(net 1 "GND")
			(pintype "passive")
		)
		(pad "2" smd roundrect
			(at 0.48 0 270)
			(size 0.59 0.64)
			(layers "F.Cu" "F.Mask" "F.Paste")
			(roundrect_rratio 0.25)
			(net 282 "+1V15")
			(pintype "passive")
		)
	)
	(footprint "antmicro-footprints:C_0402_1005Metric"
		(layer "F.Cu")
		(at 203.25 57.25 90)
		(descr "Capacitor SMD 0402")
		(tags "capacitor SMD 0402")
		(property "Reference" "C239"
			(at -2 -0.5 90)
			(layer "F.SilkS")
			(effects
				(font
					(size 0.7 0.7)
					(thickness 0.15)
				)
				(justify left bottom)
			)
		)
		(property "Value" "C_100n_0402"
			(at -1.022927 2.155213 90)
			(layer "F.Fab")
			(effects
				(font
					(size 0.7 0.7)
					(thickness 0.15)
				)
				(justify left bottom)
			)
		)
		(property "Datasheet" "https://www.murata.com/products/productdetail?partno=GRM155R61H104KE14%23"
			(at 0 0 90)
			(layer "F.Fab")
			(hide yes)
			(effects
				(font
					(size 1.27 1.27)
					(thickness 0.15)
				)
			)
		)
		(property "Description" "SMD Multilayer Ceramic Capacitor, 0.1 µF, 50 V, 0402 [1005 Metric], ± 10%, X5R, GRM Series"
			(at 0 0 90)
			(layer "F.Fab")
			(hide yes)
			(effects
				(font
					(size 1.27 1.27)
					(thickness 0.15)
				)
			)
		)
		(property "MPN" "GRM155R61H104KE14D"
			(at 0 0 90)
			(unlocked yes)
			(layer "F.Fab")
			(hide yes)
			(effects
				(font
					(size 1 1)
					(thickness 0.15)
				)
			)
		)
		(property "Val" "100n"
			(at 0 0 90)
			(unlocked yes)
			(layer "F.Fab")
			(hide yes)
			(effects
				(font
					(size 1 1)
					(thickness 0.15)
				)
			)
		)
		(property "Voltage" "50V"
			(at 0 0 90)
			(unlocked yes)
			(layer "F.Fab")
			(hide yes)
			(effects
				(font
					(size 1 1)
					(thickness 0.15)
				)
			)
		)
		(property "Dielectric" "X5R"
			(at 0 0 90)
			(unlocked yes)
			(layer "F.Fab")
			(hide yes)
			(effects
				(font
					(size 1 1)
					(thickness 0.15)
				)
			)
		)
		(property "Manufacturer" "Murata"
			(at 0 0 90)
			(unlocked yes)
			(layer "F.Fab")
			(hide yes)
			(effects
				(font
					(size 1 1)
					(thickness 0.15)
				)
			)
		)
		(property "License" "Apache-2.0"
			(at 0 0 90)
			(unlocked yes)
			(layer "F.Fab")
			(hide yes)
			(effects
				(font
					(size 1 1)
					(thickness 0.15)
				)
			)
		)
		(property "Author" "Antmicro"
			(at 0 0 90)
			(unlocked yes)
			(layer "F.Fab")
			(hide yes)
			(effects
				(font
					(size 1 1)
					(thickness 0.15)
				)
			)
		)
		(sheetname "/SoM_Power/")
		(sheetfile "som_power.kicad_sch")
		(attr smd)
		(fp_poly
			(pts
				(xy -0.925 -0.47) (xy 0.925 -0.47) (xy 0.925 0.47) (xy -0.925 0.47)
			)
			(stroke
				(width 0.05)
				(type default)
			)
			(fill no)
			(layer "F.CrtYd")
		)
		(fp_line
			(start 0.504 -0.25)
			(end 0.504 0.248)
			(stroke
				(width 0.15)
				(type solid)
			)
			(layer "F.Fab")
		)
		(fp_line
			(start -0.494 -0.25)
			(end 0.504 -0.25)
			(stroke
				(width 0.15)
				(type solid)
			)
			(layer "F.Fab")
		)
		(fp_line
			(start 0.504 0.248)
			(end -0.494 0.248)
			(stroke
				(width 0.15)
				(type solid)
			)
			(layer "F.Fab")
		)
		(fp_line
			(start -0.494 0.248)
			(end -0.494 -0.25)
			(stroke
				(width 0.15)
				(type solid)
			)
			(layer "F.Fab")
		)
		(fp_text user "License: Apache-2.0"
			(at -0.939 5.799 90)
			(layer "F.Fab")
			(effects
				(font
					(size 0.7 0.7)
					(thickness 0.15)
				)
				(justify left bottom)
			)
		)
		(fp_text user "${REFERENCE}"
			(at -0.939 4.599 90)
			(layer "F.Fab")
			(effects
				(font
					(size 0.7 0.7)
					(thickness 0.15)
				)
				(justify left bottom)
			)
		)
		(fp_text user "Author: Antmicro"
			(at -0.939 3.399 90)
			(layer "F.Fab")
			(effects
				(font
					(size 0.7 0.7)
					(thickness 0.15)
				)
				(justify left bottom)
			)
		)
		(pad "1" smd roundrect
			(at -0.48 0 90)
			(size 0.59 0.64)
			(layers "F.Cu" "F.Mask" "F.Paste")
			(roundrect_rratio 0.25)
			(net 1 "GND")
			(pintype "passive")
		)
		(pad "2" smd roundrect
			(at 0.48 0 90)
			(size 0.59 0.64)
			(layers "F.Cu" "F.Mask" "F.Paste")
			(roundrect_rratio 0.25)
			(net 495 "/SoM_Power/~{FORCE_RECOVERY}")
			(pintype "passive")
		)
	)
	(footprint "antmicro-footprints:USON-10_2.5x1mm_P0.5mm"
		(layer "F.Cu")
		(at 221.369 99.26 180)
		(descr "USON-10 2.5x1mm_ Pitch 0.5mm")
		(tags "USON-10 2.5x1mm Pitch 0.5mm")
		(property "Reference" "U26"
			(at -0.961 0.64 90)
			(layer "F.SilkS")
			(effects
				(font
					(size 0.7 0.7)
					(thickness 0.15)
				)
				(justify right top)
			)
		)
		(property "Value" "TPD4E05U06QDQARQ1"
			(at 0.018 2.499 0)
			(layer "F.Fab")
			(effects
				(font
					(size 0.7 0.7)
					(thickness 0.15)
				)
				(justify right top)
			)
		)
		(property "Datasheet" "https://www.ti.com/lit/ds/symlink/tpd4e05u06-q1.pdf?HQS=dis-mous-null-mousermode-dsf-pf-null-wwe&ts=1663591265741&ref_url=https%253A%252F%252Fwww.mouser.com%252F"
			(at 0 0 0)
			(layer "F.Fab")
			(hide yes)
			(effects
				(font
					(size 1.27 1.27)
					(thickness 0.15)
				)
			)
		)
		(property "Description" "TVS diode array, 12 kV, USON-10, 5.5 V, 0.5 pF"
			(at 0 0 0)
			(layer "F.Fab")
			(hide yes)
			(effects
				(font
					(size 1.27 1.27)
					(thickness 0.15)
				)
			)
		)
		(property "Manufacturer" "Texas Instruments"
			(at 0 0 180)
			(unlocked yes)
			(layer "F.Fab")
			(hide yes)
			(effects
				(font
					(size 1 1)
					(thickness 0.15)
				)
			)
		)
		(property "MPN" "TPD4E05U06QDQARQ1"
			(at 0 0 180)
			(unlocked yes)
			(layer "F.Fab")
			(hide yes)
			(effects
				(font
					(size 1 1)
					(thickness 0.15)
				)
			)
		)
		(property "Author" "Antmicro"
			(at 0 0 180)
			(unlocked yes)
			(layer "F.Fab")
			(hide yes)
			(effects
				(font
					(size 1 1)
					(thickness 0.15)
				)
			)
		)
		(property "License" "Apache-2.0"
			(at 0 0 180)
			(unlocked yes)
			(layer "F.Fab")
			(hide yes)
			(effects
				(font
					(size 1 1)
					(thickness 0.15)
				)
			)
		)
		(sheetname "/Recovery USB/")
		(sheetfile "recovery_usb.kicad_sch")
		(attr smd)
		(fp_line
			(start 0.498 1.398)
			(end -0.5 1.398)
			(stroke
				(width 0.15)
				(type solid)
			)
			(layer "F.SilkS")
		)
		(fp_line
			(start 0.498 -1.401)
			(end -0.5 -1.401)
			(stroke
				(width 0.15)
				(type solid)
			)
			(layer "F.SilkS")
		)
		(fp_circle
			(center -0.68 -1.27)
			(end -0.63 -1.27)
			(stroke
				(width 0.15)
				(type solid)
			)
			(fill yes)
			(layer "F.SilkS")
		)
		(fp_rect
			(start -0.8 -1.5)
			(end 0.8 1.499)
			(stroke
				(width 0.05)
				(type solid)
			)
			(fill no)
			(layer "F.CrtYd")
		)
		(fp_line
			(start 0.498 -1.25)
			(end 0.498 1.249)
			(stroke
				(width 0.15)
				(type solid)
			)
			(layer "F.Fab")
		)
		(fp_line
			(start 0.498 -1.25)
			(end -0.25 -1.25)
			(stroke
				(width 0.15)
				(type solid)
			)
			(layer "F.Fab")
		)
		(fp_line
			(start -0.25 -1.25)
			(end -0.5 -1)
			(stroke
				(width 0.15)
				(type solid)
			)
			(layer "F.Fab")
		)
		(fp_line
			(start -0.5 1.249)
			(end 0.498 1.249)
			(stroke
				(width 0.15)
				(type solid)
			)
			(layer "F.Fab")
		)
		(fp_line
			(start -0.5 -1)
			(end -0.5 1.249)
			(stroke
				(width 0.15)
				(type solid)
			)
			(layer "F.Fab")
		)
		(fp_text user "License: Apache-2.0"
			(at -0.802 6.9 0)
			(layer "F.Fab")
			(effects
				(font
					(size 0.7 0.7)
					(thickness 0.15)
				)
				(justify right top)
			)
		)
		(fp_text user "Author: Antmicro"
			(at -0.802 5.7 0)
			(layer "F.Fab")
			(effects
				(font
					(size 0.7 0.7)
					(thickness 0.15)
				)
				(justify right top)
			)
		)
		(fp_text user "${REFERENCE}"
			(at -0.802 4.498 0)
			(layer "F.Fab")
			(effects
				(font
					(size 0.7 0.7)
					(thickness 0.15)
				)
				(justify right top)
			)
		)
		(pad "1" smd roundrect
			(at -0.387 -1 90)
			(size 0.25 0.55)
			(layers "F.Cu" "F.Mask" "F.Paste")
			(roundrect_rratio 0.25)
			(net 807 "/Recovery USB/USBC2_RX2_N")
			(pintype "passive")
		)
		(pad "2" smd roundrect
			(at -0.387 -0.5 90)
			(size 0.25 0.55)
			(layers "F.Cu" "F.Mask" "F.Paste")
			(roundrect_rratio 0.25)
			(net 804 "/Recovery USB/USBC2_RX2_P")
			(pintype "passive")
		)
		(pad "3" smd roundrect
			(at -0.387 0 90)
			(size 0.4 0.55)
			(layers "F.Cu" "F.Mask" "F.Paste")
			(roundrect_rratio 0.25)
			(net 1 "GND")
			(pintype "power_in")
		)
		(pad "4" smd roundrect
			(at -0.387 0.498 90)
			(size 0.25 0.55)
			(layers "F.Cu" "F.Mask" "F.Paste")
			(roundrect_rratio 0.25)
			(net 241 "/Recovery USB/USBC2_CONN_TX2_N")
			(pintype "passive")
		)
		(pad "5" smd roundrect
			(at -0.387 0.998 90)
			(size 0.25 0.55)
			(layers "F.Cu" "F.Mask" "F.Paste")
			(roundrect_rratio 0.25)
			(net 270 "/Recovery USB/USBC2_CONN_TX2_P")
			(pintype "passive")
		)
		(pad "6" smd roundrect
			(at 0.385 0.998 90)
			(size 0.25 0.55)
			(layers "F.Cu" "F.Mask" "F.Paste")
			(roundrect_rratio 0.25)
			(net 270 "/Recovery USB/USBC2_CONN_TX2_P")
			(pintype "passive")
		)
		(pad "7" smd roundrect
			(at 0.385 0.498 90)
			(size 0.25 0.55)
			(layers "F.Cu" "F.Mask" "F.Paste")
			(roundrect_rratio 0.25)
			(net 241 "/Recovery USB/USBC2_CONN_TX2_N")
			(pintype "passive")
		)
		(pad "8" smd roundrect
			(at 0.385 0 90)
			(size 0.4 0.55)
			(layers "F.Cu" "F.Mask" "F.Paste")
			(roundrect_rratio 0.25)
			(net 1 "GND")
			(pintype "passive")
		)
		(pad "9" smd roundrect
			(at 0.385 -0.5 90)
			(size 0.25 0.55)
			(layers "F.Cu" "F.Mask" "F.Paste")
			(roundrect_rratio 0.25)
			(net 804 "/Recovery USB/USBC2_RX2_P")
			(pintype "passive")
		)
		(pad "10" smd roundrect
			(at 0.385 -1 90)
			(size 0.25 0.55)
			(layers "F.Cu" "F.Mask" "F.Paste")
			(roundrect_rratio 0.25)
			(net 807 "/Recovery USB/USBC2_RX2_N")
			(pintype "passive")
		)
	)
	(footprint "antmicro-footprints:C_0402_1005Metric"
		(layer "F.Cu")
		(at 210.119132 92.592 180)
		(descr "Capacitor SMD 0402")
		(tags "capacitor SMD 0402")
		(property "Reference" "C132"
			(at 0.859132 -0.438 0)
			(layer "F.SilkS")
			(effects
				(font
					(size 0.7 0.7)
					(thickness 0.15)
				)
				(justify right top)
			)
		)
		(property "Value" "C_100n_0402"
			(at -1.022927 2.155213 0)
			(layer "F.Fab")
			(effects
				(font
					(size 0.7 0.7)
					(thickness 0.15)
				)
				(justify right top)
			)
		)
		(property "Datasheet" "https://www.murata.com/products/productdetail?partno=GRM155R61H104KE14%23"
			(at 0 0 0)
			(layer "F.Fab")
			(hide yes)
			(effects
				(font
					(size 1.27 1.27)
					(thickness 0.15)
				)
			)
		)
		(property "Description" "SMD Multilayer Ceramic Capacitor, 0.1 µF, 50 V, 0402 [1005 Metric], ± 10%, X5R, GRM Series"
			(at 0 0 0)
			(layer "F.Fab")
			(hide yes)
			(effects
				(font
					(size 1.27 1.27)
					(thickness 0.15)
				)
			)
		)
		(property "Manufacturer" "Murata"
			(at 0 0 180)
			(unlocked yes)
			(layer "F.Fab")
			(hide yes)
			(effects
				(font
					(size 1 1)
					(thickness 0.15)
				)
			)
		)
		(property "MPN" "GRM155R61H104KE14D"
			(at 0 0 180)
			(unlocked yes)
			(layer "F.Fab")
			(hide yes)
			(effects
				(font
					(size 1 1)
					(thickness 0.15)
				)
			)
		)
		(property "Val" "100n"
			(at 0 0 180)
			(unlocked yes)
			(layer "F.Fab")
			(hide yes)
			(effects
				(font
					(size 1 1)
					(thickness 0.15)
				)
			)
		)
		(property "License" "Apache-2.0"
			(at 0 0 180)
			(unlocked yes)
			(layer "F.Fab")
			(hide yes)
			(effects
				(font
					(size 1 1)
					(thickness 0.15)
				)
			)
		)
		(property "Author" "Antmicro"
			(at 0 0 180)
			(unlocked yes)
			(layer "F.Fab")
			(hide yes)
			(effects
				(font
					(size 1 1)
					(thickness 0.15)
				)
			)
		)
		(property "Voltage" "50V"
			(at 0 0 180)
			(unlocked yes)
			(layer "F.Fab")
			(hide yes)
			(effects
				(font
					(size 1 1)
					(thickness 0.15)
				)
			)
		)
		(property "Dielectric" "X5R"
			(at 0 0 180)
			(unlocked yes)
			(layer "F.Fab")
			(hide yes)
			(effects
				(font
					(size 1 1)
					(thickness 0.15)
				)
			)
		)
		(sheetname "/USB DP Alt mode/")
		(sheetfile "usb_dp.kicad_sch")
		(attr smd)
		(fp_rect
			(start -0.925 -0.47)
			(end 0.925 0.47)
			(stroke
				(width 0.05)
				(type default)
			)
			(fill no)
			(layer "F.CrtYd")
		)
		(fp_line
			(start 0.504 0.248)
			(end -0.494 0.248)
			(stroke
				(width 0.15)
				(type solid)
			)
			(layer "F.Fab")
		)
		(fp_line
			(start 0.504 -0.25)
			(end 0.504 0.248)
			(stroke
				(width 0.15)
				(type solid)
			)
			(layer "F.Fab")
		)
		(fp_line
			(start -0.494 0.248)
			(end -0.494 -0.25)
			(stroke
				(width 0.15)
				(type solid)
			)
			(layer "F.Fab")
		)
		(fp_line
			(start -0.494 -0.25)
			(end 0.504 -0.25)
			(stroke
				(width 0.15)
				(type solid)
			)
			(layer "F.Fab")
		)
		(fp_text user "Author: Antmicro"
			(at -0.939 3.399 0)
			(layer "F.Fab")
			(effects
				(font
					(size 0.7 0.7)
					(thickness 0.15)
				)
				(justify right top)
			)
		)
		(fp_text user "${REFERENCE}"
			(at -0.939 4.599 0)
			(layer "F.Fab")
			(effects
				(font
					(size 0.7 0.7)
					(thickness 0.15)
				)
				(justify right top)
			)
		)
		(fp_text user "License: Apache-2.0"
			(at -0.939 5.799 0)
			(layer "F.Fab")
			(effects
				(font
					(size 0.7 0.7)
					(thickness 0.15)
				)
				(justify right top)
			)
		)
		(pad "1" smd roundrect
			(at -0.48 0 180)
			(size 0.59 0.64)
			(layers "F.Cu" "F.Mask" "F.Paste")
			(roundrect_rratio 0.25)
			(net 2 "+3V3")
			(pintype "passive")
		)
		(pad "2" smd roundrect
			(at 0.48 0 180)
			(size 0.59 0.64)
			(layers "F.Cu" "F.Mask" "F.Paste")
			(roundrect_rratio 0.25)
			(net 1 "GND")
			(pintype "passive")
		)
	)
	(footprint "antmicro-footprints:R_0402_1005Metric"
		(layer "F.Cu")
		(at 232.540532 82.71 180)
		(descr "Resistor SMD 0402")
		(tags "resistor SMD 0402")
		(property "Reference" "R156"
			(at -1.122484 -0.772697 0)
			(layer "F.SilkS")
			(effects
				(font
					(size 0.7 0.7)
					(thickness 0.15)
				)
				(justify right top)
			)
		)
		(property "Value" "R_470R_0402"
			(at -1.011843 1.772046 0)
			(layer "F.Fab")
			(effects
				(font
					(size 0.7 0.7)
					(thickness 0.15)
				)
				(justify right top)
			)
		)
		(property "Datasheet" "https://www.bourns.com/docs/product-datasheets/cr.pdf"
			(at 0 0 0)
			(layer "F.Fab")
			(hide yes)
			(effects
				(font
					(size 1.27 1.27)
					(thickness 0.15)
				)
			)
		)
		(property "Description" "SMD Chip Resistor, 470 ohm, ± 1%, 62.5 mW, 0402 [1005 Metric], Thick Film, General Purpose"
			(at 0 0 0)
			(layer "F.Fab")
			(hide yes)
			(effects
				(font
					(size 1.27 1.27)
					(thickness 0.15)
				)
			)
		)
		(property "MPN" "CR0402-FX-4700GLF"
			(at 0 0 180)
			(unlocked yes)
			(layer "F.Fab")
			(hide yes)
			(effects
				(font
					(size 1 1)
					(thickness 0.15)
				)
			)
		)
		(property "Manufacturer" "Bourns"
			(at 0 0 180)
			(unlocked yes)
			(layer "F.Fab")
			(hide yes)
			(effects
				(font
					(size 1 1)
					(thickness 0.15)
				)
			)
		)
		(property "License" "Apache-2.0"
			(at 0 0 180)
			(unlocked yes)
			(layer "F.Fab")
			(hide yes)
			(effects
				(font
					(size 1 1)
					(thickness 0.15)
				)
			)
		)
		(property "Author" "Antmicro"
			(at 0 0 180)
			(unlocked yes)
			(layer "F.Fab")
			(hide yes)
			(effects
				(font
					(size 1 1)
					(thickness 0.15)
				)
			)
		)
		(property "Val" "470R"
			(at 0 0 180)
			(unlocked yes)
			(layer "F.Fab")
			(hide yes)
			(effects
				(font
					(size 1 1)
					(thickness 0.15)
				)
			)
		)
		(property "Tolerance" "1%"
			(at 0 0 180)
			(unlocked yes)
			(layer "F.Fab")
			(hide yes)
			(effects
				(font
					(size 1 1)
					(thickness 0.15)
				)
			)
		)
		(sheetname "/USB Debug, PD/")
		(sheetfile "usb_debug_pd.kicad_sch")
		(attr smd)
		(fp_poly
			(pts
				(xy -0.925 -0.47) (xy 0.925 -0.47) (xy 0.925 0.47) (xy -0.925 0.47)
			)
			(stroke
				(width 0.05)
				(type default)
			)
			(fill no)
			(layer "F.CrtYd")
		)
		(fp_poly
			(pts
				(xy -0.5 -0.25) (xy 0.5 -0.25) (xy 0.5 0.25) (xy -0.5 0.25)
			)
			(stroke
				(width 0.15)
				(type solid)
			)
			(fill no)
			(layer "F.Fab")
		)
		(fp_text user "Author: Antmicro"
			(at -0.95 4.169 0)
			(layer "F.Fab")
			(effects
				(font
					(size 0.7 0.7)
					(thickness 0.15)
				)
				(justify right top)
			)
		)
		(fp_text user "License: Apache-2.0"
			(at -0.949999 5.169 0)
			(layer "F.Fab")
			(effects
				(font
					(size 0.7 0.7)
					(thickness 0.15)
				)
				(justify right top)
			)
		)
		(fp_text user "${REFERENCE}"
			(at -0.95 3.168 0)
			(layer "F.Fab")
			(effects
				(font
					(size 0.7 0.7)
					(thickness 0.15)
				)
				(justify right top)
			)
		)
		(pad "1" smd roundrect
			(at -0.48 0 180)
			(size 0.59 0.64)
			(layers "F.Cu" "F.Mask" "F.Paste")
			(roundrect_rratio 0.25)
			(net 1387 "Net-(D24-A)")
			(pintype "passive")
		)
		(pad "2" smd roundrect
			(at 0.48 0 180)
			(size 0.59 0.64)
			(layers "F.Cu" "F.Mask" "F.Paste")
			(roundrect_rratio 0.25)
			(net 176 "/USB Debug, PD/USBC0_VBUS")
			(pintype "passive")
		)
	)
	(footprint "antmicro-footprints:R_0805_2012Metric"
		(layer "F.Cu")
		(at 162.944468 96.225 180)
		(property "Reference" "R65"
			(at 1.944468 0.925 0)
			(layer "F.SilkS")
			(effects
				(font
					(size 0.7 0.7)
					(thickness 0.15)
				)
				(justify right top)
			)
		)
		(property "Value" "R_0R001_0805"
			(at 0 1.8 0)
			(layer "F.Fab")
			(effects
				(font
					(size 0.7 0.7)
					(thickness 0.15)
				)
				(justify right top)
			)
		)
		(property "Datasheet" "https://www.eaton.com/content/dam/eaton/products/electronic-components/resources/data-sheet/eaton-msma-automotive-smd-current-sense-resistor-metal-strip-data-sheet-elx1179.pdf"
			(at 0 0 0)
			(layer "F.Fab")
			(hide yes)
			(effects
				(font
					(size 1.27 1.27)
					(thickness 0.15)
				)
			)
		)
		(property "Description" "Current Sense Resistors - SMD MSMA, 0805 SIZE, 1/2 Watt, 1 mohm, 50 TCR MnCu Metal AEC-Q"
			(at 0 0 0)
			(layer "F.Fab")
			(hide yes)
			(effects
				(font
					(size 1.27 1.27)
					(thickness 0.15)
				)
			)
		)
		(property "MPN" "MSMA0805R0010FSM"
			(at 0 0 180)
			(unlocked yes)
			(layer "F.Fab")
			(hide yes)
			(effects
				(font
					(size 1 1)
					(thickness 0.15)
				)
			)
		)
		(property "Manufacturer" "Eaton"
			(at 0 0 180)
			(unlocked yes)
			(layer "F.Fab")
			(hide yes)
			(effects
				(font
					(size 1 1)
					(thickness 0.15)
				)
			)
		)
		(property "License" "Apache-2.0"
			(at 0 0 180)
			(unlocked yes)
			(layer "F.Fab")
			(hide yes)
			(effects
				(font
					(size 1 1)
					(thickness 0.15)
				)
			)
		)
		(property "Author" "Antmicro"
			(at 0 0 180)
			(unlocked yes)
			(layer "F.Fab")
			(hide yes)
			(effects
				(font
					(size 1 1)
					(thickness 0.15)
				)
			)
		)
		(property "Val" "0R001"
			(at 0 0 180)
			(unlocked yes)
			(layer "F.Fab")
			(hide yes)
			(effects
				(font
					(size 1 1)
					(thickness 0.15)
				)
			)
		)
		(property "Tolerance" "1%"
			(at 0 0 180)
			(unlocked yes)
			(layer "F.Fab")
			(hide yes)
			(effects
				(font
					(size 1 1)
					(thickness 0.15)
				)
			)
		)
		(property "Public" "False"
			(at 0 0 180)
			(unlocked yes)
			(layer "F.Fab")
			(hide yes)
			(effects
				(font
					(size 1 1)
					(thickness 0.15)
				)
			)
		)
		(component_classes
			(class "DCDC_SOM")
		)
		(sheetname "/DCDC/")
		(sheetfile "dcdc.kicad_sch")
		(attr smd)
		(fp_line
			(start -0.3 -0.701)
			(end 0.298 -0.701)
			(stroke
				(width 0.15)
				(type solid)
			)
			(layer "F.SilkS")
		)
		(fp_line
			(start -0.32 0.699)
			(end 0.28 0.699)
			(stroke
				(width 0.15)
				(type solid)
			)
			(layer "F.SilkS")
		)
		(fp_rect
			(start 1.95 -0.9)
			(end -1.95 0.9)
			(stroke
				(width 0.05)
				(type default)
			)
			(fill no)
			(layer "F.CrtYd")
		)
		(fp_line
			(start 0.949 -0.677)
			(end 0.949 0.675)
			(stroke
				(width 0.15)
				(type solid)
			)
			(layer "F.Fab")
		)
		(fp_line
			(start -0.951 0.68)
			(end 0.949 0.68)
			(stroke
				(width 0.15)
				(type solid)
			)
			(layer "F.Fab")
		)
		(fp_line
			(start -0.951 -0.677)
			(end -0.951 0.675)
			(stroke
				(width 0.15)
				(type solid)
			)
			(layer "F.Fab")
		)
		(fp_line
			(start -0.951 -0.682)
			(end 0.949 -0.682)
			(stroke
				(width 0.15)
				(type solid)
			)
			(layer "F.Fab")
		)
		(fp_text user "Author: Antmicro"
			(at -1.9 4.4 0)
			(layer "F.Fab")
			(effects
				(font
					(size 0.7 0.7)
					(thickness 0.15)
				)
				(justify right top)
			)
		)
		(fp_text user "License: Apache-2.0"
			(at -1.9 5.75 0)
			(layer "F.Fab")
			(effects
				(font
					(size 0.7 0.7)
					(thickness 0.15)
				)
				(justify right top)
			)
		)
		(fp_text user "${REFERENCE}"
			(at -1.9 3.1 0)
			(layer "F.Fab")
			(effects
				(font
					(size 0.7 0.7)
					(thickness 0.15)
				)
				(justify right top)
			)
		)
		(pad "1" smd roundrect
			(at -1.1 0 180)
			(size 1.2 1.3)
			(layers "F.Cu" "F.Mask" "F.Paste")
			(roundrect_rratio 0.25)
			(net 903 "/DCDC/16V_OUT")
			(pintype "passive")
		)
		(pad "2" smd roundrect
			(at 1.1 0 180)
			(size 1.2 1.3)
			(layers "F.Cu" "F.Mask" "F.Paste")
			(roundrect_rratio 0.25)
			(net 12 "SYS_VIN_HV")
			(pintype "passive")
		)
	)
	(footprint "antmicro-footprints:SOT-563"
		(layer "F.Cu")
		(at 190.08 127.36 90)
		(property "Reference" "U69"
			(at -0.94 -3.78 90)
			(layer "F.SilkS")
			(effects
				(font
					(size 0.7 0.7)
					(thickness 0.15)
				)
				(justify left bottom)
			)
		)
		(property "Value" "TPS564247DRLR"
			(at 0 2 90)
			(layer "F.Fab")
			(effects
				(font
					(size 0.7 0.7)
					(thickness 0.15)
				)
				(justify left bottom)
			)
		)
		(property "Datasheet" "https://www.ti.com/lit/ds/symlink/tps564247.pdf?ts=1713526387938&ref_url=https%253A%252F%252Fwww.mouser.pl%252F"
			(at 0 0 90)
			(layer "F.Fab")
			(hide yes)
			(effects
				(font
					(size 1.27 1.27)
					(thickness 0.15)
				)
			)
		)
		(property "Description" "Switching Voltage Regulators 3-V to 16-V input voltage, 4-A FCCM mode, synchronous buck converter in SOT-563 package 6-SOT-5X3 -40 to 125"
			(at 0 0 90)
			(layer "F.Fab")
			(hide yes)
			(effects
				(font
					(size 1.27 1.27)
					(thickness 0.15)
				)
			)
		)
		(property "MPN" "TPS564247DRLR"
			(at 0 0 90)
			(unlocked yes)
			(layer "F.Fab")
			(hide yes)
			(effects
				(font
					(size 1 1)
					(thickness 0.15)
				)
			)
		)
		(property "Author" "Antmicro"
			(at 0 0 90)
			(unlocked yes)
			(layer "F.Fab")
			(hide yes)
			(effects
				(font
					(size 1 1)
					(thickness 0.15)
				)
			)
		)
		(property "License" "Apache-2.0"
			(at 0 0 90)
			(unlocked yes)
			(layer "F.Fab")
			(hide yes)
			(effects
				(font
					(size 1 1)
					(thickness 0.15)
				)
			)
		)
		(property "Manufacturer" "Texas Instruments"
			(at 0 0 90)
			(unlocked yes)
			(layer "F.Fab")
			(hide yes)
			(effects
				(font
					(size 1 1)
					(thickness 0.15)
				)
			)
		)
		(component_classes
			(class "DCDC_1V15")
		)
		(sheetname "/DCDC/")
		(sheetfile "dcdc.kicad_sch")
		(attr smd)
		(fp_line
			(start 0.776 -0.974)
			(end 0.526 -0.974)
			(stroke
				(width 0.15)
				(type solid)
			)
			(layer "F.SilkS")
		)
		(fp_line
			(start 0.776 -0.974)
			(end 0.776 -0.778)
			(stroke
				(width 0.15)
				(type solid)
			)
			(layer "F.SilkS")
		)
		(fp_line
			(start -0.499 -0.974)
			(end -0.724 -0.778)
			(stroke
				(width 0.15)
				(type solid)
			)
			(layer "F.SilkS")
		)
		(fp_line
			(start 0.776 0.776)
			(end 0.776 0.972)
			(stroke
				(width 0.15)
				(type solid)
			)
			(layer "F.SilkS")
		)
		(fp_line
			(start -0.778 0.776)
			(end -0.778 0.949)
			(stroke
				(width 0.15)
				(type solid)
			)
			(layer "F.SilkS")
		)
		(fp_line
			(start -0.778 0.949)
			(end -0.424 0.949)
			(stroke
				(width 0.15)
				(type solid)
			)
			(layer "F.SilkS")
		)
		(fp_line
			(start 0.776 0.972)
			(end 0.526 0.972)
			(stroke
				(width 0.15)
				(type solid)
			)
			(layer "F.SilkS")
		)
		(fp_circle
			(center -0.903 -0.999)
			(end -0.952 -0.95)
			(stroke
				(width 0.15)
				(type solid)
			)
			(fill yes)
			(layer "F.SilkS")
		)
		(fp_rect
			(start 1.19 -1.12)
			(end -1.2 1.1)
			(stroke
				(width 0.05)
				(type solid)
			)
			(fill no)
			(layer "F.CrtYd")
		)
		(fp_line
			(start 0.651 -0.849)
			(end 0.651 0.847)
			(stroke
				(width 0.15)
				(type solid)
			)
			(layer "F.Fab")
		)
		(fp_line
			(start -0.453 -0.849)
			(end 0.651 -0.849)
			(stroke
				(width 0.15)
				(type solid)
			)
			(layer "F.Fab")
		)
		(fp_line
			(start -0.453 -0.849)
			(end -0.653 -0.678)
			(stroke
				(width 0.15)
				(type solid)
			)
			(layer "F.Fab")
		)
		(fp_line
			(start -0.653 -0.678)
			(end -0.653 0.847)
			(stroke
				(width 0.15)
				(type solid)
			)
			(layer "F.Fab")
		)
		(fp_line
			(start 0.651 0.847)
			(end -0.653 0.847)
			(stroke
				(width 0.15)
				(type solid)
			)
			(layer "F.Fab")
		)
		(fp_text user "License: Apache-2.0"
			(at -1.299 4.924 90)
			(layer "F.Fab")
			(effects
				(font
					(size 0.7 0.7)
					(thickness 0.15)
				)
				(justify left bottom)
			)
		)
		(fp_text user "Author: Antmicro"
			(at -1.299 6.124 90)
			(layer "F.Fab")
			(effects
				(font
					(size 0.7 0.7)
					(thickness 0.15)
				)
				(justify left bottom)
			)
		)
		(fp_text user "${REFERENCE}"
			(at -1.299 7.323 90)
			(layer "F.Fab")
			(effects
				(font
					(size 0.7 0.7)
					(thickness 0.15)
				)
				(justify left bottom)
			)
		)
		(pad "1" smd roundrect
			(at -0.749 -0.499)
			(size 0.3 0.6)
			(layers "F.Cu" "F.Mask" "F.Paste")
			(roundrect_rratio 0.25)
			(net 5 "+5V")
			(pinfunction "V_{IN}")
			(pintype "power_in")
		)
		(pad "2" smd roundrect
			(at -0.749 0.001)
			(size 0.3 0.6)
			(layers "F.Cu" "F.Mask" "F.Paste")
			(roundrect_rratio 0.25)
			(net 1034 "/DCDC/1V15_SW")
			(pinfunction "SW")
			(pintype "passive")
		)
		(pad "3" smd roundrect
			(at -0.749 0.497)
			(size 0.3 0.6)
			(layers "F.Cu" "F.Mask" "F.Paste")
			(roundrect_rratio 0.25)
			(net 1 "GND")
			(pinfunction "GND")
			(pintype "power_in")
		)
		(pad "4" smd roundrect
			(at 0.747 0.497)
			(size 0.3 0.6)
			(layers "F.Cu" "F.Mask" "F.Paste")
			(roundrect_rratio 0.25)
			(net 1 "GND")
			(pinfunction "AGND")
			(pintype "power_in")
		)
		(pad "5" smd roundrect
			(at 0.747 0.001)
			(size 0.3 0.6)
			(layers "F.Cu" "F.Mask" "F.Paste")
			(roundrect_rratio 0.25)
			(net 1293 "/DCDC/CARRIER_PWR_ON")
			(pinfunction "EN")
			(pintype "passive")
		)
		(pad "6" smd roundrect
			(at 0.747 -0.499)
			(size 0.3 0.6)
			(layers "F.Cu" "F.Mask" "F.Paste")
			(roundrect_rratio 0.25)
			(net 1232 "/DCDC/1V15_FB")
			(pinfunction "FB")
			(pintype "passive")
		)
	)
	(footprint "antmicro-footprints:R_0402_1005Metric"
		(layer "F.Cu")
		(at 232.540532 121.71 180)
		(descr "Resistor SMD 0402")
		(tags "resistor SMD 0402")
		(property "Reference" "R74"
			(at -1.122484 -0.772697 0)
			(layer "F.SilkS")
			(effects
				(font
					(size 0.7 0.7)
					(thickness 0.15)
				)
				(justify right top)
			)
		)
		(property "Value" "R_470R_0402"
			(at -1.011843 1.772046 0)
			(layer "F.Fab")
			(effects
				(font
					(size 0.7 0.7)
					(thickness 0.15)
				)
				(justify right top)
			)
		)
		(property "Datasheet" "https://www.bourns.com/docs/product-datasheets/cr.pdf"
			(at 0 0 0)
			(layer "F.Fab")
			(hide yes)
			(effects
				(font
					(size 1.27 1.27)
					(thickness 0.15)
				)
			)
		)
		(property "Description" "SMD Chip Resistor, 470 ohm, ± 1%, 62.5 mW, 0402 [1005 Metric], Thick Film, General Purpose"
			(at 0 0 0)
			(layer "F.Fab")
			(hide yes)
			(effects
				(font
					(size 1.27 1.27)
					(thickness 0.15)
				)
			)
		)
		(property "Manufacturer" "Bourns"
			(at 0 0 180)
			(unlocked yes)
			(layer "F.Fab")
			(hide yes)
			(effects
				(font
					(size 1 1)
					(thickness 0.15)
				)
			)
		)
		(property "MPN" "CR0402-FX-4700GLF"
			(at 0 0 180)
			(unlocked yes)
			(layer "F.Fab")
			(hide yes)
			(effects
				(font
					(size 1 1)
					(thickness 0.15)
				)
			)
		)
		(property "Val" "470R"
			(at 0 0 180)
			(unlocked yes)
			(layer "F.Fab")
			(hide yes)
			(effects
				(font
					(size 1 1)
					(thickness 0.15)
				)
			)
		)
		(property "License" "Apache-2.0"
			(at 0 0 180)
			(unlocked yes)
			(layer "F.Fab")
			(hide yes)
			(effects
				(font
					(size 1 1)
					(thickness 0.15)
				)
			)
		)
		(property "Author" "Antmicro"
			(at 0 0 180)
			(unlocked yes)
			(layer "F.Fab")
			(hide yes)
			(effects
				(font
					(size 1 1)
					(thickness 0.15)
				)
			)
		)
		(property "Tolerance" "1%"
			(at 0 0 180)
			(unlocked yes)
			(layer "F.Fab")
			(hide yes)
			(effects
				(font
					(size 1 1)
					(thickness 0.15)
				)
			)
		)
		(sheetname "/USB Hub/")
		(sheetfile "usb_hub.kicad_sch")
		(attr smd)
		(fp_poly
			(pts
				(xy -0.925 -0.47) (xy 0.925 -0.47) (xy 0.925 0.47) (xy -0.925 0.47)
			)
			(stroke
				(width 0.05)
				(type default)
			)
			(fill no)
			(layer "F.CrtYd")
		)
		(fp_poly
			(pts
				(xy -0.5 -0.25) (xy 0.5 -0.25) (xy 0.5 0.25) (xy -0.5 0.25)
			)
			(stroke
				(width 0.15)
				(type solid)
			)
			(fill no)
			(layer "F.Fab")
		)
		(fp_text user "Author: Antmicro"
			(at -0.95 4.169 0)
			(layer "F.Fab")
			(effects
				(font
					(size 0.7 0.7)
					(thickness 0.15)
				)
				(justify right top)
			)
		)
		(fp_text user "${REFERENCE}"
			(at -0.95 3.168 0)
			(layer "F.Fab")
			(effects
				(font
					(size 0.7 0.7)
					(thickness 0.15)
				)
				(justify right top)
			)
		)
		(fp_text user "License: Apache-2.0"
			(at -0.949999 5.169 0)
			(layer "F.Fab")
			(effects
				(font
					(size 0.7 0.7)
					(thickness 0.15)
				)
				(justify right top)
			)
		)
		(pad "1" smd roundrect
			(at -0.48 0 180)
			(size 0.59 0.64)
			(layers "F.Cu" "F.Mask" "F.Paste")
			(roundrect_rratio 0.25)
			(net 1389 "Net-(D47-A)")
			(pintype "passive")
		)
		(pad "2" smd roundrect
			(at 0.48 0 180)
			(size 0.59 0.64)
			(layers "F.Cu" "F.Mask" "F.Paste")
			(roundrect_rratio 0.25)
			(net 71 "/USB Hub/USBC3_VBUS")
			(pintype "passive")
		)
	)
	(footprint "antmicro-footprints:C_0402_1005Metric"
		(layer "F.Cu")
		(at 157.37 144.95)
		(descr "Capacitor SMD 0402")
		(tags "capacitor SMD 0402")
		(property "Reference" "C202"
			(at -1.54 -3.85 0)
			(layer "F.SilkS")
			(effects
				(font
					(size 0.7 0.7)
					(thickness 0.15)
				)
				(justify left bottom)
			)
		)
		(property "Value" "C_100n_0402"
			(at -1.022927 2.155213 0)
			(layer "F.Fab")
			(effects
				(font
					(size 0.7 0.7)
					(thickness 0.15)
				)
				(justify left bottom)
			)
		)
		(property "Datasheet" "https://www.murata.com/products/productdetail?partno=GRM155R61H104KE14%23"
			(at 0 0 0)
			(layer "F.Fab")
			(hide yes)
			(effects
				(font
					(size 1.27 1.27)
					(thickness 0.15)
				)
			)
		)
		(property "Description" "SMD Multilayer Ceramic Capacitor, 0.1 µF, 50 V, 0402 [1005 Metric], ± 10%, X5R, GRM Series"
			(at 0 0 0)
			(layer "F.Fab")
			(hide yes)
			(effects
				(font
					(size 1.27 1.27)
					(thickness 0.15)
				)
			)
		)
		(property "Manufacturer" "Murata"
			(at 0 0 0)
			(unlocked yes)
			(layer "F.Fab")
			(hide yes)
			(effects
				(font
					(size 1 1)
					(thickness 0.15)
				)
			)
		)
		(property "MPN" "GRM155R61H104KE14D"
			(at 0 0 0)
			(unlocked yes)
			(layer "F.Fab")
			(hide yes)
			(effects
				(font
					(size 1 1)
					(thickness 0.15)
				)
			)
		)
		(property "Val" "100n"
			(at 0 0 0)
			(unlocked yes)
			(layer "F.Fab")
			(hide yes)
			(effects
				(font
					(size 1 1)
					(thickness 0.15)
				)
			)
		)
		(property "License" "Apache-2.0"
			(at 0 0 0)
			(unlocked yes)
			(layer "F.Fab")
			(hide yes)
			(effects
				(font
					(size 1 1)
					(thickness 0.15)
				)
			)
		)
		(property "Author" "Antmicro"
			(at 0 0 0)
			(unlocked yes)
			(layer "F.Fab")
			(hide yes)
			(effects
				(font
					(size 1 1)
					(thickness 0.15)
				)
			)
		)
		(property "Voltage" "50V"
			(at 0 0 0)
			(unlocked yes)
			(layer "F.Fab")
			(hide yes)
			(effects
				(font
					(size 1 1)
					(thickness 0.15)
				)
			)
		)
		(property "Dielectric" "X5R"
			(at 0 0 0)
			(unlocked yes)
			(layer "F.Fab")
			(hide yes)
			(effects
				(font
					(size 1 1)
					(thickness 0.15)
				)
			)
		)
		(sheetname "/Peripherals/")
		(sheetfile "peripherals.kicad_sch")
		(attr smd)
		(fp_rect
			(start -0.925 -0.47)
			(end 0.925 0.47)
			(stroke
				(width 0.05)
				(type default)
			)
			(fill no)
			(layer "F.CrtYd")
		)
		(fp_line
			(start -0.494 -0.25)
			(end 0.504 -0.25)
			(stroke
				(width 0.15)
				(type solid)
			)
			(layer "F.Fab")
		)
		(fp_line
			(start -0.494 0.248)
			(end -0.494 -0.25)
			(stroke
				(width 0.15)
				(type solid)
			)
			(layer "F.Fab")
		)
		(fp_line
			(start 0.504 -0.25)
			(end 0.504 0.248)
			(stroke
				(width 0.15)
				(type solid)
			)
			(layer "F.Fab")
		)
		(fp_line
			(start 0.504 0.248)
			(end -0.494 0.248)
			(stroke
				(width 0.15)
				(type solid)
			)
			(layer "F.Fab")
		)
		(fp_text user "${REFERENCE}"
			(at -0.939 4.599 0)
			(layer "F.Fab")
			(effects
				(font
					(size 0.7 0.7)
					(thickness 0.15)
				)
				(justify left bottom)
			)
		)
		(fp_text user "Author: Antmicro"
			(at -0.939 3.399 0)
			(layer "F.Fab")
			(effects
				(font
					(size 0.7 0.7)
					(thickness 0.15)
				)
				(justify left bottom)
			)
		)
		(fp_text user "License: Apache-2.0"
			(at -0.939 5.799 0)
			(layer "F.Fab")
			(effects
				(font
					(size 0.7 0.7)
					(thickness 0.15)
				)
				(justify left bottom)
			)
		)
		(pad "1" smd roundrect
			(at -0.48 0)
			(size 0.59 0.64)
			(layers "F.Cu" "F.Mask" "F.Paste")
			(roundrect_rratio 0.25)
			(net 1 "GND")
			(pintype "passive")
		)
		(pad "2" smd roundrect
			(at 0.48 0)
			(size 0.59 0.64)
			(layers "F.Cu" "F.Mask" "F.Paste")
			(roundrect_rratio 0.25)
			(net 11 "+1V8")
			(pintype "passive")
		)
	)
	(footprint "antmicro-footprints:R_0402_1005Metric"
		(layer "F.Cu")
		(at 62.809 58.177 90)
		(descr "Resistor SMD 0402")
		(tags "resistor SMD 0402")
		(property "Reference" "R162"
			(at -1.429 -1.539 90)
			(layer "F.SilkS")
			(effects
				(font
					(size 0.7 0.7)
					(thickness 0.15)
				)
				(justify left bottom)
			)
		)
		(property "Value" "R_0R_0402"
			(at -1.011843 1.772047 90)
			(layer "F.Fab")
			(effects
				(font
					(size 0.7 0.7)
					(thickness 0.15)
				)
				(justify left bottom)
			)
		)
		(property "Datasheet" "https://industrial.panasonic.com/cdbs/www-data/pdf/RDA0000/AOA0000C301.pdf"
			(at 0 0 90)
			(layer "F.Fab")
			(hide yes)
			(effects
				(font
					(size 1.27 1.27)
					(thickness 0.15)
				)
			)
		)
		(property "Description" "SMD Chip Resistor, Jumper, 0 ohm, 100 mW, 0402 [1005 Metric], Thick Film, General Purpose"
			(at 0 0 90)
			(layer "F.Fab")
			(hide yes)
			(effects
				(font
					(size 1.27 1.27)
					(thickness 0.15)
				)
			)
		)
		(property "Manufacturer" "Panasonic"
			(at 0 0 90)
			(unlocked yes)
			(layer "F.Fab")
			(hide yes)
			(effects
				(font
					(size 1 1)
					(thickness 0.15)
				)
			)
		)
		(property "MPN" "ERJ2GE0R00X"
			(at 0 0 90)
			(unlocked yes)
			(layer "F.Fab")
			(hide yes)
			(effects
				(font
					(size 1 1)
					(thickness 0.15)
				)
			)
		)
		(property "Val" "0R"
			(at 0 0 90)
			(unlocked yes)
			(layer "F.Fab")
			(hide yes)
			(effects
				(font
					(size 1 1)
					(thickness 0.15)
				)
			)
		)
		(property "License" "Apache-2.0"
			(at 0 0 90)
			(unlocked yes)
			(layer "F.Fab")
			(hide yes)
			(effects
				(font
					(size 1 1)
					(thickness 0.15)
				)
			)
		)
		(property "Author" "Antmicro"
			(at 0 0 90)
			(unlocked yes)
			(layer "F.Fab")
			(hide yes)
			(effects
				(font
					(size 1 1)
					(thickness 0.15)
				)
			)
		)
		(property "Tolerance" "~"
			(at 0 0 90)
			(unlocked yes)
			(layer "F.Fab")
			(hide yes)
			(effects
				(font
					(size 1 1)
					(thickness 0.15)
				)
			)
		)
		(property "Current" "1A"
			(at 0 0 90)
			(unlocked yes)
			(layer "F.Fab")
			(hide yes)
			(effects
				(font
					(size 1 1)
					(thickness 0.15)
				)
			)
		)
		(sheetname "/CSI/")
		(sheetfile "csi.kicad_sch")
		(attr smd)
		(fp_rect
			(start -0.925 -0.47)
			(end 0.925 0.47)
			(stroke
				(width 0.05)
				(type default)
			)
			(fill no)
			(layer "F.CrtYd")
		)
		(fp_rect
			(start -0.5 -0.25)
			(end 0.5 0.25)
			(stroke
				(width 0.15)
				(type solid)
			)
			(fill no)
			(layer "F.Fab")
		)
		(fp_text user "Author: Antmicro"
			(at -0.95 4.169 90)
			(layer "F.Fab")
			(effects
				(font
					(size 0.7 0.7)
					(thickness 0.15)
				)
				(justify left bottom)
			)
		)
		(fp_text user "${REFERENCE}"
			(at -0.95 3.168 90)
			(layer "F.Fab")
			(effects
				(font
					(size 0.7 0.7)
					(thickness 0.15)
				)
				(justify left bottom)
			)
		)
		(fp_text user "License: Apache-2.0"
			(at -0.95 5.169 90)
			(layer "F.Fab")
			(effects
				(font
					(size 0.7 0.7)
					(thickness 0.15)
				)
				(justify left bottom)
			)
		)
		(pad "1" smd roundrect
			(at -0.48 0 90)
			(size 0.59 0.64)
			(layers "F.Cu" "F.Mask" "F.Paste")
			(roundrect_rratio 0.25)
			(net 982 "/CSI/I2C_MUX_SDA")
			(pintype "passive")
		)
		(pad "2" smd roundrect
			(at 0.48 0 90)
			(size 0.59 0.64)
			(layers "F.Cu" "F.Mask" "F.Paste")
			(roundrect_rratio 0.25)
			(net 981 "/CSI/I2C_{CAM}.SDA")
			(pintype "passive")
		)
	)
	(footprint "antmicro-footprints:R_0402_1005Metric"
		(layer "F.Cu")
		(at 92.7 118.1 180)
		(descr "Resistor SMD 0402")
		(tags "resistor SMD 0402")
		(property "Reference" "R49"
			(at -1.1 -1.5 180)
			(layer "F.SilkS")
			(effects
				(font
					(size 0.7 0.7)
					(thickness 0.15)
				)
				(justify left bottom)
			)
		)
		(property "Value" "R_0R_0402"
			(at -1.011843 1.772046 180)
			(layer "F.Fab")
			(effects
				(font
					(size 0.7 0.7)
					(thickness 0.15)
				)
				(justify left bottom)
			)
		)
		(property "Datasheet" "https://industrial.panasonic.com/cdbs/www-data/pdf/RDA0000/AOA0000C301.pdf"
			(at 0 0 180)
			(layer "F.Fab")
			(hide yes)
			(effects
				(font
					(size 1.27 1.27)
					(thickness 0.15)
				)
			)
		)
		(property "Description" "SMD Chip Resistor, Jumper, 0 ohm, 100 mW, 0402 [1005 Metric], Thick Film, General Purpose"
			(at 0 0 180)
			(layer "F.Fab")
			(hide yes)
			(effects
				(font
					(size 1.27 1.27)
					(thickness 0.15)
				)
			)
		)
		(property "MPN" "ERJ2GE0R00X"
			(at 0 0 180)
			(unlocked yes)
			(layer "F.Fab")
			(hide yes)
			(effects
				(font
					(size 1 1)
					(thickness 0.15)
				)
			)
		)
		(property "Manufacturer" "Panasonic"
			(at 0 0 180)
			(unlocked yes)
			(layer "F.Fab")
			(hide yes)
			(effects
				(font
					(size 1 1)
					(thickness 0.15)
				)
			)
		)
		(property "License" "Apache-2.0"
			(at 0 0 180)
			(unlocked yes)
			(layer "F.Fab")
			(hide yes)
			(effects
				(font
					(size 1 1)
					(thickness 0.15)
				)
			)
		)
		(property "Author" "Antmicro"
			(at 0 0 180)
			(unlocked yes)
			(layer "F.Fab")
			(hide yes)
			(effects
				(font
					(size 1 1)
					(thickness 0.15)
				)
			)
		)
		(property "Val" "0R"
			(at 0 0 180)
			(unlocked yes)
			(layer "F.Fab")
			(hide yes)
			(effects
				(font
					(size 1 1)
					(thickness 0.15)
				)
			)
		)
		(property "Tolerance" "~"
			(at 0 0 180)
			(unlocked yes)
			(layer "F.Fab")
			(hide yes)
			(effects
				(font
					(size 1 1)
					(thickness 0.15)
				)
			)
		)
		(property "Current" "1A"
			(at 0 0 180)
			(unlocked yes)
			(layer "F.Fab")
			(hide yes)
			(effects
				(font
					(size 1 1)
					(thickness 0.15)
				)
			)
		)
		(sheetname "/Expansion connector/")
		(sheetfile "expansion_connector.kicad_sch")
		(attr smd)
		(fp_poly
			(pts
				(xy -0.925 -0.47) (xy 0.925 -0.47) (xy 0.925 0.47) (xy -0.925 0.47)
			)
			(stroke
				(width 0.05)
				(type default)
			)
			(fill no)
			(layer "F.CrtYd")
		)
		(fp_poly
			(pts
				(xy -0.5 -0.25) (xy 0.5 -0.25) (xy 0.5 0.25) (xy -0.5 0.25)
			)
			(stroke
				(width 0.15)
				(type solid)
			)
			(fill no)
			(layer "F.Fab")
		)
		(fp_text user "${REFERENCE}"
			(at -0.95 3.168 180)
			(layer "F.Fab")
			(effects
				(font
					(size 0.7 0.7)
					(thickness 0.15)
				)
				(justify left bottom)
			)
		)
		(fp_text user "Author: Antmicro"
			(at -0.95 4.169 180)
			(layer "F.Fab")
			(effects
				(font
					(size 0.7 0.7)
					(thickness 0.15)
				)
				(justify left bottom)
			)
		)
		(fp_text user "License: Apache-2.0"
			(at -0.949999 5.169 180)
			(layer "F.Fab")
			(effects
				(font
					(size 0.7 0.7)
					(thickness 0.15)
				)
				(justify left bottom)
			)
		)
		(pad "1" smd roundrect
			(at -0.48 0 180)
			(size 0.59 0.64)
			(layers "F.Cu" "F.Mask" "F.Paste")
			(roundrect_rratio 0.25)
			(net 637 "/Expansion connector/PCIe_{C2x1}.RX0-")
			(pintype "passive")
		)
		(pad "2" smd roundrect
			(at 0.48 0 180)
			(size 0.59 0.64)
			(layers "F.Cu" "F.Mask" "F.Paste")
			(roundrect_rratio 0.25)
			(net 728 "/Expansion connector/PER0_C2_P")
			(pintype "passive")
		)
	)
	(footprint "antmicro-footprints:SOT-523"
		(layer "F.Cu")
		(at 138.57 133.45 -90)
		(property "Reference" "Q10"
			(at -1.15 4.37 90)
			(layer "F.SilkS")
			(effects
				(font
					(size 0.7 0.7)
					(thickness 0.15)
				)
				(justify right top)
			)
		)
		(property "Value" "DMG1012T-7"
			(at 0.1 1.824 90)
			(layer "F.Fab")
			(effects
				(font
					(size 0.7 0.7)
					(thickness 0.15)
				)
				(justify right top)
			)
		)
		(property "Datasheet" "https://www.diodes.com/assets/Datasheets/ds31783.pdf"
			(at 0 0 90)
			(layer "F.Fab")
			(hide yes)
			(effects
				(font
					(size 1.27 1.27)
					(thickness 0.15)
				)
			)
		)
		(property "Description" "Power MOSFET, N Channel, 20 V, 630 mA, 0.3 ohm, SOT-523, Surface Mount"
			(at 0 0 90)
			(layer "F.Fab")
			(hide yes)
			(effects
				(font
					(size 1.27 1.27)
					(thickness 0.15)
				)
			)
		)
		(property "MPN" "DMG1012T-7"
			(at 0 0 90)
			(unlocked yes)
			(layer "F.Fab")
			(hide yes)
			(effects
				(font
					(size 1 1)
					(thickness 0.15)
				)
			)
		)
		(property "Manufacturer" "Diodes Incorporated"
			(at 0 0 90)
			(unlocked yes)
			(layer "F.Fab")
			(hide yes)
			(effects
				(font
					(size 1 1)
					(thickness 0.15)
				)
			)
		)
		(property "Author" "Antmicro"
			(at 0 0 90)
			(unlocked yes)
			(layer "F.Fab")
			(hide yes)
			(effects
				(font
					(size 1 1)
					(thickness 0.15)
				)
			)
		)
		(property "License" "Apache-2.0"
			(at 0 0 90)
			(unlocked yes)
			(layer "F.Fab")
			(hide yes)
			(effects
				(font
					(size 1 1)
					(thickness 0.15)
				)
			)
		)
		(sheetname "/SoM_Power/")
		(sheetfile "som_power.kicad_sch")
		(attr smd)
		(fp_line
			(start -0.927 -0.051)
			(end -0.927 -0.351)
			(stroke
				(width 0.15)
				(type solid)
			)
			(layer "F.SilkS")
		)
		(fp_line
			(start -0.927 -0.351)
			(end -0.725 -0.551)
			(stroke
				(width 0.15)
				(type solid)
			)
			(layer "F.SilkS")
		)
		(fp_line
			(start -0.725 -0.551)
			(end -0.277 -0.551)
			(stroke
				(width 0.15)
				(type solid)
			)
			(layer "F.SilkS")
		)
		(fp_line
			(start -0.277 -0.551)
			(end -0.277 -0.75)
			(stroke
				(width 0.15)
				(type solid)
			)
			(layer "F.SilkS")
		)
		(fp_circle
			(center -0.9652 0.9652)
			(end -0.9152 0.9652)
			(stroke
				(width 0.15)
				(type solid)
			)
			(fill yes)
			(layer "F.SilkS")
		)
		(fp_line
			(start -1.12 1.15)
			(end 1.1 1.15)
			(stroke
				(width 0.05)
				(type solid)
			)
			(layer "F.CrtYd")
		)
		(fp_line
			(start -1.12 -1.16)
			(end -1.12 1.15)
			(stroke
				(width 0.05)
				(type solid)
			)
			(layer "F.CrtYd")
		)
		(fp_line
			(start -1.12 -1.16)
			(end 1.1 -1.16)
			(stroke
				(width 0.05)
				(type solid)
			)
			(layer "F.CrtYd")
		)
		(fp_line
			(start 1.1 -1.16)
			(end 1.1 1.15)
			(stroke
				(width 0.05)
				(type solid)
			)
			(layer "F.CrtYd")
		)
		(fp_line
			(start 0.8 0.424)
			(end -0.802 0.424)
			(stroke
				(width 0.15)
				(type solid)
			)
			(layer "F.Fab")
		)
		(fp_line
			(start -0.802 -0.276)
			(end -0.802 0.424)
			(stroke
				(width 0.15)
				(type solid)
			)
			(layer "F.Fab")
		)
		(fp_line
			(start -0.652 -0.425)
			(end -0.802 -0.276)
			(stroke
				(width 0.15)
				(type solid)
			)
			(layer "F.Fab")
		)
		(fp_line
			(start 0.8 -0.425)
			(end 0.8 0.424)
			(stroke
				(width 0.15)
				(type solid)
			)
			(layer "F.Fab")
		)
		(fp_line
			(start 0.8 -0.425)
			(end -0.652 -0.425)
			(stroke
				(width 0.15)
				(type solid)
			)
			(layer "F.Fab")
		)
		(fp_circle
			(center -0.9652 0.9652)
			(end -0.9144 0.9652)
			(stroke
				(width 0.15)
				(type solid)
			)
			(fill no)
			(layer "F.Fab")
		)
		(fp_text user "Author: Antmicro"
			(at -1.12 6.224 90)
			(layer "F.Fab")
			(effects
				(font
					(size 0.7 0.7)
					(thickness 0.15)
				)
				(justify right top)
			)
		)
		(fp_text user "License: Apache-2.0"
			(at -1.12 5.024 90)
			(layer "F.Fab")
			(effects
				(font
					(size 0.7 0.7)
					(thickness 0.15)
				)
				(justify right top)
			)
		)
		(fp_text user "${REFERENCE}"
			(at -1.12 3.824 90)
			(layer "F.Fab")
			(effects
				(font
					(size 0.7 0.7)
					(thickness 0.15)
				)
				(justify right top)
			)
		)
		(pad "1" smd rect
			(at -0.5 0.65 270)
			(size 0.4 0.51)
			(layers "F.Cu" "F.Mask" "F.Paste")
			(net 883 "Net-(Q10-G)")
			(pinfunction "G")
			(pintype "input")
		)
		(pad "2" smd rect
			(at 0.498 0.65 270)
			(size 0.4 0.51)
			(layers "F.Cu" "F.Mask" "F.Paste")
			(net 1 "GND")
			(pinfunction "S")
			(pintype "passive")
		)
		(pad "3" smd rect
			(at 0 -0.652 270)
			(size 0.4 0.51)
			(layers "F.Cu" "F.Mask" "F.Paste")
			(net 885 "Net-(Q10-D)")
			(pinfunction "D")
			(pintype "passive")
		)
	)
	(footprint "antmicro-footprints:R_0402_1005Metric"
		(layer "F.Cu")
		(at 88 65.45)
		(descr "Resistor SMD 0402")
		(tags "resistor SMD 0402")
		(property "Reference" "R298"
			(at -19.18 9.49 0)
			(layer "F.SilkS")
			(effects
				(font
					(size 0.7 0.7)
					(thickness 0.15)
				)
				(justify left bottom)
			)
		)
		(property "Value" "R_0R_0402"
			(at -1.011843 1.772046 0)
			(layer "F.Fab")
			(effects
				(font
					(size 0.7 0.7)
					(thickness 0.15)
				)
				(justify left bottom)
			)
		)
		(property "Datasheet" "https://industrial.panasonic.com/cdbs/www-data/pdf/RDA0000/AOA0000C301.pdf"
			(at 0 0 0)
			(layer "F.Fab")
			(hide yes)
			(effects
				(font
					(size 1.27 1.27)
					(thickness 0.15)
				)
			)
		)
		(property "Description" "SMD Chip Resistor, Jumper, 0 ohm, 100 mW, 0402 [1005 Metric], Thick Film, General Purpose"
			(at 0 0 0)
			(layer "F.Fab")
			(hide yes)
			(effects
				(font
					(size 1.27 1.27)
					(thickness 0.15)
				)
			)
		)
		(property "MPN" "ERJ2GE0R00X"
			(at 0 0 0)
			(unlocked yes)
			(layer "F.Fab")
			(hide yes)
			(effects
				(font
					(size 1 1)
					(thickness 0.15)
				)
			)
		)
		(property "Manufacturer" "Panasonic"
			(at 0 0 0)
			(unlocked yes)
			(layer "F.Fab")
			(hide yes)
			(effects
				(font
					(size 1 1)
					(thickness 0.15)
				)
			)
		)
		(property "License" "Apache-2.0"
			(at 0 0 0)
			(unlocked yes)
			(layer "F.Fab")
			(hide yes)
			(effects
				(font
					(size 1 1)
					(thickness 0.15)
				)
			)
		)
		(property "Author" "Antmicro"
			(at 0 0 0)
			(unlocked yes)
			(layer "F.Fab")
			(hide yes)
			(effects
				(font
					(size 1 1)
					(thickness 0.15)
				)
			)
		)
		(property "Val" "0R"
			(at 0 0 0)
			(unlocked yes)
			(layer "F.Fab")
			(hide yes)
			(effects
				(font
					(size 1 1)
					(thickness 0.15)
				)
			)
		)
		(property "Tolerance" "~"
			(at 0 0 0)
			(unlocked yes)
			(layer "F.Fab")
			(hide yes)
			(effects
				(font
					(size 1 1)
					(thickness 0.15)
				)
			)
		)
		(property "Current" "1A"
			(at 0 0 0)
			(unlocked yes)
			(layer "F.Fab")
			(hide yes)
			(effects
				(font
					(size 1 1)
					(thickness 0.15)
				)
			)
		)
		(sheetname "/SoM_Power/")
		(sheetfile "som_power.kicad_sch")
		(attr smd)
		(fp_poly
			(pts
				(xy -0.925 -0.47) (xy -0.925 0.47) (xy 0.925 0.47) (xy 0.925 -0.47)
			)
			(stroke
				(width 0.05)
				(type default)
			)
			(fill no)
			(layer "F.CrtYd")
		)
		(fp_poly
			(pts
				(xy -0.5 -0.25) (xy -0.5 0.25) (xy 0.5 0.25) (xy 0.5 -0.25)
			)
			(stroke
				(width 0.15)
				(type solid)
			)
			(fill no)
			(layer "F.Fab")
		)
		(fp_text user "${REFERENCE}"
			(at -0.95 3.168 0)
			(layer "F.Fab")
			(effects
				(font
					(size 0.7 0.7)
					(thickness 0.15)
				)
				(justify left bottom)
			)
		)
		(fp_text user "Author: Antmicro"
			(at -0.95 4.169 0)
			(layer "F.Fab")
			(effects
				(font
					(size 0.7 0.7)
					(thickness 0.15)
				)
				(justify left bottom)
			)
		)
		(fp_text user "License: Apache-2.0"
			(at -0.949999 5.169 0)
			(layer "F.Fab")
			(effects
				(font
					(size 0.7 0.7)
					(thickness 0.15)
				)
				(justify left bottom)
			)
		)
		(pad "1" smd roundrect
			(at -0.48 0)
			(size 0.59 0.64)
			(layers "F.Cu" "F.Mask" "F.Paste")
			(roundrect_rratio 0.25)
			(net 888 "Net-(Q18-D)")
			(pintype "passive")
		)
		(pad "2" smd roundrect
			(at 0.48 0)
			(size 0.59 0.64)
			(layers "F.Cu" "F.Mask" "F.Paste")
			(roundrect_rratio 0.25)
			(net 1032 "/SoM_Power/~{FORCE_SHDN}")
			(pintype "passive")
		)
	)
	(footprint "antmicro-footprints:C_0805_2012Metric"
		(layer "F.Cu")
		(at 164.054468 93.31 -90)
		(descr "Capacitor SMD 0805")
		(tags "capacitor SMD 0805")
		(property "Reference" "C260"
			(at -4.71 0.454468 90)
			(layer "F.SilkS")
			(effects
				(font
					(size 0.7 0.7)
					(thickness 0.15)
				)
				(justify right top)
			)
		)
		(property "Value" "C_22u_25V_0805"
			(at -2.055717 1.963152 90)
			(layer "F.Fab")
			(effects
				(font
					(size 0.7 0.7)
					(thickness 0.15)
				)
				(justify right top)
			)
		)
		(property "Datasheet" "https://product.samsungsem.com/mlcc/CL21A226MAYNNN.do"
			(at 0 0 90)
			(layer "F.Fab")
			(hide yes)
			(effects
				(font
					(size 1.27 1.27)
					(thickness 0.15)
				)
			)
		)
		(property "Description" "SMT Multilayer Ceramic Capacitor, 22uF, +/-20%, 25V, X5R, 0805 [2012 Metric]"
			(at 0 0 90)
			(layer "F.Fab")
			(hide yes)
			(effects
				(font
					(size 1.27 1.27)
					(thickness 0.15)
				)
			)
		)
		(property "MPN" "CL21A226MAYNNNE"
			(at 0 0 270)
			(unlocked yes)
			(layer "F.Fab")
			(hide yes)
			(effects
				(font
					(size 1 1)
					(thickness 0.15)
				)
			)
		)
		(property "Manufacturer" "Samsung Electro-Mechanics"
			(at 0 0 270)
			(unlocked yes)
			(layer "F.Fab")
			(hide yes)
			(effects
				(font
					(size 1 1)
					(thickness 0.15)
				)
			)
		)
		(property "License" "Apache-2.0"
			(at 0 0 270)
			(unlocked yes)
			(layer "F.Fab")
			(hide yes)
			(effects
				(font
					(size 1 1)
					(thickness 0.15)
				)
			)
		)
		(property "Author" "Antmicro"
			(at 0 0 270)
			(unlocked yes)
			(layer "F.Fab")
			(hide yes)
			(effects
				(font
					(size 1 1)
					(thickness 0.15)
				)
			)
		)
		(property "Val" "22u"
			(at 0 0 270)
			(unlocked yes)
			(layer "F.Fab")
			(hide yes)
			(effects
				(font
					(size 1 1)
					(thickness 0.15)
				)
			)
		)
		(property "Voltage" "25V"
			(at 0 0 270)
			(unlocked yes)
			(layer "F.Fab")
			(hide yes)
			(effects
				(font
					(size 1 1)
					(thickness 0.15)
				)
			)
		)
		(property "Dielectric" "X5R"
			(at 0 0 270)
			(unlocked yes)
			(layer "F.Fab")
			(hide yes)
			(effects
				(font
					(size 1 1)
					(thickness 0.15)
				)
			)
		)
		(property "Public" "False"
			(at 0 0 270)
			(unlocked yes)
			(layer "F.Fab")
			(hide yes)
			(effects
				(font
					(size 1 1)
					(thickness 0.15)
				)
			)
		)
		(component_classes
			(class "DCDC_SOM")
		)
		(sheetname "/DCDC/")
		(sheetfile "dcdc.kicad_sch")
		(attr smd)
		(fp_line
			(start -0.3 0.7)
			(end 0.3 0.7)
			(stroke
				(width 0.15)
				(type solid)
			)
			(layer "F.SilkS")
		)
		(fp_line
			(start -0.3 -0.7)
			(end 0.3 -0.7)
			(stroke
				(width 0.15)
				(type solid)
			)
			(layer "F.SilkS")
		)
		(fp_rect
			(start 1.95 -0.9)
			(end -1.95 0.9)
			(stroke
				(width 0.05)
				(type default)
			)
			(fill no)
			(layer "F.CrtYd")
		)
		(fp_rect
			(start -0.95 -0.675)
			(end 0.95 0.675)
			(stroke
				(width 0.15)
				(type solid)
			)
			(fill no)
			(layer "F.Fab")
		)
		(fp_text user "${REFERENCE}"
			(at -1.9 3.947 90)
			(layer "F.Fab")
			(effects
				(font
					(size 0.7 0.7)
					(thickness 0.15)
				)
				(justify right top)
			)
		)
		(fp_text user "License: Apache-2.0"
			(at -1.9 4.947 90)
			(layer "F.Fab")
			(effects
				(font
					(size 0.7 0.7)
					(thickness 0.15)
				)
				(justify right top)
			)
		)
		(fp_text user "Author: Antmicro"
			(at -1.9 5.947 90)
			(layer "F.Fab")
			(effects
				(font
					(size 0.7 0.7)
					(thickness 0.15)
				)
				(justify right top)
			)
		)
		(pad "1" smd roundrect
			(at -1.1 0 270)
			(size 1.2 1.3)
			(layers "F.Cu" "F.Mask" "F.Paste")
			(roundrect_rratio 0.25)
			(net 1 "GND")
			(pintype "passive")
		)
		(pad "2" smd roundrect
			(at 1.1 0 270)
			(size 1.2 1.3)
			(layers "F.Cu" "F.Mask" "F.Paste")
			(roundrect_rratio 0.25)
			(net 903 "/DCDC/16V_OUT")
			(pintype "passive")
		)
	)
	(footprint "antmicro-footprints:LED_0603_1608Metric_Y"
		(layer "F.Cu")
		(at 190.686 149.7 180)
		(descr "LED SMD 0603 Yellow")
		(tags "LED SMD 0603 Yellow")
		(property "Reference" "D30"
			(at -0.84 -0.9 0)
			(layer "F.SilkS")
			(effects
				(font
					(size 0.7 0.7)
					(thickness 0.15)
				)
				(justify right top)
			)
		)
		(property "Value" "LED_Y_0603_LTST-C191KSKT"
			(at 0 1.6 0)
			(layer "F.Fab")
			(effects
				(font
					(size 0.7 0.7)
					(thickness 0.15)
				)
				(justify right top)
			)
		)
		(property "Datasheet" "https://optoelectronics.liteon.com/upload/download/DS22-2000-224/LTST-C191KSKT.PDF"
			(at 0 0 0)
			(layer "F.Fab")
			(hide yes)
			(effects
				(font
					(size 1.27 1.27)
					(thickness 0.15)
				)
			)
		)
		(property "Description" "LED, Yellow, SMD, 0603, 30 mA, 2.1 V, 588 nm"
			(at 0 0 0)
			(layer "F.Fab")
			(hide yes)
			(effects
				(font
					(size 1.27 1.27)
					(thickness 0.15)
				)
			)
		)
		(property "MPN" "LTST-C191KSKT"
			(at 0 0 180)
			(unlocked yes)
			(layer "F.Fab")
			(hide yes)
			(effects
				(font
					(size 1 1)
					(thickness 0.15)
				)
			)
		)
		(property "Manufacturer" "Lite-On"
			(at 0 0 180)
			(unlocked yes)
			(layer "F.Fab")
			(hide yes)
			(effects
				(font
					(size 1 1)
					(thickness 0.15)
				)
			)
		)
		(property "Color" "Yellow"
			(at 0 0 180)
			(unlocked yes)
			(layer "F.Fab")
			(hide yes)
			(effects
				(font
					(size 1 1)
					(thickness 0.15)
				)
			)
		)
		(property "Author" "Antmicro"
			(at 0 0 180)
			(unlocked yes)
			(layer "F.Fab")
			(hide yes)
			(effects
				(font
					(size 1 1)
					(thickness 0.15)
				)
			)
		)
		(property "License" "Apache-2.0"
			(at 0 0 180)
			(unlocked yes)
			(layer "F.Fab")
			(hide yes)
			(effects
				(font
					(size 1 1)
					(thickness 0.15)
				)
			)
		)
		(sheetname "/SFP/")
		(sheetfile "sfp.kicad_sch")
		(attr smd)
		(fp_line
			(start 0.22 0.35)
			(end -0.22 0.35)
			(stroke
				(width 0.15)
				(type solid)
			)
			(layer "F.SilkS")
		)
		(fp_line
			(start 0.22 -0.35)
			(end -0.22 -0.35)
			(stroke
				(width 0.15)
				(type solid)
			)
			(layer "F.SilkS")
		)
		(fp_line
			(start 0.105328 0.201008)
			(end 0.105329 -0.198992)
			(stroke
				(width 0.1)
				(type solid)
			)
			(layer "F.SilkS")
		)
		(fp_line
			(start 0.105328 0.201008)
			(end -0.094672 0.001008)
			(stroke
				(width 0.1)
				(type solid)
			)
			(layer "F.SilkS")
		)
		(fp_line
			(start 0.105328 0.001008)
			(end 0.240001 0.001)
			(stroke
				(width 0.1)
				(type solid)
			)
			(layer "F.SilkS")
		)
		(fp_line
			(start -0.094672 0.201008)
			(end -0.094672 -0.198992)
			(stroke
				(width 0.1)
				(type solid)
			)
			(layer "F.SilkS")
		)
		(fp_line
			(start -0.094672 0.001008)
			(end 0.105329 -0.198992)
			(stroke
				(width 0.1)
				(type solid)
			)
			(layer "F.SilkS")
		)
		(fp_line
			(start -0.094672 0.001008)
			(end -0.24 0.001008)
			(stroke
				(width 0.1)
				(type solid)
			)
			(layer "F.SilkS")
		)
		(fp_line
			(start -1.18 -0.319)
			(end -1.18 0.321)
			(stroke
				(width 0.15)
				(type solid)
			)
			(layer "F.SilkS")
		)
		(fp_poly
			(pts
				(xy 1.25 0.65) (xy -1.25 0.65) (xy -1.25 -0.65) (xy 1.25 -0.65)
			)
			(stroke
				(width 0.05)
				(type solid)
			)
			(fill no)
			(layer "F.CrtYd")
		)
		(fp_line
			(start 0.599 0)
			(end 0.200999 0)
			(stroke
				(width 0.15)
				(type solid)
			)
			(layer "F.Fab")
		)
		(fp_line
			(start 0.201 0.2)
			(end 0.200999 0)
			(stroke
				(width 0.15)
				(type solid)
			)
			(layer "F.Fab")
		)
		(fp_line
			(start 0.201 -0.202)
			(end -0.101 0)
			(stroke
				(width 0.15)
				(type solid)
			)
			(layer "F.Fab")
		)
		(fp_line
			(start 0.200999 0)
			(end 0.201 -0.202)
			(stroke
				(width 0.15)
				(type solid)
			)
			(layer "F.Fab")
		)
		(fp_line
			(start -0.101 0)
			(end 0.201 0.2)
			(stroke
				(width 0.15)
				(type solid)
			)
			(layer "F.Fab")
		)
		(fp_line
			(start -0.199 0.2)
			(end -0.199 0.1)
			(stroke
				(width 0.15)
				(type solid)
			)
			(layer "F.Fab")
		)
		(fp_line
			(start -0.199 0)
			(end -0.597 0)
			(stroke
				(width 0.15)
				(type solid)
			)
			(layer "F.Fab")
		)
		(fp_line
			(start -0.199 -0.202)
			(end -0.199 0.1)
			(stroke
				(width 0.15)
				(type solid)
			)
			(layer "F.Fab")
		)
		(fp_poly
			(pts
				(xy 0.848 0.4) (xy -0.85 0.4) (xy -0.85 -0.402) (xy 0.848 -0.401999)
			)
			(stroke
				(width 0.15)
				(type solid)
			)
			(fill no)
			(layer "F.Fab")
		)
		(fp_text user "Author: Antmicro"
			(at -1.31 4.769 0)
			(layer "F.Fab")
			(effects
				(font
					(size 0.7 0.7)
					(thickness 0.15)
				)
				(justify right top)
			)
		)
		(fp_text user "License: Apache-2.0"
			(at -1.31 5.769 0)
			(layer "F.Fab")
			(effects
				(font
					(size 0.7 0.7)
					(thickness 0.15)
				)
				(justify right top)
			)
		)
		(fp_text user "${REFERENCE}"
			(at -1.309999 3.769 0)
			(layer "F.Fab")
			(effects
				(font
					(size 0.7 0.7)
					(thickness 0.15)
				)
				(justify right top)
			)
		)
		(pad "1" smd roundrect
			(at -0.7 0)
			(size 0.8 1)
			(layers "F.Cu" "F.Mask" "F.Paste")
			(roundrect_rratio 0.2)
			(net 543 "Net-(D30-C)")
			(pinfunction "C")
			(pintype "passive")
		)
		(pad "2" smd roundrect
			(at 0.7 0)
			(size 0.8 1)
			(layers "F.Cu" "F.Mask" "F.Paste")
			(roundrect_rratio 0.2)
			(net 2 "+3V3")
			(pinfunction "A")
			(pintype "passive")
		)
	)
	(footprint "antmicro-footprints:C_0805_2012Metric"
		(layer "F.Cu")
		(at 171.38 99.81 90)
		(descr "Capacitor SMD 0805")
		(tags "capacitor SMD 0805")
		(property "Reference" "C257"
			(at -4.595 0.345 90)
			(layer "F.SilkS")
			(effects
				(font
					(size 0.7 0.7)
					(thickness 0.15)
				)
				(justify left bottom)
			)
		)
		(property "Value" "C_22u_25V_0805"
			(at -2.055717 1.963152 90)
			(layer "F.Fab")
			(effects
				(font
					(size 0.7 0.7)
					(thickness 0.15)
				)
				(justify left bottom)
			)
		)
		(property "Datasheet" "https://product.samsungsem.com/mlcc/CL21A226MAYNNN.do"
			(at 0 0 90)
			(layer "F.Fab")
			(hide yes)
			(effects
				(font
					(size 1.27 1.27)
					(thickness 0.15)
				)
			)
		)
		(property "Description" "SMT Multilayer Ceramic Capacitor, 22uF, +/-20%, 25V, X5R, 0805 [2012 Metric]"
			(at 0 0 90)
			(layer "F.Fab")
			(hide yes)
			(effects
				(font
					(size 1.27 1.27)
					(thickness 0.15)
				)
			)
		)
		(property "MPN" "CL21A226MAYNNNE"
			(at 0 0 90)
			(unlocked yes)
			(layer "F.Fab")
			(hide yes)
			(effects
				(font
					(size 1 1)
					(thickness 0.15)
				)
			)
		)
		(property "Manufacturer" "Samsung Electro-Mechanics"
			(at 0 0 90)
			(unlocked yes)
			(layer "F.Fab")
			(hide yes)
			(effects
				(font
					(size 1 1)
					(thickness 0.15)
				)
			)
		)
		(property "License" "Apache-2.0"
			(at 0 0 90)
			(unlocked yes)
			(layer "F.Fab")
			(hide yes)
			(effects
				(font
					(size 1 1)
					(thickness 0.15)
				)
			)
		)
		(property "Author" "Antmicro"
			(at 0 0 90)
			(unlocked yes)
			(layer "F.Fab")
			(hide yes)
			(effects
				(font
					(size 1 1)
					(thickness 0.15)
				)
			)
		)
		(property "Val" "22u"
			(at 0 0 90)
			(unlocked yes)
			(layer "F.Fab")
			(hide yes)
			(effects
				(font
					(size 1 1)
					(thickness 0.15)
				)
			)
		)
		(property "Voltage" "25V"
			(at 0 0 90)
			(unlocked yes)
			(layer "F.Fab")
			(hide yes)
			(effects
				(font
					(size 1 1)
					(thickness 0.15)
				)
			)
		)
		(property "Dielectric" "X5R"
			(at 0 0 90)
			(unlocked yes)
			(layer "F.Fab")
			(hide yes)
			(effects
				(font
					(size 1 1)
					(thickness 0.15)
				)
			)
		)
		(property "Public" "False"
			(at 0 0 90)
			(unlocked yes)
			(layer "F.Fab")
			(hide yes)
			(effects
				(font
					(size 1 1)
					(thickness 0.15)
				)
			)
		)
		(component_classes
			(class "DCDC_SOM")
		)
		(sheetname "/DCDC/")
		(sheetfile "dcdc.kicad_sch")
		(attr smd)
		(fp_line
			(start -0.3 -0.7)
			(end 0.3 -0.7)
			(stroke
				(width 0.15)
				(type solid)
			)
			(layer "F.SilkS")
		)
		(fp_line
			(start -0.3 0.7)
			(end 0.3 0.7)
			(stroke
				(width 0.15)
				(type solid)
			)
			(layer "F.SilkS")
		)
		(fp_rect
			(start 1.95 -0.9)
			(end -1.95 0.9)
			(stroke
				(width 0.05)
				(type default)
			)
			(fill no)
			(layer "F.CrtYd")
		)
		(fp_rect
			(start -0.95 -0.675)
			(end 0.95 0.675)
			(stroke
				(width 0.15)
				(type solid)
			)
			(fill no)
			(layer "F.Fab")
		)
		(fp_text user "Author: Antmicro"
			(at -1.9 5.947 90)
			(layer "F.Fab")
			(effects
				(font
					(size 0.7 0.7)
					(thickness 0.15)
				)
				(justify left bottom)
			)
		)
		(fp_text user "${REFERENCE}"
			(at -1.9 3.947 90)
			(layer "F.Fab")
			(effects
				(font
					(size 0.7 0.7)
					(thickness 0.15)
				)
				(justify left bottom)
			)
		)
		(fp_text user "License: Apache-2.0"
			(at -1.9 4.947 90)
			(layer "F.Fab")
			(effects
				(font
					(size 0.7 0.7)
					(thickness 0.15)
				)
				(justify left bottom)
			)
		)
		(pad "1" smd roundrect
			(at -1.1 0 90)
			(size 1.2 1.3)
			(layers "F.Cu" "F.Mask" "F.Paste")
			(roundrect_rratio 0.25)
			(net 1 "GND")
			(pintype "passive")
		)
		(pad "2" smd roundrect
			(at 1.1 0 90)
			(size 1.2 1.3)
			(layers "F.Cu" "F.Mask" "F.Paste")
			(roundrect_rratio 0.25)
			(net 903 "/DCDC/16V_OUT")
			(pintype "passive")
		)
	)
	(footprint "antmicro-footprints:C_0805_2012Metric"
		(layer "F.Cu")
		(at 171.34 93.32 -90)
		(descr "Capacitor SMD 0805")
		(tags "capacitor SMD 0805")
		(property "Reference" "C249"
			(at 1.745 0.425 90)
			(layer "F.SilkS")
			(effects
				(font
					(size 0.7 0.7)
					(thickness 0.15)
				)
				(justify right top)
			)
		)
		(property "Value" "C_22u_25V_0805"
			(at -2.055717 1.963152 90)
			(layer "F.Fab")
			(effects
				(font
					(size 0.7 0.7)
					(thickness 0.15)
				)
				(justify right top)
			)
		)
		(property "Datasheet" "https://product.samsungsem.com/mlcc/CL21A226MAYNNN.do"
			(at 0 0 90)
			(layer "F.Fab")
			(hide yes)
			(effects
				(font
					(size 1.27 1.27)
					(thickness 0.15)
				)
			)
		)
		(property "Description" "SMT Multilayer Ceramic Capacitor, 22uF, +/-20%, 25V, X5R, 0805 [2012 Metric]"
			(at 0 0 90)
			(layer "F.Fab")
			(hide yes)
			(effects
				(font
					(size 1.27 1.27)
					(thickness 0.15)
				)
			)
		)
		(property "MPN" "CL21A226MAYNNNE"
			(at 0 0 270)
			(unlocked yes)
			(layer "F.Fab")
			(hide yes)
			(effects
				(font
					(size 1 1)
					(thickness 0.15)
				)
			)
		)
		(property "Manufacturer" "Samsung Electro-Mechanics"
			(at 0 0 270)
			(unlocked yes)
			(layer "F.Fab")
			(hide yes)
			(effects
				(font
					(size 1 1)
					(thickness 0.15)
				)
			)
		)
		(property "License" "Apache-2.0"
			(at 0 0 270)
			(unlocked yes)
			(layer "F.Fab")
			(hide yes)
			(effects
				(font
					(size 1 1)
					(thickness 0.15)
				)
			)
		)
		(property "Author" "Antmicro"
			(at 0 0 270)
			(unlocked yes)
			(layer "F.Fab")
			(hide yes)
			(effects
				(font
					(size 1 1)
					(thickness 0.15)
				)
			)
		)
		(property "Val" "22u"
			(at 0 0 270)
			(unlocked yes)
			(layer "F.Fab")
			(hide yes)
			(effects
				(font
					(size 1 1)
					(thickness 0.15)
				)
			)
		)
		(property "Voltage" "25V"
			(at 0 0 270)
			(unlocked yes)
			(layer "F.Fab")
			(hide yes)
			(effects
				(font
					(size 1 1)
					(thickness 0.15)
				)
			)
		)
		(property "Dielectric" "X5R"
			(at 0 0 270)
			(unlocked yes)
			(layer "F.Fab")
			(hide yes)
			(effects
				(font
					(size 1 1)
					(thickness 0.15)
				)
			)
		)
		(property "Public" "False"
			(at 0 0 270)
			(unlocked yes)
			(layer "F.Fab")
			(hide yes)
			(effects
				(font
					(size 1 1)
					(thickness 0.15)
				)
			)
		)
		(component_classes
			(class "DCDC_SOM")
		)
		(sheetname "/DCDC/")
		(sheetfile "dcdc.kicad_sch")
		(attr smd)
		(fp_line
			(start -0.3 0.7)
			(end 0.3 0.7)
			(stroke
				(width 0.15)
				(type solid)
			)
			(layer "F.SilkS")
		)
		(fp_line
			(start -0.3 -0.7)
			(end 0.3 -0.7)
			(stroke
				(width 0.15)
				(type solid)
			)
			(layer "F.SilkS")
		)
		(fp_rect
			(start 1.95 -0.9)
			(end -1.95 0.9)
			(stroke
				(width 0.05)
				(type default)
			)
			(fill no)
			(layer "F.CrtYd")
		)
		(fp_rect
			(start -0.95 -0.675)
			(end 0.95 0.675)
			(stroke
				(width 0.15)
				(type solid)
			)
			(fill no)
			(layer "F.Fab")
		)
		(fp_text user "${REFERENCE}"
			(at -1.9 3.947 90)
			(layer "F.Fab")
			(effects
				(font
					(size 0.7 0.7)
					(thickness 0.15)
				)
				(justify right top)
			)
		)
		(fp_text user "License: Apache-2.0"
			(at -1.9 4.947 90)
			(layer "F.Fab")
			(effects
				(font
					(size 0.7 0.7)
					(thickness 0.15)
				)
				(justify right top)
			)
		)
		(fp_text user "Author: Antmicro"
			(at -1.9 5.947 90)
			(layer "F.Fab")
			(effects
				(font
					(size 0.7 0.7)
					(thickness 0.15)
				)
				(justify right top)
			)
		)
		(pad "1" smd roundrect
			(at -1.1 0 270)
			(size 1.2 1.3)
			(layers "F.Cu" "F.Mask" "F.Paste")
			(roundrect_rratio 0.25)
			(net 1 "GND")
			(pintype "passive")
		)
		(pad "2" smd roundrect
			(at 1.1 0 270)
			(size 1.2 1.3)
			(layers "F.Cu" "F.Mask" "F.Paste")
			(roundrect_rratio 0.25)
			(net 903 "/DCDC/16V_OUT")
			(pintype "passive")
		)
	)
	(footprint "antmicro-footprints:C_0402_1005Metric"
		(layer "F.Cu")
		(at 214 132.8 180)
		(descr "Capacitor SMD 0402")
		(tags "capacitor SMD 0402")
		(property "Reference" "C195"
			(at -3.67 0.47 0)
			(layer "F.SilkS")
			(effects
				(font
					(size 0.7 0.7)
					(thickness 0.15)
				)
				(justify right top)
			)
		)
		(property "Value" "C_1n_0402"
			(at -1.022927 2.155213 0)
			(layer "F.Fab")
			(effects
				(font
					(size 0.7 0.7)
					(thickness 0.15)
				)
				(justify right top)
			)
		)
		(property "Datasheet" "https://www.murata.com/products/productdetail?partno=GRM1555C1H102JA01%23"
			(at 0 0 0)
			(layer "F.Fab")
			(hide yes)
			(effects
				(font
					(size 1.27 1.27)
					(thickness 0.15)
				)
			)
		)
		(property "Description" "SMD Multilayer Ceramic Capacitor, 1000 pF, 50 V, 0402 [1005 Metric], ± 5%, C0G / NP0, GRM Series"
			(at 0 0 0)
			(layer "F.Fab")
			(hide yes)
			(effects
				(font
					(size 1.27 1.27)
					(thickness 0.15)
				)
			)
		)
		(property "MPN" "GRM1555C1H102JA01D"
			(at 0 0 180)
			(unlocked yes)
			(layer "F.Fab")
			(hide yes)
			(effects
				(font
					(size 1 1)
					(thickness 0.15)
				)
			)
		)
		(property "Manufacturer" "Murata"
			(at 0 0 180)
			(unlocked yes)
			(layer "F.Fab")
			(hide yes)
			(effects
				(font
					(size 1 1)
					(thickness 0.15)
				)
			)
		)
		(property "License" "Apache-2.0"
			(at 0 0 180)
			(unlocked yes)
			(layer "F.Fab")
			(hide yes)
			(effects
				(font
					(size 1 1)
					(thickness 0.15)
				)
			)
		)
		(property "Author" "Antmicro"
			(at 0 0 180)
			(unlocked yes)
			(layer "F.Fab")
			(hide yes)
			(effects
				(font
					(size 1 1)
					(thickness 0.15)
				)
			)
		)
		(property "Val" "1n"
			(at 0 0 180)
			(unlocked yes)
			(layer "F.Fab")
			(hide yes)
			(effects
				(font
					(size 1 1)
					(thickness 0.15)
				)
			)
		)
		(property "Voltage" "50V"
			(at 0 0 180)
			(unlocked yes)
			(layer "F.Fab")
			(hide yes)
			(effects
				(font
					(size 1 1)
					(thickness 0.15)
				)
			)
		)
		(property "Dielectric" "C0G"
			(at 0 0 180)
			(unlocked yes)
			(layer "F.Fab")
			(hide yes)
			(effects
				(font
					(size 1 1)
					(thickness 0.15)
				)
			)
		)
		(sheetname "/USB Hub/")
		(sheetfile "usb_hub.kicad_sch")
		(attr smd)
		(fp_rect
			(start -0.925 -0.47)
			(end 0.925 0.47)
			(stroke
				(width 0.05)
				(type default)
			)
			(fill no)
			(layer "F.CrtYd")
		)
		(fp_line
			(start 0.504 0.248)
			(end -0.494 0.248)
			(stroke
				(width 0.15)
				(type solid)
			)
			(layer "F.Fab")
		)
		(fp_line
			(start 0.504 -0.25)
			(end 0.504 0.248)
			(stroke
				(width 0.15)
				(type solid)
			)
			(layer "F.Fab")
		)
		(fp_line
			(start -0.494 0.248)
			(end -0.494 -0.25)
			(stroke
				(width 0.15)
				(type solid)
			)
			(layer "F.Fab")
		)
		(fp_line
			(start -0.494 -0.25)
			(end 0.504 -0.25)
			(stroke
				(width 0.15)
				(type solid)
			)
			(layer "F.Fab")
		)
		(fp_text user "${REFERENCE}"
			(at -0.939 4.599 0)
			(layer "F.Fab")
			(effects
				(font
					(size 0.7 0.7)
					(thickness 0.15)
				)
				(justify right top)
			)
		)
		(fp_text user "License: Apache-2.0"
			(at -0.939 5.799 0)
			(layer "F.Fab")
			(effects
				(font
					(size 0.7 0.7)
					(thickness 0.15)
				)
				(justify right top)
			)
		)
		(fp_text user "Author: Antmicro"
			(at -0.939 3.399 0)
			(layer "F.Fab")
			(effects
				(font
					(size 0.7 0.7)
					(thickness 0.15)
				)
				(justify right top)
			)
		)
		(pad "1" smd roundrect
			(at -0.48 0 180)
			(size 0.59 0.64)
			(layers "F.Cu" "F.Mask" "F.Paste")
			(roundrect_rratio 0.25)
			(net 1 "GND")
			(pintype "passive")
		)
		(pad "2" smd roundrect
			(at 0.48 0 180)
			(size 0.59 0.64)
			(layers "F.Cu" "F.Mask" "F.Paste")
			(roundrect_rratio 0.25)
			(net 527 "/USB Hub/~{RESET}")
			(pintype "passive")
		)
	)
	(footprint "antmicro-footprints:C_0402_1005Metric"
		(layer "F.Cu")
		(at 170.529468 119.216 180)
		(descr "Capacitor SMD 0402")
		(tags "capacitor SMD 0402")
		(property "Reference" "C197"
			(at 6.529468 -0.384 0)
			(layer "F.SilkS")
			(effects
				(font
					(size 0.7 0.7)
					(thickness 0.15)
				)
				(justify left bottom)
			)
		)
		(property "Value" "C_100n_0402"
			(at -1.022927 2.155213 0)
			(layer "F.Fab")
			(effects
				(font
					(size 0.7 0.7)
					(thickness 0.15)
				)
				(justify right top)
			)
		)
		(property "Datasheet" "https://www.murata.com/products/productdetail?partno=GRM155R61H104KE14%23"
			(at 0 0 0)
			(layer "F.Fab")
			(hide yes)
			(effects
				(font
					(size 1.27 1.27)
					(thickness 0.15)
				)
			)
		)
		(property "Description" "SMD Multilayer Ceramic Capacitor, 0.1 µF, 50 V, 0402 [1005 Metric], ± 10%, X5R, GRM Series"
			(at 0 0 0)
			(layer "F.Fab")
			(hide yes)
			(effects
				(font
					(size 1.27 1.27)
					(thickness 0.15)
				)
			)
		)
		(property "MPN" "GRM155R61H104KE14D"
			(at 0 0 180)
			(unlocked yes)
			(layer "F.Fab")
			(hide yes)
			(effects
				(font
					(size 1 1)
					(thickness 0.15)
				)
			)
		)
		(property "Manufacturer" "Murata"
			(at 0 0 180)
			(unlocked yes)
			(layer "F.Fab")
			(hide yes)
			(effects
				(font
					(size 1 1)
					(thickness 0.15)
				)
			)
		)
		(property "License" "Apache-2.0"
			(at 0 0 180)
			(unlocked yes)
			(layer "F.Fab")
			(hide yes)
			(effects
				(font
					(size 1 1)
					(thickness 0.15)
				)
			)
		)
		(property "Author" "Antmicro"
			(at 0 0 180)
			(unlocked yes)
			(layer "F.Fab")
			(hide yes)
			(effects
				(font
					(size 1 1)
					(thickness 0.15)
				)
			)
		)
		(property "Val" "100n"
			(at 0 0 180)
			(unlocked yes)
			(layer "F.Fab")
			(hide yes)
			(effects
				(font
					(size 1 1)
					(thickness 0.15)
				)
			)
		)
		(property "Voltage" "50V"
			(at 0 0 180)
			(unlocked yes)
			(layer "F.Fab")
			(hide yes)
			(effects
				(font
					(size 1 1)
					(thickness 0.15)
				)
			)
		)
		(property "Dielectric" "X5R"
			(at 0 0 180)
			(unlocked yes)
			(layer "F.Fab")
			(hide yes)
			(effects
				(font
					(size 1 1)
					(thickness 0.15)
				)
			)
		)
		(property "Public" "False"
			(at 0 0 180)
			(unlocked yes)
			(layer "F.Fab")
			(hide yes)
			(effects
				(font
					(size 1 1)
					(thickness 0.15)
				)
			)
		)
		(sheetname "/DCDC/")
		(sheetfile "dcdc.kicad_sch")
		(attr smd)
		(fp_rect
			(start -0.925 -0.47)
			(end 0.925 0.47)
			(stroke
				(width 0.05)
				(type default)
			)
			(fill no)
			(layer "F.CrtYd")
		)
		(fp_line
			(start 0.504 0.248)
			(end -0.494 0.248)
			(stroke
				(width 0.15)
				(type solid)
			)
			(layer "F.Fab")
		)
		(fp_line
			(start 0.504 -0.25)
			(end 0.504 0.248)
			(stroke
				(width 0.15)
				(type solid)
			)
			(layer "F.Fab")
		)
		(fp_line
			(start -0.494 0.248)
			(end -0.494 -0.25)
			(stroke
				(width 0.15)
				(type solid)
			)
			(layer "F.Fab")
		)
		(fp_line
			(start -0.494 -0.25)
			(end 0.504 -0.25)
			(stroke
				(width 0.15)
				(type solid)
			)
			(layer "F.Fab")
		)
		(fp_text user "${REFERENCE}"
			(at -0.939 4.599 0)
			(layer "F.Fab")
			(effects
				(font
					(size 0.7 0.7)
					(thickness 0.15)
				)
				(justify right top)
			)
		)
		(fp_text user "Author: Antmicro"
			(at -0.939 3.399 0)
			(layer "F.Fab")
			(effects
				(font
					(size 0.7 0.7)
					(thickness 0.15)
				)
				(justify right top)
			)
		)
		(fp_text user "License: Apache-2.0"
			(at -0.939 5.799 0)
			(layer "F.Fab")
			(effects
				(font
					(size 0.7 0.7)
					(thickness 0.15)
				)
				(justify right top)
			)
		)
		(pad "1" smd roundrect
			(at -0.48 0 180)
			(size 0.59 0.64)
			(layers "F.Cu" "F.Mask" "F.Paste")
			(roundrect_rratio 0.25)
			(net 1 "GND")
			(pintype "passive")
		)
		(pad "2" smd roundrect
			(at 0.48 0 180)
			(size 0.59 0.64)
			(layers "F.Cu" "F.Mask" "F.Paste")
			(roundrect_rratio 0.25)
			(net 4 "+3V3_AON")
			(pintype "passive")
		)
	)
	(footprint "antmicro-footprints:XSON-8_1x1.95mm_P0.5mm"
		(layer "F.Cu")
		(at 211.2 79.8 90)
		(property "Reference" "U31"
			(at -0.2 1.2 180)
			(layer "F.SilkS")
			(effects
				(font
					(size 0.7 0.7)
					(thickness 0.15)
				)
				(justify left bottom)
			)
		)
		(property "Value" "NTS0102_XSON"
			(at 0 2.2 90)
			(layer "F.Fab")
			(effects
				(font
					(size 0.7 0.7)
					(thickness 0.15)
				)
				(justify left bottom)
			)
		)
		(property "Datasheet" "http://www.farnell.com/datasheets/1760723.pdf"
			(at 0 0 90)
			(layer "F.Fab")
			(hide yes)
			(effects
				(font
					(size 1.27 1.27)
					(thickness 0.15)
				)
			)
		)
		(property "Description" "Transceiver, 1.65 V to 3.6 V, XSON-8"
			(at 0 0 90)
			(layer "F.Fab")
			(hide yes)
			(effects
				(font
					(size 1.27 1.27)
					(thickness 0.15)
				)
			)
		)
		(property "MPN" "NTS0102GT"
			(at 0 0 90)
			(unlocked yes)
			(layer "F.Fab")
			(hide yes)
			(effects
				(font
					(size 1 1)
					(thickness 0.15)
				)
			)
		)
		(property "Manufacturer" "NXP"
			(at 0 0 90)
			(unlocked yes)
			(layer "F.Fab")
			(hide yes)
			(effects
				(font
					(size 1 1)
					(thickness 0.15)
				)
			)
		)
		(property "Author" "Antmicro"
			(at 0 0 90)
			(unlocked yes)
			(layer "F.Fab")
			(hide yes)
			(effects
				(font
					(size 1 1)
					(thickness 0.15)
				)
			)
		)
		(property "License" "Apache-2.0"
			(at 0 0 90)
			(unlocked yes)
			(layer "F.Fab")
			(hide yes)
			(effects
				(font
					(size 1 1)
					(thickness 0.15)
				)
			)
		)
		(sheetname "/USB Debug, PD/")
		(sheetfile "usb_debug_pd.kicad_sch")
		(attr smd)
		(fp_line
			(start -0.5 -1.1)
			(end 0.5 -1.1)
			(stroke
				(width 0.15)
				(type solid)
			)
			(layer "F.SilkS")
		)
		(fp_line
			(start 0.5 1.1)
			(end -0.5 1.1)
			(stroke
				(width 0.15)
				(type solid)
			)
			(layer "F.SilkS")
		)
		(fp_circle
			(center -0.750001 -1.1)
			(end -0.700999 -1.1)
			(stroke
				(width 0.15)
				(type solid)
			)
			(fill no)
			(layer "F.SilkS")
		)
		(fp_poly
			(pts
				(xy -0.8 -1.200001) (xy 0.8 -1.200001) (xy 0.8 1.200001) (xy -0.8 1.200001)
			)
			(stroke
				(width 0.05)
				(type solid)
			)
			(fill no)
			(layer "F.CrtYd")
		)
		(fp_line
			(start 0.5305 -1.001)
			(end 0.5305 1)
			(stroke
				(width 0.15)
				(type solid)
			)
			(layer "F.Fab")
		)
		(fp_line
			(start -0.5305 -1.001)
			(end 0.5305 -1.001)
			(stroke
				(width 0.15)
				(type solid)
			)
			(layer "F.Fab")
		)
		(fp_line
			(start 0.5305 1)
			(end -0.5305 1)
			(stroke
				(width 0.15)
				(type solid)
			)
			(layer "F.Fab")
		)
		(fp_line
			(start -0.5305 1)
			(end -0.5305 -1.001)
			(stroke
				(width 0.15)
				(type solid)
			)
			(layer "F.Fab")
		)
		(fp_text user "${REFERENCE}"
			(at -0.527 5.905 90)
			(layer "F.Fab")
			(effects
				(font
					(size 0.7 0.7)
					(thickness 0.15)
				)
				(justify left bottom)
			)
		)
		(fp_text user "License: Apache-2.0"
			(at -0.527 8.306 90)
			(layer "F.Fab")
			(effects
				(font
					(size 0.7 0.7)
					(thickness 0.15)
				)
				(justify left bottom)
			)
		)
		(fp_text user "Author: Antmicro"
			(at -0.527 7.105 90)
			(layer "F.Fab")
			(effects
				(font
					(size 0.7 0.7)
					(thickness 0.15)
				)
				(justify left bottom)
			)
		)
		(pad "1" smd roundrect
			(at -0.45 -0.75 270)
			(size 0.6 0.3)
			(layers "F.Cu" "F.Mask" "F.Paste")
			(roundrect_rratio 0.25)
			(net 945 "/USB Debug, PD/DEBUG_SCL")
			(pinfunction "B_{2}")
			(pintype "bidirectional")
		)
		(pad "2" smd roundrect
			(at -0.45 -0.25 270)
			(size 0.6 0.25)
			(layers "F.Cu" "F.Mask" "F.Paste")
			(roundrect_rratio 0.25)
			(net 1 "GND")
			(pinfunction "GND")
			(pintype "power_in")
		)
		(pad "3" smd roundrect
			(at -0.45 0.25 270)
			(size 0.6 0.25)
			(layers "F.Cu" "F.Mask" "F.Paste")
			(roundrect_rratio 0.25)
			(net 334 "/USB Debug, PD/FTDI_3V3")
			(pinfunction "VCC_{A}")
			(pintype "power_in")
		)
		(pad "4" smd roundrect
			(at -0.45 0.75 270)
			(size 0.6 0.3)
			(layers "F.Cu" "F.Mask" "F.Paste")
			(roundrect_rratio 0.25)
			(net 955 "/USB Debug, PD/FTDI_CBUS3{slash}SCL")
			(pinfunction "A_{2}")
			(pintype "bidirectional")
		)
		(pad "5" smd roundrect
			(at 0.45 0.75 270)
			(size 0.6 0.3)
			(layers "F.Cu" "F.Mask" "F.Paste")
			(roundrect_rratio 0.25)
			(net 956 "/USB Debug, PD/FTDI_CBUS0{slash}SDA")
			(pinfunction "A_{1}")
			(pintype "bidirectional")
		)
		(pad "6" smd roundrect
			(at 0.45 0.25 270)
			(size 0.6 0.25)
			(layers "F.Cu" "F.Mask" "F.Paste")
			(roundrect_rratio 0.25)
			(net 881 "/USB Debug, PD/FTDI_CBUS_EN")
			(pinfunction "OE")
			(pintype "input")
		)
		(pad "7" smd roundrect
			(at 0.45 -0.25 270)
			(size 0.6 0.25)
			(layers "F.Cu" "F.Mask" "F.Paste")
			(roundrect_rratio 0.25)
			(net 334 "/USB Debug, PD/FTDI_3V3")
			(pinfunction "VCC_{B}")
			(pintype "power_in")
		)
		(pad "8" smd roundrect
			(at 0.45 -0.75 270)
			(size 0.6 0.3)
			(layers "F.Cu" "F.Mask" "F.Paste")
			(roundrect_rratio 0.25)
			(net 946 "/USB Debug, PD/DEBUG_SDA")
			(pinfunction "B_{1}")
			(pintype "bidirectional")
		)
	)
	(footprint "antmicro-footprints:C_0402_1005Metric"
		(layer "F.Cu")
		(at 219.564132 86.75)
		(descr "Capacitor SMD 0402")
		(tags "capacitor SMD 0402")
		(property "Reference" "C142"
			(at -1.764132 -0.64 0)
			(layer "F.SilkS")
			(effects
				(font
					(size 0.7 0.7)
					(thickness 0.15)
				)
				(justify left bottom)
			)
		)
		(property "Value" "C_100n_0402"
			(at -1.022927 2.155213 0)
			(layer "F.Fab")
			(effects
				(font
					(size 0.7 0.7)
					(thickness 0.15)
				)
				(justify left bottom)
			)
		)
		(property "Datasheet" "https://www.murata.com/products/productdetail?partno=GRM155R61H104KE14%23"
			(at 0 0 0)
			(layer "F.Fab")
			(hide yes)
			(effects
				(font
					(size 1.27 1.27)
					(thickness 0.15)
				)
			)
		)
		(property "Description" "SMD Multilayer Ceramic Capacitor, 0.1 µF, 50 V, 0402 [1005 Metric], ± 10%, X5R, GRM Series"
			(at 0 0 0)
			(layer "F.Fab")
			(hide yes)
			(effects
				(font
					(size 1.27 1.27)
					(thickness 0.15)
				)
			)
		)
		(property "Manufacturer" "Murata"
			(at 0 0 0)
			(unlocked yes)
			(layer "F.Fab")
			(hide yes)
			(effects
				(font
					(size 1 1)
					(thickness 0.15)
				)
			)
		)
		(property "MPN" "GRM155R61H104KE14D"
			(at 0 0 0)
			(unlocked yes)
			(layer "F.Fab")
			(hide yes)
			(effects
				(font
					(size 1 1)
					(thickness 0.15)
				)
			)
		)
		(property "Val" "100n"
			(at 0 0 0)
			(unlocked yes)
			(layer "F.Fab")
			(hide yes)
			(effects
				(font
					(size 1 1)
					(thickness 0.15)
				)
			)
		)
		(property "License" "Apache-2.0"
			(at 0 0 0)
			(unlocked yes)
			(layer "F.Fab")
			(hide yes)
			(effects
				(font
					(size 1 1)
					(thickness 0.15)
				)
			)
		)
		(property "Author" "Antmicro"
			(at 0 0 0)
			(unlocked yes)
			(layer "F.Fab")
			(hide yes)
			(effects
				(font
					(size 1 1)
					(thickness 0.15)
				)
			)
		)
		(property "Voltage" "50V"
			(at 0 0 0)
			(unlocked yes)
			(layer "F.Fab")
			(hide yes)
			(effects
				(font
					(size 1 1)
					(thickness 0.15)
				)
			)
		)
		(property "Dielectric" "X5R"
			(at 0 0 0)
			(unlocked yes)
			(layer "F.Fab")
			(hide yes)
			(effects
				(font
					(size 1 1)
					(thickness 0.15)
				)
			)
		)
		(sheetname "/USB DP Alt mode/")
		(sheetfile "usb_dp.kicad_sch")
		(attr smd)
		(fp_rect
			(start -0.925 -0.47)
			(end 0.925 0.47)
			(stroke
				(width 0.05)
				(type default)
			)
			(fill no)
			(layer "F.CrtYd")
		)
		(fp_line
			(start -0.494 -0.25)
			(end 0.504 -0.25)
			(stroke
				(width 0.15)
				(type solid)
			)
			(layer "F.Fab")
		)
		(fp_line
			(start -0.494 0.248)
			(end -0.494 -0.25)
			(stroke
				(width 0.15)
				(type solid)
			)
			(layer "F.Fab")
		)
		(fp_line
			(start 0.504 -0.25)
			(end 0.504 0.248)
			(stroke
				(width 0.15)
				(type solid)
			)
			(layer "F.Fab")
		)
		(fp_line
			(start 0.504 0.248)
			(end -0.494 0.248)
			(stroke
				(width 0.15)
				(type solid)
			)
			(layer "F.Fab")
		)
		(fp_text user "${REFERENCE}"
			(at -0.939 4.599 0)
			(layer "F.Fab")
			(effects
				(font
					(size 0.7 0.7)
					(thickness 0.15)
				)
				(justify left bottom)
			)
		)
		(fp_text user "License: Apache-2.0"
			(at -0.939 5.799 0)
			(layer "F.Fab")
			(effects
				(font
					(size 0.7 0.7)
					(thickness 0.15)
				)
				(justify left bottom)
			)
		)
		(fp_text user "Author: Antmicro"
			(at -0.939 3.399 0)
			(layer "F.Fab")
			(effects
				(font
					(size 0.7 0.7)
					(thickness 0.15)
				)
				(justify left bottom)
			)
		)
		(pad "1" smd roundrect
			(at -0.48 0)
			(size 0.59 0.64)
			(layers "F.Cu" "F.Mask" "F.Paste")
			(roundrect_rratio 0.25)
			(net 354 "/USB DP Alt mode/USBC1_TX2_P")
			(pintype "passive")
		)
		(pad "2" smd roundrect
			(at 0.48 0)
			(size 0.59 0.64)
			(layers "F.Cu" "F.Mask" "F.Paste")
			(roundrect_rratio 0.25)
			(net 347 "/USB DP Alt mode/USBC1_CONN_TX2_P")
			(pintype "passive")
		)
	)
	(footprint "antmicro-footprints:R_0805_2012Metric"
		(layer "F.Cu")
		(at 109.510001 60.719999 -90)
		(property "Reference" "R366"
			(at -1.519999 1.690001 90)
			(layer "F.SilkS")
			(effects
				(font
					(size 0.7 0.7)
					(thickness 0.15)
				)
				(justify right top)
			)
		)
		(property "Value" "R_0R001_0805"
			(at 0 1.8 90)
			(layer "F.Fab")
			(effects
				(font
					(size 0.7 0.7)
					(thickness 0.15)
				)
				(justify right top)
			)
		)
		(property "Datasheet" "https://www.eaton.com/content/dam/eaton/products/electronic-components/resources/data-sheet/eaton-msma-automotive-smd-current-sense-resistor-metal-strip-data-sheet-elx1179.pdf"
			(at 0 0 90)
			(layer "F.Fab")
			(hide yes)
			(effects
				(font
					(size 1.27 1.27)
					(thickness 0.15)
				)
			)
		)
		(property "Description" "Current Sense Resistors - SMD MSMA, 0805 SIZE, 1/2 Watt, 1 mohm, 50 TCR MnCu Metal AEC-Q"
			(at 0 0 90)
			(layer "F.Fab")
			(hide yes)
			(effects
				(font
					(size 1.27 1.27)
					(thickness 0.15)
				)
			)
		)
		(property "MPN" "MSMA0805R0010FSM"
			(at 0 0 270)
			(unlocked yes)
			(layer "F.Fab")
			(hide yes)
			(effects
				(font
					(size 1 1)
					(thickness 0.15)
				)
			)
		)
		(property "Manufacturer" "Eaton"
			(at 0 0 270)
			(unlocked yes)
			(layer "F.Fab")
			(hide yes)
			(effects
				(font
					(size 1 1)
					(thickness 0.15)
				)
			)
		)
		(property "License" "Apache-2.0"
			(at 0 0 270)
			(unlocked yes)
			(layer "F.Fab")
			(hide yes)
			(effects
				(font
					(size 1 1)
					(thickness 0.15)
				)
			)
		)
		(property "Author" "Antmicro"
			(at 0 0 270)
			(unlocked yes)
			(layer "F.Fab")
			(hide yes)
			(effects
				(font
					(size 1 1)
					(thickness 0.15)
				)
			)
		)
		(property "Val" "0R001"
			(at 0 0 270)
			(unlocked yes)
			(layer "F.Fab")
			(hide yes)
			(effects
				(font
					(size 1 1)
					(thickness 0.15)
				)
			)
		)
		(property "Tolerance" "1%"
			(at 0 0 270)
			(unlocked yes)
			(layer "F.Fab")
			(hide yes)
			(effects
				(font
					(size 1 1)
					(thickness 0.15)
				)
			)
		)
		(property "Public" "False"
			(at 0 0 270)
			(unlocked yes)
			(layer "F.Fab")
			(hide yes)
			(effects
				(font
					(size 1 1)
					(thickness 0.15)
				)
			)
		)
		(sheetname "/DCDC/")
		(sheetfile "dcdc.kicad_sch")
		(attr smd)
		(fp_line
			(start -0.32 0.699)
			(end 0.28 0.699001)
			(stroke
				(width 0.15)
				(type solid)
			)
			(layer "F.SilkS")
		)
		(fp_line
			(start -0.3 -0.701)
			(end 0.298 -0.701)
			(stroke
				(width 0.15)
				(type solid)
			)
			(layer "F.SilkS")
		)
		(fp_poly
			(pts
				(xy 1.95 -0.9) (xy -1.95 -0.9) (xy -1.95 0.9) (xy 1.95 0.9)
			)
			(stroke
				(width 0.05)
				(type default)
			)
			(fill no)
			(layer "F.CrtYd")
		)
		(fp_line
			(start -0.951 0.68)
			(end 0.949 0.68)
			(stroke
				(width 0.15)
				(type solid)
			)
			(layer "F.Fab")
		)
		(fp_line
			(start -0.951 -0.677)
			(end -0.951 0.675001)
			(stroke
				(width 0.15)
				(type solid)
			)
			(layer "F.Fab")
		)
		(fp_line
			(start 0.949 -0.677)
			(end 0.949 0.675)
			(stroke
				(width 0.15)
				(type solid)
			)
			(layer "F.Fab")
		)
		(fp_line
			(start -0.951 -0.682)
			(end 0.949 -0.682)
			(stroke
				(width 0.15)
				(type solid)
			)
			(layer "F.Fab")
		)
		(fp_text user "${REFERENCE}"
			(at -1.9 3.1 90)
			(layer "F.Fab")
			(effects
				(font
					(size 0.7 0.7)
					(thickness 0.15)
				)
				(justify right top)
			)
		)
		(fp_text user "License: Apache-2.0"
			(at -1.9 5.75 90)
			(layer "F.Fab")
			(effects
				(font
					(size 0.7 0.7)
					(thickness 0.15)
				)
				(justify right top)
			)
		)
		(fp_text user "Author: Antmicro"
			(at -1.9 4.4 90)
			(layer "F.Fab")
			(effects
				(font
					(size 0.7 0.7)
					(thickness 0.15)
				)
				(justify right top)
			)
		)
		(pad "1" smd roundrect
			(at -1.099999 0 270)
			(size 1.2 1.3)
			(layers "F.Cu" "F.Mask" "F.Paste")
			(roundrect_rratio 0.25)
			(net 1278 "/DCDC/5V_{AON}_OUT")
			(pintype "passive")
		)
		(pad "2" smd roundrect
			(at 1.099999 0 270)
			(size 1.2 1.3)
			(layers "F.Cu" "F.Mask" "F.Paste")
			(roundrect_rratio 0.25)
			(net 491 "+5V_AON")
			(pintype "passive")
		)
	)
	(footprint "antmicro-footprints:R_0402_1005Metric"
		(layer "F.Cu")
		(at 208.1 66.12 90)
		(descr "Resistor SMD 0402")
		(tags "resistor SMD 0402")
		(property "Reference" "R411"
			(at -0.98 -3.2 0)
			(layer "F.SilkS")
			(effects
				(font
					(size 0.7 0.7)
					(thickness 0.15)
				)
				(justify left bottom)
			)
		)
		(property "Value" "R_11k8_0402"
			(at -1.011843 1.772047 90)
			(layer "F.Fab")
			(effects
				(font
					(size 0.7 0.7)
					(thickness 0.15)
				)
				(justify left bottom)
			)
		)
		(property "Datasheet" "https://www.bourns.com/docs/product-datasheets/cr.pdf"
			(at 0 0 90)
			(layer "F.Fab")
			(hide yes)
			(effects
				(font
					(size 1.27 1.27)
					(thickness 0.15)
				)
			)
		)
		(property "Description" "SMD Chip Resistor, 11.8 kohm, ± 1%, 100 mW, 0402 [1005 Metric], Thick Film, Precision"
			(at 0 0 90)
			(layer "F.Fab")
			(hide yes)
			(effects
				(font
					(size 1.27 1.27)
					(thickness 0.15)
				)
			)
		)
		(property "MPN" "CR0402-FX-1182GLF"
			(at 0 0 90)
			(unlocked yes)
			(layer "F.Fab")
			(hide yes)
			(effects
				(font
					(size 1 1)
					(thickness 0.15)
				)
			)
		)
		(property "Manufacturer" "Bourns"
			(at 0 0 90)
			(unlocked yes)
			(layer "F.Fab")
			(hide yes)
			(effects
				(font
					(size 1 1)
					(thickness 0.15)
				)
			)
		)
		(property "License" "Apache-2.0"
			(at 0 0 90)
			(unlocked yes)
			(layer "F.Fab")
			(hide yes)
			(effects
				(font
					(size 1 1)
					(thickness 0.15)
				)
			)
		)
		(property "Author" "Antmicro"
			(at 0 0 90)
			(unlocked yes)
			(layer "F.Fab")
			(hide yes)
			(effects
				(font
					(size 1 1)
					(thickness 0.15)
				)
			)
		)
		(property "Val" "11k8"
			(at 0 0 90)
			(unlocked yes)
			(layer "F.Fab")
			(hide yes)
			(effects
				(font
					(size 1 1)
					(thickness 0.15)
				)
			)
		)
		(property "Tolerance" "1%"
			(at 0 0 90)
			(unlocked yes)
			(layer "F.Fab")
			(hide yes)
			(effects
				(font
					(size 1 1)
					(thickness 0.15)
				)
			)
		)
		(sheetname "/Power/")
		(sheetfile "power.kicad_sch")
		(attr smd)
		(fp_rect
			(start -0.925 -0.47)
			(end 0.925 0.47)
			(stroke
				(width 0.05)
				(type default)
			)
			(fill no)
			(layer "F.CrtYd")
		)
		(fp_rect
			(start -0.5 -0.25)
			(end 0.5 0.25)
			(stroke
				(width 0.15)
				(type solid)
			)
			(fill no)
			(layer "F.Fab")
		)
		(fp_text user "License: Apache-2.0"
			(at -0.95 5.169 90)
			(layer "F.Fab")
			(effects
				(font
					(size 0.7 0.7)
					(thickness 0.15)
				)
				(justify left bottom)
			)
		)
		(fp_text user "Author: Antmicro"
			(at -0.95 4.169 90)
			(layer "F.Fab")
			(effects
				(font
					(size 0.7 0.7)
					(thickness 0.15)
				)
				(justify left bottom)
			)
		)
		(fp_text user "${REFERENCE}"
			(at -0.95 3.168 90)
			(layer "F.Fab")
			(effects
				(font
					(size 0.7 0.7)
					(thickness 0.15)
				)
				(justify left bottom)
			)
		)
		(pad "1" smd roundrect
			(at -0.48 0 90)
			(size 0.59 0.64)
			(layers "F.Cu" "F.Mask" "F.Paste")
			(roundrect_rratio 0.25)
			(net 1 "GND")
			(pintype "passive")
		)
		(pad "2" smd roundrect
			(at 0.48 0 90)
			(size 0.59 0.64)
			(layers "F.Cu" "F.Mask" "F.Paste")
			(roundrect_rratio 0.25)
			(net 1386 "Net-(U9-SET)")
			(pintype "passive")
		)
	)
	(footprint "antmicro-footprints:R_0402_1005Metric"
		(layer "F.Cu")
		(at 214 131.8)
		(descr "Resistor SMD 0402")
		(tags "resistor SMD 0402")
		(property "Reference" "R261"
			(at -0.6 -1.5 0)
			(layer "F.SilkS")
			(effects
				(font
					(size 0.7 0.7)
					(thickness 0.15)
				)
				(justify left bottom)
			)
		)
		(property "Value" "R_43k_0402"
			(at -1.011843 1.772047 0)
			(layer "F.Fab")
			(effects
				(font
					(size 0.7 0.7)
					(thickness 0.15)
				)
				(justify left bottom)
			)
		)
		(property "Datasheet" "https://www.bourns.com/docs/product-datasheets/cr.pdf"
			(at 0 0 0)
			(layer "F.Fab")
			(hide yes)
			(effects
				(font
					(size 1.27 1.27)
					(thickness 0.15)
				)
			)
		)
		(property "Description" "SMD Chip Resistor"
			(at 0 0 0)
			(layer "F.Fab")
			(hide yes)
			(effects
				(font
					(size 1.27 1.27)
					(thickness 0.15)
				)
			)
		)
		(property "MPN" "CR0402-FX-4302GLF"
			(at 0 0 0)
			(unlocked yes)
			(layer "F.Fab")
			(hide yes)
			(effects
				(font
					(size 1 1)
					(thickness 0.15)
				)
			)
		)
		(property "Manufacturer" "Bourns"
			(at 0 0 0)
			(unlocked yes)
			(layer "F.Fab")
			(hide yes)
			(effects
				(font
					(size 1 1)
					(thickness 0.15)
				)
			)
		)
		(property "License" "Apache-2.0"
			(at 0 0 0)
			(unlocked yes)
			(layer "F.Fab")
			(hide yes)
			(effects
				(font
					(size 1 1)
					(thickness 0.15)
				)
			)
		)
		(property "Author" "Antmicro"
			(at 0 0 0)
			(unlocked yes)
			(layer "F.Fab")
			(hide yes)
			(effects
				(font
					(size 1 1)
					(thickness 0.15)
				)
			)
		)
		(property "Val" "43k"
			(at 0 0 0)
			(unlocked yes)
			(layer "F.Fab")
			(hide yes)
			(effects
				(font
					(size 1 1)
					(thickness 0.15)
				)
			)
		)
		(property "Tolerance" "1%"
			(at 0 0 0)
			(unlocked yes)
			(layer "F.Fab")
			(hide yes)
			(effects
				(font
					(size 1 1)
					(thickness 0.15)
				)
			)
		)
		(sheetname "/USB Hub/")
		(sheetfile "usb_hub.kicad_sch")
		(attr smd)
		(fp_rect
			(start -0.925 -0.47)
			(end 0.925 0.47)
			(stroke
				(width 0.05)
				(type default)
			)
			(fill no)
			(layer "F.CrtYd")
		)
		(fp_rect
			(start -0.5 -0.25)
			(end 0.5 0.25)
			(stroke
				(width 0.15)
				(type solid)
			)
			(fill no)
			(layer "F.Fab")
		)
		(fp_text user "${REFERENCE}"
			(at -0.95 3.168 0)
			(layer "F.Fab")
			(effects
				(font
					(size 0.7 0.7)
					(thickness 0.15)
				)
				(justify left bottom)
			)
		)
		(fp_text user "Author: Antmicro"
			(at -0.95 4.169 0)
			(layer "F.Fab")
			(effects
				(font
					(size 0.7 0.7)
					(thickness 0.15)
				)
				(justify left bottom)
			)
		)
		(fp_text user "License: Apache-2.0"
			(at -0.95 5.169 0)
			(layer "F.Fab")
			(effects
				(font
					(size 0.7 0.7)
					(thickness 0.15)
				)
				(justify left bottom)
			)
		)
		(pad "1" smd roundrect
			(at -0.48 0)
			(size 0.59 0.64)
			(layers "F.Cu" "F.Mask" "F.Paste")
			(roundrect_rratio 0.25)
			(net 932 "/USB Hub/USBC4_VBUS_MON")
			(pintype "passive")
		)
		(pad "2" smd roundrect
			(at 0.48 0)
			(size 0.59 0.64)
			(layers "F.Cu" "F.Mask" "F.Paste")
			(roundrect_rratio 0.25)
			(net 115 "/USB Hub/USBC4_VBUS")
			(pintype "passive")
		)
	)
	(footprint "antmicro-footprints:TP_SMD_0.75mm"
		(layer "F.Cu")
		(at 69.289 59.331 90)
		(property "Reference" "TP24"
			(at 0.52 3.19 0)
			(layer "F.SilkS")
			(effects
				(font
					(size 0.7 0.7)
					(thickness 0.15)
				)
				(justify right top)
			)
		)
		(property "Value" "TP_0.75mm_SMD"
			(at 0 1.2 90)
			(layer "F.Fab")
			(effects
				(font
					(size 0.7 0.7)
					(thickness 0.15)
				)
				(justify left bottom)
			)
		)
		(property "Description" "SMT test point"
			(at 0 0 90)
			(layer "F.Fab")
			(hide yes)
			(effects
				(font
					(size 1.27 1.27)
					(thickness 0.15)
				)
			)
		)
		(property "MPN" ""
			(at 0 0 90)
			(unlocked yes)
			(layer "F.Fab")
			(hide yes)
			(effects
				(font
					(size 1 1)
					(thickness 0.15)
				)
			)
		)
		(property "Manufacturer" ""
			(at 0 0 90)
			(unlocked yes)
			(layer "F.Fab")
			(hide yes)
			(effects
				(font
					(size 1 1)
					(thickness 0.15)
				)
			)
		)
		(property "Author" "Antmicro"
			(at 0 0 90)
			(unlocked yes)
			(layer "F.Fab")
			(hide yes)
			(effects
				(font
					(size 1 1)
					(thickness 0.15)
				)
			)
		)
		(property "License" "Apache-2.0"
			(at 0 0 90)
			(unlocked yes)
			(layer "F.Fab")
			(hide yes)
			(effects
				(font
					(size 1 1)
					(thickness 0.15)
				)
			)
		)
		(sheetname "/CSI/")
		(sheetfile "csi.kicad_sch")
		(attr exclude_from_pos_files exclude_from_bom)
		(fp_circle
			(center 0 0)
			(end 0.475 0)
			(stroke
				(width 0.05)
				(type default)
			)
			(fill no)
			(layer "F.CrtYd")
		)
		(fp_text user "License: Apache-2.0"
			(at -0.4 5.101 90)
			(layer "F.Fab")
			(effects
				(font
					(size 0.7 0.7)
					(thickness 0.15)
				)
				(justify left bottom)
			)
		)
		(fp_text user "${REFERENCE}"
			(at -0.4 2.7 90)
			(layer "F.Fab")
			(effects
				(font
					(size 0.7 0.7)
					(thickness 0.15)
				)
				(justify left bottom)
			)
		)
		(fp_text user "Author: Antmicro"
			(at -0.4 3.901 90)
			(layer "F.Fab")
			(effects
				(font
					(size 0.7 0.7)
					(thickness 0.15)
				)
				(justify left bottom)
			)
		)
		(pad "1" smd circle
			(at 0 0 90)
			(size 0.75 0.75)
			(layers "F.Cu" "F.Mask")
			(net 1048 "/CSI/MUX_I2C_5_SCL")
			(pinfunction "1")
			(pintype "passive")
		)
	)
	(footprint "antmicro-footprints:C_0402_1005Metric"
		(layer "F.Cu")
		(at 152.48 114.8)
		(descr "Capacitor SMD 0402")
		(tags "capacitor SMD 0402")
		(property "Reference" "C9"
			(at 0.92 1.6 0)
			(layer "F.SilkS")
			(effects
				(font
					(size 0.7 0.7)
					(thickness 0.15)
				)
				(justify left bottom)
			)
		)
		(property "Value" "C_100n_0402"
			(at -1.022927 2.155213 0)
			(layer "F.Fab")
			(effects
				(font
					(size 0.7 0.7)
					(thickness 0.15)
				)
				(justify left bottom)
			)
		)
		(property "Datasheet" "https://www.murata.com/products/productdetail?partno=GRM155R61H104KE14%23"
			(at 0 0 0)
			(layer "F.Fab")
			(hide yes)
			(effects
				(font
					(size 1.27 1.27)
					(thickness 0.15)
				)
			)
		)
		(property "Description" "SMD Multilayer Ceramic Capacitor, 0.1 µF, 50 V, 0402 [1005 Metric], ± 10%, X5R, GRM Series"
			(at 0 0 0)
			(layer "F.Fab")
			(hide yes)
			(effects
				(font
					(size 1.27 1.27)
					(thickness 0.15)
				)
			)
		)
		(property "Manufacturer" "Murata"
			(at 0 0 0)
			(unlocked yes)
			(layer "F.Fab")
			(hide yes)
			(effects
				(font
					(size 1 1)
					(thickness 0.15)
				)
			)
		)
		(property "MPN" "GRM155R61H104KE14D"
			(at 0 0 0)
			(unlocked yes)
			(layer "F.Fab")
			(hide yes)
			(effects
				(font
					(size 1 1)
					(thickness 0.15)
				)
			)
		)
		(property "Val" "100n"
			(at 0 0 0)
			(unlocked yes)
			(layer "F.Fab")
			(hide yes)
			(effects
				(font
					(size 1 1)
					(thickness 0.15)
				)
			)
		)
		(property "License" "Apache-2.0"
			(at 0 0 0)
			(unlocked yes)
			(layer "F.Fab")
			(hide yes)
			(effects
				(font
					(size 1 1)
					(thickness 0.15)
				)
			)
		)
		(property "Author" "Antmicro"
			(at 0 0 0)
			(unlocked yes)
			(layer "F.Fab")
			(hide yes)
			(effects
				(font
					(size 1 1)
					(thickness 0.15)
				)
			)
		)
		(property "Voltage" "50V"
			(at 0 0 0)
			(unlocked yes)
			(layer "F.Fab")
			(hide yes)
			(effects
				(font
					(size 1 1)
					(thickness 0.15)
				)
			)
		)
		(property "Dielectric" "X5R"
			(at 0 0 0)
			(unlocked yes)
			(layer "F.Fab")
			(hide yes)
			(effects
				(font
					(size 1 1)
					(thickness 0.15)
				)
			)
		)
		(sheetname "/SoM_IO/")
		(sheetfile "som_io.kicad_sch")
		(attr smd)
		(fp_poly
			(pts
				(xy -0.925 -0.47) (xy -0.925 0.47) (xy 0.925 0.47) (xy 0.925 -0.47)
			)
			(stroke
				(width 0.05)
				(type default)
			)
			(fill no)
			(layer "F.CrtYd")
		)
		(fp_line
			(start -0.494 -0.25)
			(end 0.504 -0.25)
			(stroke
				(width 0.15)
				(type solid)
			)
			(layer "F.Fab")
		)
		(fp_line
			(start -0.494 0.248)
			(end -0.494 -0.25)
			(stroke
				(width 0.15)
				(type solid)
			)
			(layer "F.Fab")
		)
		(fp_line
			(start 0.504 -0.25)
			(end 0.504 0.248)
			(stroke
				(width 0.15)
				(type solid)
			)
			(layer "F.Fab")
		)
		(fp_line
			(start 0.504 0.248)
			(end -0.494 0.248)
			(stroke
				(width 0.15)
				(type solid)
			)
			(layer "F.Fab")
		)
		(fp_text user "License: Apache-2.0"
			(at -0.939 5.799 0)
			(layer "F.Fab")
			(effects
				(font
					(size 0.7 0.7)
					(thickness 0.15)
				)
				(justify left bottom)
			)
		)
		(fp_text user "${REFERENCE}"
			(at -0.939 4.599 0)
			(layer "F.Fab")
			(effects
				(font
					(size 0.7 0.7)
					(thickness 0.15)
				)
				(justify left bottom)
			)
		)
		(fp_text user "Author: Antmicro"
			(at -0.939 3.399 0)
			(layer "F.Fab")
			(effects
				(font
					(size 0.7 0.7)
					(thickness 0.15)
				)
				(justify left bottom)
			)
		)
		(pad "1" smd roundrect
			(at -0.48 0)
			(size 0.59 0.64)
			(layers "F.Cu" "F.Mask" "F.Paste")
			(roundrect_rratio 0.25)
			(net 1 "GND")
			(pintype "passive")
		)
		(pad "2" smd roundrect
			(at 0.48 0)
			(size 0.59 0.64)
			(layers "F.Cu" "F.Mask" "F.Paste")
			(roundrect_rratio 0.25)
			(net 11 "+1V8")
			(pintype "passive")
		)
	)
	(footprint "antmicro-footprints:LED_0603_1608Metric_G"
		(layer "F.Cu")
		(at 175.25 55.32 -90)
		(descr "LED SMD 0603 Green")
		(tags "LED SMD 0603 Green")
		(property "Reference" "D61"
			(at -1.055 1.495 90)
			(layer "F.SilkS")
			(effects
				(font
					(size 0.7 0.7)
					(thickness 0.15)
				)
				(justify right top)
			)
		)
		(property "Value" "LED_G_0603_LTST-C190GKT"
			(at -0.001 1.599 90)
			(layer "F.Fab")
			(effects
				(font
					(size 0.7 0.7)
					(thickness 0.15)
				)
				(justify right top)
			)
		)
		(property "Datasheet" "https://media.digikey.com/pdf/Data%20Sheets/Lite-On%20PDFs/LTST-C190GKT.pdf"
			(at 0 0 90)
			(layer "F.Fab")
			(hide yes)
			(effects
				(font
					(size 1.27 1.27)
					(thickness 0.15)
				)
			)
		)
		(property "Description" "LED, Green, SMD, 0603, 20 mA, 2.1 V, 569 nm"
			(at 0 0 90)
			(layer "F.Fab")
			(hide yes)
			(effects
				(font
					(size 1.27 1.27)
					(thickness 0.15)
				)
			)
		)
		(property "MPN" "LTST-C190GKT"
			(at 0 0 270)
			(unlocked yes)
			(layer "F.Fab")
			(hide yes)
			(effects
				(font
					(size 1 1)
					(thickness 0.15)
				)
			)
		)
		(property "Manufacturer" "Lite-On"
			(at 0 0 270)
			(unlocked yes)
			(layer "F.Fab")
			(hide yes)
			(effects
				(font
					(size 1 1)
					(thickness 0.15)
				)
			)
		)
		(property "Author" "Antmicro"
			(at 0 0 270)
			(unlocked yes)
			(layer "F.Fab")
			(hide yes)
			(effects
				(font
					(size 1 1)
					(thickness 0.15)
				)
			)
		)
		(property "License" "Apache-2.0"
			(at 0 0 270)
			(unlocked yes)
			(layer "F.Fab")
			(hide yes)
			(effects
				(font
					(size 1 1)
					(thickness 0.15)
				)
			)
		)
		(property "Color" "Green"
			(at 0 0 270)
			(unlocked yes)
			(layer "F.Fab")
			(hide yes)
			(effects
				(font
					(size 1 1)
					(thickness 0.15)
				)
			)
		)
		(sheetname "/Power/")
		(sheetfile "power.kicad_sch")
		(attr smd)
		(fp_line
			(start 0.22 0.35)
			(end -0.22 0.35)
			(stroke
				(width 0.15)
				(type solid)
			)
			(layer "F.SilkS")
		)
		(fp_line
			(start -0.094672 0.201008)
			(end -0.094672 -0.198992)
			(stroke
				(width 0.1)
				(type solid)
			)
			(layer "F.SilkS")
		)
		(fp_line
			(start 0.105328 0.201008)
			(end -0.094672 0.001008)
			(stroke
				(width 0.1)
				(type solid)
			)
			(layer "F.SilkS")
		)
		(fp_line
			(start 0.105328 0.201008)
			(end 0.105328 -0.198992)
			(stroke
				(width 0.1)
				(type solid)
			)
			(layer "F.SilkS")
		)
		(fp_line
			(start -0.094672 0.001008)
			(end -0.24 0.001008)
			(stroke
				(width 0.1)
				(type solid)
			)
			(layer "F.SilkS")
		)
		(fp_line
			(start -0.094672 0.001008)
			(end 0.105328 -0.198992)
			(stroke
				(width 0.1)
				(type solid)
			)
			(layer "F.SilkS")
		)
		(fp_line
			(start 0.105328 0.001008)
			(end 0.24 0.001)
			(stroke
				(width 0.1)
				(type solid)
			)
			(layer "F.SilkS")
		)
		(fp_line
			(start -1.18 -0.319)
			(end -1.18 0.321)
			(stroke
				(width 0.15)
				(type solid)
			)
			(layer "F.SilkS")
		)
		(fp_line
			(start 0.22 -0.35)
			(end -0.22 -0.35)
			(stroke
				(width 0.15)
				(type solid)
			)
			(layer "F.SilkS")
		)
		(fp_rect
			(start 1.25 0.65)
			(end -1.25 -0.65)
			(stroke
				(width 0.05)
				(type solid)
			)
			(fill no)
			(layer "F.CrtYd")
		)
		(fp_line
			(start -0.199 0.2)
			(end -0.199 0.1)
			(stroke
				(width 0.15)
				(type solid)
			)
			(layer "F.Fab")
		)
		(fp_line
			(start 0.201 0.2)
			(end 0.201 0)
			(stroke
				(width 0.15)
				(type solid)
			)
			(layer "F.Fab")
		)
		(fp_line
			(start -0.199 0)
			(end -0.597 0)
			(stroke
				(width 0.15)
				(type solid)
			)
			(layer "F.Fab")
		)
		(fp_line
			(start -0.101 0)
			(end 0.201 0.2)
			(stroke
				(width 0.15)
				(type solid)
			)
			(layer "F.Fab")
		)
		(fp_line
			(start 0.201 0)
			(end 0.201 -0.202)
			(stroke
				(width 0.15)
				(type solid)
			)
			(layer "F.Fab")
		)
		(fp_line
			(start 0.599 0)
			(end 0.201 0)
			(stroke
				(width 0.15)
				(type solid)
			)
			(layer "F.Fab")
		)
		(fp_line
			(start -0.199 -0.202)
			(end -0.199 0.1)
			(stroke
				(width 0.15)
				(type solid)
			)
			(layer "F.Fab")
		)
		(fp_line
			(start 0.201 -0.202)
			(end -0.101 0)
			(stroke
				(width 0.15)
				(type solid)
			)
			(layer "F.Fab")
		)
		(fp_rect
			(start 0.848 0.4)
			(end -0.85 -0.402)
			(stroke
				(width 0.15)
				(type solid)
			)
			(fill no)
			(layer "F.Fab")
		)
		(fp_text user "Author: Antmicro"
			(at -1.4224 4.799 90)
			(layer "F.Fab")
			(effects
				(font
					(size 0.7 0.7)
					(thickness 0.15)
				)
				(justify right top)
			)
		)
		(fp_text user "License: Apache-2.0"
			(at -1.4224 3.599 90)
			(layer "F.Fab")
			(effects
				(font
					(size 0.7 0.7)
					(thickness 0.15)
				)
				(justify right top)
			)
		)
		(fp_text user "${REFERENCE}"
			(at -1.4224 5.999 90)
			(layer "F.Fab")
			(effects
				(font
					(size 0.7 0.7)
					(thickness 0.15)
				)
				(justify right top)
			)
		)
		(pad "1" smd roundrect
			(at -0.7 0 90)
			(size 0.8 1)
			(layers "F.Cu" "F.Mask" "F.Paste")
			(roundrect_rratio 0.2)
			(net 1 "GND")
			(pinfunction "C")
			(pintype "passive")
		)
		(pad "2" smd roundrect
			(at 0.7 0 90)
			(size 0.8 1)
			(layers "F.Cu" "F.Mask" "F.Paste")
			(roundrect_rratio 0.2)
			(net 1286 "Net-(D61-A)")
			(pinfunction "A")
			(pintype "passive")
		)
	)
	(footprint "antmicro-footprints:C_0805_2012Metric"
		(layer "F.Cu")
		(at 164.059468 73.31 -90)
		(descr "Capacitor SMD 0805")
		(tags "capacitor SMD 0805")
		(property "Reference" "C301"
			(at -4.81 -0.540532 90)
			(layer "F.SilkS")
			(effects
				(font
					(size 0.7 0.7)
					(thickness 0.15)
				)
				(justify right top)
			)
		)
		(property "Value" "C_22u_25V_0805"
			(at -2.055717 1.963152 90)
			(layer "F.Fab")
			(effects
				(font
					(size 0.7 0.7)
					(thickness 0.15)
				)
				(justify right top)
			)
		)
		(property "Datasheet" "https://product.samsungsem.com/mlcc/CL21A226MAYNNN.do"
			(at 0 0 90)
			(layer "F.Fab")
			(hide yes)
			(effects
				(font
					(size 1.27 1.27)
					(thickness 0.15)
				)
			)
		)
		(property "Description" "SMT Multilayer Ceramic Capacitor, 22uF, +/-20%, 25V, X5R, 0805 [2012 Metric]"
			(at 0 0 90)
			(layer "F.Fab")
			(hide yes)
			(effects
				(font
					(size 1.27 1.27)
					(thickness 0.15)
				)
			)
		)
		(property "MPN" "CL21A226MAYNNNE"
			(at 0 0 270)
			(unlocked yes)
			(layer "F.Fab")
			(hide yes)
			(effects
				(font
					(size 1 1)
					(thickness 0.15)
				)
			)
		)
		(property "Manufacturer" "Samsung Electro-Mechanics"
			(at 0 0 270)
			(unlocked yes)
			(layer "F.Fab")
			(hide yes)
			(effects
				(font
					(size 1 1)
					(thickness 0.15)
				)
			)
		)
		(property "License" "Apache-2.0"
			(at 0 0 270)
			(unlocked yes)
			(layer "F.Fab")
			(hide yes)
			(effects
				(font
					(size 1 1)
					(thickness 0.15)
				)
			)
		)
		(property "Author" "Antmicro"
			(at 0 0 270)
			(unlocked yes)
			(layer "F.Fab")
			(hide yes)
			(effects
				(font
					(size 1 1)
					(thickness 0.15)
				)
			)
		)
		(property "Val" "22u"
			(at 0 0 270)
			(unlocked yes)
			(layer "F.Fab")
			(hide yes)
			(effects
				(font
					(size 1 1)
					(thickness 0.15)
				)
			)
		)
		(property "Voltage" "25V"
			(at 0 0 270)
			(unlocked yes)
			(layer "F.Fab")
			(hide yes)
			(effects
				(font
					(size 1 1)
					(thickness 0.15)
				)
			)
		)
		(property "Dielectric" "X5R"
			(at 0 0 270)
			(unlocked yes)
			(layer "F.Fab")
			(hide yes)
			(effects
				(font
					(size 1 1)
					(thickness 0.15)
				)
			)
		)
		(property "Public" "False"
			(at 0 0 270)
			(unlocked yes)
			(layer "F.Fab")
			(hide yes)
			(effects
				(font
					(size 1 1)
					(thickness 0.15)
				)
			)
		)
		(component_classes
			(class "DCDC_20V")
		)
		(sheetname "/DCDC/")
		(sheetfile "dcdc.kicad_sch")
		(attr smd)
		(fp_line
			(start -0.3 0.7)
			(end 0.3 0.7)
			(stroke
				(width 0.15)
				(type solid)
			)
			(layer "F.SilkS")
		)
		(fp_line
			(start -0.3 -0.7)
			(end 0.3 -0.7)
			(stroke
				(width 0.15)
				(type solid)
			)
			(layer "F.SilkS")
		)
		(fp_rect
			(start 1.95 -0.9)
			(end -1.95 0.9)
			(stroke
				(width 0.05)
				(type default)
			)
			(fill no)
			(layer "F.CrtYd")
		)
		(fp_rect
			(start -0.95 -0.675)
			(end 0.95 0.675)
			(stroke
				(width 0.15)
				(type solid)
			)
			(fill no)
			(layer "F.Fab")
		)
		(fp_text user "License: Apache-2.0"
			(at -1.9 4.947 90)
			(layer "F.Fab")
			(effects
				(font
					(size 0.7 0.7)
					(thickness 0.15)
				)
				(justify right top)
			)
		)
		(fp_text user "Author: Antmicro"
			(at -1.9 5.947 90)
			(layer "F.Fab")
			(effects
				(font
					(size 0.7 0.7)
					(thickness 0.15)
				)
				(justify right top)
			)
		)
		(fp_text user "${REFERENCE}"
			(at -1.9 3.947 90)
			(layer "F.Fab")
			(effects
				(font
					(size 0.7 0.7)
					(thickness 0.15)
				)
				(justify right top)
			)
		)
		(pad "1" smd roundrect
			(at -1.1 0 270)
			(size 1.2 1.3)
			(layers "F.Cu" "F.Mask" "F.Paste")
			(roundrect_rratio 0.25)
			(net 1 "GND")
			(pintype "passive")
		)
		(pad "2" smd roundrect
			(at 1.1 0 270)
			(size 1.2 1.3)
			(layers "F.Cu" "F.Mask" "F.Paste")
			(roundrect_rratio 0.25)
			(net 1105 "/DCDC/20V_OUT")
			(pintype "passive")
		)
	)
	(footprint "antmicro-footprints:R_0402_1005Metric"
		(layer "F.Cu")
		(at 147.8 117.2)
		(descr "Resistor SMD 0402")
		(tags "resistor SMD 0402")
		(property "Reference" "R360"
			(at -3.7 0.5 0)
			(layer "F.SilkS")
			(effects
				(font
					(size 0.7 0.7)
					(thickness 0.15)
				)
				(justify left bottom)
			)
		)
		(property "Value" "R_2k2_0402"
			(at -1.011843 1.772047 0)
			(layer "F.Fab")
			(effects
				(font
					(size 0.7 0.7)
					(thickness 0.15)
				)
				(justify left bottom)
			)
		)
		(property "Datasheet" "https://www.bourns.com/docs/product-datasheets/cr.pdf"
			(at 0 0 0)
			(layer "F.Fab")
			(hide yes)
			(effects
				(font
					(size 1.27 1.27)
					(thickness 0.15)
				)
			)
		)
		(property "Description" "SMD Chip Resistor, 2.2 kohm, ± 1%, 62.5 mW, 0402 [1005 Metric], Thick Film, General Purpose"
			(at 0 0 0)
			(layer "F.Fab")
			(hide yes)
			(effects
				(font
					(size 1.27 1.27)
					(thickness 0.15)
				)
			)
		)
		(property "MPN" "CR0402-FX-2201GLF"
			(at 0 0 0)
			(unlocked yes)
			(layer "F.Fab")
			(hide yes)
			(effects
				(font
					(size 1 1)
					(thickness 0.15)
				)
			)
		)
		(property "Manufacturer" "Bourns"
			(at 0 0 0)
			(unlocked yes)
			(layer "F.Fab")
			(hide yes)
			(effects
				(font
					(size 1 1)
					(thickness 0.15)
				)
			)
		)
		(property "License" "Apache-2.0"
			(at 0 0 0)
			(unlocked yes)
			(layer "F.Fab")
			(hide yes)
			(effects
				(font
					(size 1 1)
					(thickness 0.15)
				)
			)
		)
		(property "Author" "Antmicro"
			(at 0 0 0)
			(unlocked yes)
			(layer "F.Fab")
			(hide yes)
			(effects
				(font
					(size 1 1)
					(thickness 0.15)
				)
			)
		)
		(property "Val" "2k2"
			(at 0 0 0)
			(unlocked yes)
			(layer "F.Fab")
			(hide yes)
			(effects
				(font
					(size 1 1)
					(thickness 0.15)
				)
			)
		)
		(property "Tolerance" "1%"
			(at 0 0 0)
			(unlocked yes)
			(layer "F.Fab")
			(hide yes)
			(effects
				(font
					(size 1 1)
					(thickness 0.15)
				)
			)
		)
		(sheetname "/SoM_IO/")
		(sheetfile "som_io.kicad_sch")
		(attr smd)
		(fp_rect
			(start -0.925 -0.47)
			(end 0.925 0.47)
			(stroke
				(width 0.05)
				(type default)
			)
			(fill no)
			(layer "F.CrtYd")
		)
		(fp_rect
			(start -0.5 -0.25)
			(end 0.5 0.25)
			(stroke
				(width 0.15)
				(type solid)
			)
			(fill no)
			(layer "F.Fab")
		)
		(fp_text user "${REFERENCE}"
			(at -0.95 3.168 0)
			(layer "F.Fab")
			(effects
				(font
					(size 0.7 0.7)
					(thickness 0.15)
				)
				(justify left bottom)
			)
		)
		(fp_text user "Author: Antmicro"
			(at -0.95 4.169 0)
			(layer "F.Fab")
			(effects
				(font
					(size 0.7 0.7)
					(thickness 0.15)
				)
				(justify left bottom)
			)
		)
		(fp_text user "License: Apache-2.0"
			(at -0.95 5.169 0)
			(layer "F.Fab")
			(effects
				(font
					(size 0.7 0.7)
					(thickness 0.15)
				)
				(justify left bottom)
			)
		)
		(pad "1" smd roundrect
			(at -0.48 0)
			(size 0.59 0.64)
			(layers "F.Cu" "F.Mask" "F.Paste")
			(roundrect_rratio 0.25)
			(net 2 "+3V3")
			(pintype "passive")
		)
		(pad "2" smd roundrect
			(at 0.48 0)
			(size 0.59 0.64)
			(layers "F.Cu" "F.Mask" "F.Paste")
			(roundrect_rratio 0.25)
			(net 1000 "/SFP/I2C_{SFP}.SCL")
			(pintype "passive")
		)
	)
	(footprint "antmicro-footprints:TP_SMD_0.75mm"
		(layer "F.Cu")
		(at 200.2 73.45 -90)
		(property "Reference" "TP12"
			(at -3.35 0.2 90)
			(layer "F.SilkS")
			(effects
				(font
					(size 0.7 0.7)
					(thickness 0.15)
				)
				(justify right top)
			)
		)
		(property "Value" "TP_0.75mm_SMD"
			(at 0 1.2 90)
			(layer "F.Fab")
			(effects
				(font
					(size 0.7 0.7)
					(thickness 0.15)
				)
				(justify right top)
			)
		)
		(property "Description" "SMT test point"
			(at 0 0 90)
			(layer "F.Fab")
			(hide yes)
			(effects
				(font
					(size 1.27 1.27)
					(thickness 0.15)
				)
			)
		)
		(property "MPN" ""
			(at 0 0 270)
			(unlocked yes)
			(layer "F.Fab")
			(hide yes)
			(effects
				(font
					(size 1 1)
					(thickness 0.15)
				)
			)
		)
		(property "Manufacturer" ""
			(at 0 0 270)
			(unlocked yes)
			(layer "F.Fab")
			(hide yes)
			(effects
				(font
					(size 1 1)
					(thickness 0.15)
				)
			)
		)
		(property "Author" "Antmicro"
			(at 0 0 270)
			(unlocked yes)
			(layer "F.Fab")
			(hide yes)
			(effects
				(font
					(size 1 1)
					(thickness 0.15)
				)
			)
		)
		(property "License" "Apache-2.0"
			(at 0 0 270)
			(unlocked yes)
			(layer "F.Fab")
			(hide yes)
			(effects
				(font
					(size 1 1)
					(thickness 0.15)
				)
			)
		)
		(sheetname "/USB Debug, PD/")
		(sheetfile "usb_debug_pd.kicad_sch")
		(attr exclude_from_pos_files exclude_from_bom)
		(fp_circle
			(center 0 0)
			(end 0.475 0)
			(stroke
				(width 0.05)
				(type default)
			)
			(fill no)
			(layer "F.CrtYd")
		)
		(fp_text user "License: Apache-2.0"
			(at -0.4 5.101 90)
			(layer "F.Fab")
			(effects
				(font
					(size 0.7 0.7)
					(thickness 0.15)
				)
				(justify right top)
			)
		)
		(fp_text user "${REFERENCE}"
			(at -0.4 2.7 90)
			(layer "F.Fab")
			(effects
				(font
					(size 0.7 0.7)
					(thickness 0.15)
				)
				(justify right top)
			)
		)
		(fp_text user "Author: Antmicro"
			(at -0.4 3.901 90)
			(layer "F.Fab")
			(effects
				(font
					(size 0.7 0.7)
					(thickness 0.15)
				)
				(justify right top)
			)
		)
		(pad "1" smd circle
			(at 0 0 270)
			(size 0.75 0.75)
			(layers "F.Cu" "F.Mask")
			(net 1041 "/USB Debug, PD/~{PDC_I2C3_IRQ}")
			(pinfunction "1")
			(pintype "passive")
		)
	)
	(footprint "antmicro-footprints:C_0402_1005Metric"
		(layer "F.Cu")
		(at 133.325 54.875 180)
		(descr "Capacitor SMD 0402")
		(tags "capacitor SMD 0402")
		(property "Reference" "C6"
			(at -11.835 -0.115 0)
			(layer "F.SilkS")
			(effects
				(font
					(size 0.7 0.7)
					(thickness 0.15)
				)
				(justify right top)
			)
		)
		(property "Value" "C_100n_0402"
			(at -1.022927 2.155213 0)
			(layer "F.Fab")
			(effects
				(font
					(size 0.7 0.7)
					(thickness 0.15)
				)
				(justify right top)
			)
		)
		(property "Datasheet" "https://www.murata.com/products/productdetail?partno=GRM155R61H104KE14%23"
			(at 0 0 0)
			(layer "F.Fab")
			(hide yes)
			(effects
				(font
					(size 1.27 1.27)
					(thickness 0.15)
				)
			)
		)
		(property "Description" "SMD Multilayer Ceramic Capacitor, 0.1 µF, 50 V, 0402 [1005 Metric], ± 10%, X5R, GRM Series"
			(at 0 0 0)
			(layer "F.Fab")
			(hide yes)
			(effects
				(font
					(size 1.27 1.27)
					(thickness 0.15)
				)
			)
		)
		(property "MPN" "GRM155R61H104KE14D"
			(at 0 0 180)
			(unlocked yes)
			(layer "F.Fab")
			(hide yes)
			(effects
				(font
					(size 1 1)
					(thickness 0.15)
				)
			)
		)
		(property "Manufacturer" "Murata"
			(at 0 0 180)
			(unlocked yes)
			(layer "F.Fab")
			(hide yes)
			(effects
				(font
					(size 1 1)
					(thickness 0.15)
				)
			)
		)
		(property "License" "Apache-2.0"
			(at 0 0 180)
			(unlocked yes)
			(layer "F.Fab")
			(hide yes)
			(effects
				(font
					(size 1 1)
					(thickness 0.15)
				)
			)
		)
		(property "Author" "Antmicro"
			(at 0 0 180)
			(unlocked yes)
			(layer "F.Fab")
			(hide yes)
			(effects
				(font
					(size 1 1)
					(thickness 0.15)
				)
			)
		)
		(property "Val" "100n"
			(at 0 0 180)
			(unlocked yes)
			(layer "F.Fab")
			(hide yes)
			(effects
				(font
					(size 1 1)
					(thickness 0.15)
				)
			)
		)
		(property "Voltage" "50V"
			(at 0 0 180)
			(unlocked yes)
			(layer "F.Fab")
			(hide yes)
			(effects
				(font
					(size 1 1)
					(thickness 0.15)
				)
			)
		)
		(property "Dielectric" "X5R"
			(at 0 0 180)
			(unlocked yes)
			(layer "F.Fab")
			(hide yes)
			(effects
				(font
					(size 1 1)
					(thickness 0.15)
				)
			)
		)
		(sheetname "/DCDC/")
		(sheetfile "dcdc.kicad_sch")
		(attr smd)
		(fp_rect
			(start -0.925 -0.47)
			(end 0.925 0.47)
			(stroke
				(width 0.05)
				(type default)
			)
			(fill no)
			(layer "F.CrtYd")
		)
		(fp_line
			(start 0.504 0.248)
			(end -0.494 0.248)
			(stroke
				(width 0.15)
				(type solid)
			)
			(layer "F.Fab")
		)
		(fp_line
			(start 0.504 -0.25)
			(end 0.504 0.248)
			(stroke
				(width 0.15)
				(type solid)
			)
			(layer "F.Fab")
		)
		(fp_line
			(start -0.494 0.248)
			(end -0.494 -0.25)
			(stroke
				(width 0.15)
				(type solid)
			)
			(layer "F.Fab")
		)
		(fp_line
			(start -0.494 -0.25)
			(end 0.504 -0.25)
			(stroke
				(width 0.15)
				(type solid)
			)
			(layer "F.Fab")
		)
		(fp_text user "Author: Antmicro"
			(at -0.939 3.399 0)
			(layer "F.Fab")
			(effects
				(font
					(size 0.7 0.7)
					(thickness 0.15)
				)
				(justify right top)
			)
		)
		(fp_text user "${REFERENCE}"
			(at -0.939 4.599 0)
			(layer "F.Fab")
			(effects
				(font
					(size 0.7 0.7)
					(thickness 0.15)
				)
				(justify right top)
			)
		)
		(fp_text user "License: Apache-2.0"
			(at -0.939 5.799 0)
			(layer "F.Fab")
			(effects
				(font
					(size 0.7 0.7)
					(thickness 0.15)
				)
				(justify right top)
			)
		)
		(pad "1" smd roundrect
			(at -0.48 0 180)
			(size 0.59 0.64)
			(layers "F.Cu" "F.Mask" "F.Paste")
			(roundrect_rratio 0.25)
			(net 1 "GND")
			(pintype "passive")
		)
		(pad "2" smd roundrect
			(at 0.48 0 180)
			(size 0.59 0.64)
			(layers "F.Cu" "F.Mask" "F.Paste")
			(roundrect_rratio 0.25)
			(net 1305 "/DCDC/5V_{AON}_EN")
			(pintype "passive")
		)
	)
	(footprint "antmicro-footprints:R_0402_1005Metric"
		(layer "F.Cu")
		(at 193.026 140.1 180)
		(descr "Resistor SMD 0402")
		(tags "resistor SMD 0402")
		(property "Reference" "R205"
			(at -1.574 1.6 0)
			(layer "F.SilkS")
			(effects
				(font
					(size 0.7 0.7)
					(thickness 0.15)
				)
				(justify right top)
			)
		)
		(property "Value" "R_200R_0402"
			(at -1.011843 1.772046 0)
			(layer "F.Fab")
			(effects
				(font
					(size 0.7 0.7)
					(thickness 0.15)
				)
				(justify right top)
			)
		)
		(property "Datasheet" "https://www.bourns.com/docs/product-datasheets/cr.pdf"
			(at 0 0 0)
			(layer "F.Fab")
			(hide yes)
			(effects
				(font
					(size 1.27 1.27)
					(thickness 0.15)
				)
			)
		)
		(property "Description" "SMD Chip Resistor, 200 ohm, ± 1%, 62.5 mW, 0402 [1005 Metric], Thick Film, General Purpose"
			(at 0 0 0)
			(layer "F.Fab")
			(hide yes)
			(effects
				(font
					(size 1.27 1.27)
					(thickness 0.15)
				)
			)
		)
		(property "MPN" "CR0402-FX-2000GLF"
			(at 0 0 180)
			(unlocked yes)
			(layer "F.Fab")
			(hide yes)
			(effects
				(font
					(size 1 1)
					(thickness 0.15)
				)
			)
		)
		(property "Manufacturer" "Bourns"
			(at 0 0 180)
			(unlocked yes)
			(layer "F.Fab")
			(hide yes)
			(effects
				(font
					(size 1 1)
					(thickness 0.15)
				)
			)
		)
		(property "License" "Apache-2.0"
			(at 0 0 180)
			(unlocked yes)
			(layer "F.Fab")
			(hide yes)
			(effects
				(font
					(size 1 1)
					(thickness 0.15)
				)
			)
		)
		(property "Author" "Antmicro"
			(at 0 0 180)
			(unlocked yes)
			(layer "F.Fab")
			(hide yes)
			(effects
				(font
					(size 1 1)
					(thickness 0.15)
				)
			)
		)
		(property "Val" "200R"
			(at 0 0 180)
			(unlocked yes)
			(layer "F.Fab")
			(hide yes)
			(effects
				(font
					(size 1 1)
					(thickness 0.15)
				)
			)
		)
		(property "Tolerance" "1%"
			(at 0 0 180)
			(unlocked yes)
			(layer "F.Fab")
			(hide yes)
			(effects
				(font
					(size 1 1)
					(thickness 0.15)
				)
			)
		)
		(sheetname "/SFP/")
		(sheetfile "sfp.kicad_sch")
		(attr smd)
		(fp_poly
			(pts
				(xy -0.925 -0.47) (xy 0.925 -0.47) (xy 0.925 0.47) (xy -0.925 0.47)
			)
			(stroke
				(width 0.05)
				(type default)
			)
			(fill no)
			(layer "F.CrtYd")
		)
		(fp_poly
			(pts
				(xy -0.5 -0.25) (xy 0.5 -0.25) (xy 0.5 0.25) (xy -0.5 0.25)
			)
			(stroke
				(width 0.15)
				(type solid)
			)
			(fill no)
			(layer "F.Fab")
		)
		(fp_text user "License: Apache-2.0"
			(at -0.949999 5.169 0)
			(layer "F.Fab")
			(effects
				(font
					(size 0.7 0.7)
					(thickness 0.15)
				)
				(justify right top)
			)
		)
		(fp_text user "Author: Antmicro"
			(at -0.95 4.169 0)
			(layer "F.Fab")
			(effects
				(font
					(size 0.7 0.7)
					(thickness 0.15)
				)
				(justify right top)
			)
		)
		(fp_text user "${REFERENCE}"
			(at -0.95 3.168 0)
			(layer "F.Fab")
			(effects
				(font
					(size 0.7 0.7)
					(thickness 0.15)
				)
				(justify right top)
			)
		)
		(pad "1" smd roundrect
			(at -0.48 0 180)
			(size 0.59 0.64)
			(layers "F.Cu" "F.Mask" "F.Paste")
			(roundrect_rratio 0.25)
			(net 1004 "/SFP/SFP_LEDG")
			(pintype "passive")
		)
		(pad "2" smd roundrect
			(at 0.48 0 180)
			(size 0.59 0.64)
			(layers "F.Cu" "F.Mask" "F.Paste")
			(roundrect_rratio 0.25)
			(net 530 "Net-(D14-C)")
			(pintype "passive")
		)
	)
	(footprint "antmicro-footprints:R_0402_1005Metric"
		(layer "F.Cu")
		(at 173.24 63.49 90)
		(descr "Resistor SMD 0402")
		(tags "resistor SMD 0402")
		(property "Reference" "R234"
			(at -1.01 2.36 90)
			(layer "F.SilkS")
			(effects
				(font
					(size 0.7 0.7)
					(thickness 0.15)
				)
				(justify left bottom)
			)
		)
		(property "Value" "R_200R_0402"
			(at -1.011843 1.772047 90)
			(layer "F.Fab")
			(effects
				(font
					(size 0.7 0.7)
					(thickness 0.15)
				)
				(justify left bottom)
			)
		)
		(property "Datasheet" "https://www.bourns.com/docs/product-datasheets/cr.pdf"
			(at 0 0 90)
			(layer "F.Fab")
			(hide yes)
			(effects
				(font
					(size 1.27 1.27)
					(thickness 0.15)
				)
			)
		)
		(property "Description" "SMD Chip Resistor, 200 ohm, ± 1%, 62.5 mW, 0402 [1005 Metric], Thick Film, General Purpose"
			(at 0 0 90)
			(layer "F.Fab")
			(hide yes)
			(effects
				(font
					(size 1.27 1.27)
					(thickness 0.15)
				)
			)
		)
		(property "Manufacturer" "Bourns"
			(at 0 0 90)
			(unlocked yes)
			(layer "F.Fab")
			(hide yes)
			(effects
				(font
					(size 1 1)
					(thickness 0.15)
				)
			)
		)
		(property "MPN" "CR0402-FX-2000GLF"
			(at 0 0 90)
			(unlocked yes)
			(layer "F.Fab")
			(hide yes)
			(effects
				(font
					(size 1 1)
					(thickness 0.15)
				)
			)
		)
		(property "Val" "200R"
			(at 0 0 90)
			(unlocked yes)
			(layer "F.Fab")
			(hide yes)
			(effects
				(font
					(size 1 1)
					(thickness 0.15)
				)
			)
		)
		(property "License" "Apache-2.0"
			(at 0 0 90)
			(unlocked yes)
			(layer "F.Fab")
			(hide yes)
			(effects
				(font
					(size 1 1)
					(thickness 0.15)
				)
			)
		)
		(property "Author" "Antmicro"
			(at 0 0 90)
			(unlocked yes)
			(layer "F.Fab")
			(hide yes)
			(effects
				(font
					(size 1 1)
					(thickness 0.15)
				)
			)
		)
		(property "Tolerance" "1%"
			(at 0 0 90)
			(unlocked yes)
			(layer "F.Fab")
			(hide yes)
			(effects
				(font
					(size 1 1)
					(thickness 0.15)
				)
			)
		)
		(sheetname "/Peripherals/")
		(sheetfile "peripherals.kicad_sch")
		(attr smd)
		(fp_rect
			(start -0.925 -0.47)
			(end 0.925 0.47)
			(stroke
				(width 0.05)
				(type default)
			)
			(fill no)
			(layer "F.CrtYd")
		)
		(fp_rect
			(start -0.5 -0.25)
			(end 0.5 0.25)
			(stroke
				(width 0.15)
				(type solid)
			)
			(fill no)
			(layer "F.Fab")
		)
		(fp_text user "Author: Antmicro"
			(at -0.95 4.169 90)
			(layer "F.Fab")
			(effects
				(font
					(size 0.7 0.7)
					(thickness 0.15)
				)
				(justify left bottom)
			)
		)
		(fp_text user "License: Apache-2.0"
			(at -0.95 5.169 90)
			(layer "F.Fab")
			(effects
				(font
					(size 0.7 0.7)
					(thickness 0.15)
				)
				(justify left bottom)
			)
		)
		(fp_text user "${REFERENCE}"
			(at -0.95 3.168 90)
			(layer "F.Fab")
			(effects
				(font
					(size 0.7 0.7)
					(thickness 0.15)
				)
				(justify left bottom)
			)
		)
		(pad "1" smd roundrect
			(at -0.48 0 90)
			(size 0.59 0.64)
			(layers "F.Cu" "F.Mask" "F.Paste")
			(roundrect_rratio 0.25)
			(net 38 "Net-(D36-A)")
			(pintype "passive")
		)
		(pad "2" smd roundrect
			(at 0.48 0 90)
			(size 0.59 0.64)
			(layers "F.Cu" "F.Mask" "F.Paste")
			(roundrect_rratio 0.25)
			(net 2 "+3V3")
			(pintype "passive")
		)
	)
	(footprint "antmicro-footprints:R_0402_1005Metric"
		(layer "F.Cu")
		(at 130.8 143.2 -90)
		(descr "Resistor SMD 0402")
		(tags "resistor SMD 0402")
		(property "Reference" "R348"
			(at 1 0.4 90)
			(layer "F.SilkS")
			(effects
				(font
					(size 0.7 0.7)
					(thickness 0.15)
				)
				(justify right top)
			)
		)
		(property "Value" "R_10k_0402"
			(at -1.011843 1.772046 90)
			(layer "F.Fab")
			(effects
				(font
					(size 0.7 0.7)
					(thickness 0.15)
				)
				(justify right top)
			)
		)
		(property "Datasheet" "https://www.bourns.com/docs/product-datasheets/cr.pdf"
			(at 0 0 90)
			(layer "F.Fab")
			(hide yes)
			(effects
				(font
					(size 1.27 1.27)
					(thickness 0.15)
				)
			)
		)
		(property "Description" "SMD Chip Resistor, 10 kohm, ± 1%, 62.5 mW, 0402 [1005 Metric], Thick Film, General Purpose"
			(at 0 0 90)
			(layer "F.Fab")
			(hide yes)
			(effects
				(font
					(size 1.27 1.27)
					(thickness 0.15)
				)
			)
		)
		(property "MPN" "CR0402-FX-1002GLF"
			(at 0 0 270)
			(unlocked yes)
			(layer "F.Fab")
			(hide yes)
			(effects
				(font
					(size 1 1)
					(thickness 0.15)
				)
			)
		)
		(property "Manufacturer" "Bourns"
			(at 0 0 270)
			(unlocked yes)
			(layer "F.Fab")
			(hide yes)
			(effects
				(font
					(size 1 1)
					(thickness 0.15)
				)
			)
		)
		(property "License" "Apache-2.0"
			(at 0 0 270)
			(unlocked yes)
			(layer "F.Fab")
			(hide yes)
			(effects
				(font
					(size 1 1)
					(thickness 0.15)
				)
			)
		)
		(property "Author" "Antmicro"
			(at 0 0 270)
			(unlocked yes)
			(layer "F.Fab")
			(hide yes)
			(effects
				(font
					(size 1 1)
					(thickness 0.15)
				)
			)
		)
		(property "Val" "10k"
			(at 0 0 270)
			(unlocked yes)
			(layer "F.Fab")
			(hide yes)
			(effects
				(font
					(size 1 1)
					(thickness 0.15)
				)
			)
		)
		(property "Tolerance" "1%"
			(at 0 0 270)
			(unlocked yes)
			(layer "F.Fab")
			(hide yes)
			(effects
				(font
					(size 1 1)
					(thickness 0.15)
				)
			)
		)
		(sheetname "/Expansion connector/")
		(sheetfile "expansion_connector.kicad_sch")
		(attr smd exclude_from_pos_files exclude_from_bom dnp)
		(fp_poly
			(pts
				(xy -0.925 -0.47) (xy 0.925 -0.47) (xy 0.925 0.47) (xy -0.925 0.47)
			)
			(stroke
				(width 0.05)
				(type default)
			)
			(fill no)
			(layer "F.CrtYd")
		)
		(fp_poly
			(pts
				(xy -0.5 -0.25) (xy 0.5 -0.25) (xy 0.5 0.25) (xy -0.5 0.25)
			)
			(stroke
				(width 0.15)
				(type solid)
			)
			(fill no)
			(layer "F.Fab")
		)
		(fp_text user "License: Apache-2.0"
			(at -0.949999 5.169 90)
			(layer "F.Fab")
			(effects
				(font
					(size 0.7 0.7)
					(thickness 0.15)
				)
				(justify right top)
			)
		)
		(fp_text user "${REFERENCE}"
			(at -0.95 3.168 90)
			(layer "F.Fab")
			(effects
				(font
					(size 0.7 0.7)
					(thickness 0.15)
				)
				(justify right top)
			)
		)
		(fp_text user "Author: Antmicro"
			(at -0.95 4.169 90)
			(layer "F.Fab")
			(effects
				(font
					(size 0.7 0.7)
					(thickness 0.15)
				)
				(justify right top)
			)
		)
		(pad "1" smd roundrect
			(at -0.48 0 270)
			(size 0.59 0.64)
			(layers "F.Cu" "F.Mask" "F.Paste")
			(roundrect_rratio 0.25)
			(net 472 "/Expansion connector/ADDR1")
			(pintype "passive")
		)
		(pad "2" smd roundrect
			(at 0.48 0 270)
			(size 0.59 0.64)
			(layers "F.Cu" "F.Mask" "F.Paste")
			(roundrect_rratio 0.25)
			(net 1 "GND")
			(pintype "passive")
		)
	)
	(footprint "antmicro-footprints:R_0402_1005Metric"
		(layer "F.Cu")
		(at 197.9 98.82 -90)
		(descr "Resistor SMD 0402")
		(tags "resistor SMD 0402")
		(property "Reference" "R387"
			(at -0.72 3.5 90)
			(layer "F.SilkS")
			(effects
				(font
					(size 0.7 0.7)
					(thickness 0.15)
				)
				(justify right top)
			)
		)
		(property "Value" "R_0R_0402"
			(at -1.011843 1.772047 90)
			(layer "F.Fab")
			(effects
				(font
					(size 0.7 0.7)
					(thickness 0.15)
				)
				(justify right top)
			)
		)
		(property "Datasheet" "https://industrial.panasonic.com/cdbs/www-data/pdf/RDA0000/AOA0000C301.pdf"
			(at 0 0 90)
			(layer "F.Fab")
			(hide yes)
			(effects
				(font
					(size 1.27 1.27)
					(thickness 0.15)
				)
			)
		)
		(property "Description" "SMD Chip Resistor, Jumper, 0 ohm, 100 mW, 0402 [1005 Metric], Thick Film, General Purpose"
			(at 0 0 90)
			(layer "F.Fab")
			(hide yes)
			(effects
				(font
					(size 1.27 1.27)
					(thickness 0.15)
				)
			)
		)
		(property "MPN" "ERJ2GE0R00X"
			(at 0 0 270)
			(unlocked yes)
			(layer "F.Fab")
			(hide yes)
			(effects
				(font
					(size 1 1)
					(thickness 0.15)
				)
			)
		)
		(property "Manufacturer" "Panasonic"
			(at 0 0 270)
			(unlocked yes)
			(layer "F.Fab")
			(hide yes)
			(effects
				(font
					(size 1 1)
					(thickness 0.15)
				)
			)
		)
		(property "License" "Apache-2.0"
			(at 0 0 270)
			(unlocked yes)
			(layer "F.Fab")
			(hide yes)
			(effects
				(font
					(size 1 1)
					(thickness 0.15)
				)
			)
		)
		(property "Author" "Antmicro"
			(at 0 0 270)
			(unlocked yes)
			(layer "F.Fab")
			(hide yes)
			(effects
				(font
					(size 1 1)
					(thickness 0.15)
				)
			)
		)
		(property "Val" "0R"
			(at 0 0 270)
			(unlocked yes)
			(layer "F.Fab")
			(hide yes)
			(effects
				(font
					(size 1 1)
					(thickness 0.15)
				)
			)
		)
		(property "Tolerance" "~"
			(at 0 0 270)
			(unlocked yes)
			(layer "F.Fab")
			(hide yes)
			(effects
				(font
					(size 1 1)
					(thickness 0.15)
				)
			)
		)
		(property "Current" "1A"
			(at 0 0 270)
			(unlocked yes)
			(layer "F.Fab")
			(hide yes)
			(effects
				(font
					(size 1 1)
					(thickness 0.15)
				)
			)
		)
		(sheetname "/USB Debug, PD/")
		(sheetfile "usb_debug_pd.kicad_sch")
		(attr smd exclude_from_pos_files exclude_from_bom dnp)
		(fp_rect
			(start -0.925 -0.47)
			(end 0.925 0.47)
			(stroke
				(width 0.05)
				(type default)
			)
			(fill no)
			(layer "F.CrtYd")
		)
		(fp_rect
			(start -0.5 -0.25)
			(end 0.5 0.25)
			(stroke
				(width 0.15)
				(type solid)
			)
			(fill no)
			(layer "F.Fab")
		)
		(fp_text user "Author: Antmicro"
			(at -0.95 4.169 90)
			(layer "F.Fab")
			(effects
				(font
					(size 0.7 0.7)
					(thickness 0.15)
				)
				(justify right top)
			)
		)
		(fp_text user "${REFERENCE}"
			(at -0.95 3.168 90)
			(layer "F.Fab")
			(effects
				(font
					(size 0.7 0.7)
					(thickness 0.15)
				)
				(justify right top)
			)
		)
		(fp_text user "License: Apache-2.0"
			(at -0.95 5.169 90)
			(layer "F.Fab")
			(effects
				(font
					(size 0.7 0.7)
					(thickness 0.15)
				)
				(justify right top)
			)
		)
		(pad "1" smd roundrect
			(at -0.48 0 270)
			(size 0.59 0.64)
			(layers "F.Cu" "F.Mask" "F.Paste")
			(roundrect_rratio 0.25)
			(net 810 "/USB Debug, PD/MISO")
			(pintype "passive")
		)
		(pad "2" smd roundrect
			(at 0.48 0 270)
			(size 0.59 0.64)
			(layers "F.Cu" "F.Mask" "F.Paste")
			(roundrect_rratio 0.25)
			(net 850 "/I2C_{SYS}.SDA")
			(pintype "passive")
		)
	)
	(footprint "antmicro-footprints:R_0603_1608Metric"
		(layer "F.Cu")
		(at 114.77 63.45 180)
		(descr "Resistor SMD 0603")
		(tags "resistor SMD 0603")
		(property "Reference" "R76"
			(at -1.06 -0.74 0)
			(layer "F.SilkS")
			(effects
				(font
					(size 0.7 0.7)
					(thickness 0.15)
				)
				(justify right top)
			)
		)
		(property "Value" "R_0R_22.4A_0603"
			(at 0 1.6 0)
			(layer "F.Fab")
			(effects
				(font
					(size 0.7 0.7)
					(thickness 0.15)
				)
				(justify right top)
			)
		)
		(property "Datasheet" "https://fscdn.rohm.com/en/products/databook/datasheet/passive/resistor/chip_resistor/pmr-jpw-e.pdf"
			(at 0 0 0)
			(layer "F.Fab")
			(hide yes)
			(effects
				(font
					(size 1.27 1.27)
					(thickness 0.15)
				)
			)
		)
		(property "Description" "SMD Chip Resistor"
			(at 0 0 0)
			(layer "F.Fab")
			(hide yes)
			(effects
				(font
					(size 1.27 1.27)
					(thickness 0.15)
				)
			)
		)
		(property "Manufacturer" "ROHM Semiconductor"
			(at 0 0 180)
			(unlocked yes)
			(layer "F.Fab")
			(hide yes)
			(effects
				(font
					(size 1 1)
					(thickness 0.15)
				)
			)
		)
		(property "MPN" "PMR03EZPJ000"
			(at 0 0 180)
			(unlocked yes)
			(layer "F.Fab")
			(hide yes)
			(effects
				(font
					(size 1 1)
					(thickness 0.15)
				)
			)
		)
		(property "Val" "0R"
			(at 0 0 180)
			(unlocked yes)
			(layer "F.Fab")
			(hide yes)
			(effects
				(font
					(size 1 1)
					(thickness 0.15)
				)
			)
		)
		(property "Author" "Antmicro"
			(at 0 0 180)
			(unlocked yes)
			(layer "F.Fab")
			(hide yes)
			(effects
				(font
					(size 1 1)
					(thickness 0.15)
				)
			)
		)
		(property "License" "Apache-2.0"
			(at 0 0 180)
			(unlocked yes)
			(layer "F.Fab")
			(hide yes)
			(effects
				(font
					(size 1 1)
					(thickness 0.15)
				)
			)
		)
		(property "Max. Curr." "22.4A"
			(at 0 0 180)
			(unlocked yes)
			(layer "F.Fab")
			(hide yes)
			(effects
				(font
					(size 1 1)
					(thickness 0.15)
				)
			)
		)
		(property "Tolerance" "template_tolerance"
			(at 0 0 180)
			(unlocked yes)
			(layer "F.Fab")
			(hide yes)
			(effects
				(font
					(size 1 1)
					(thickness 0.15)
				)
			)
		)
		(sheetname "/SoM_Power/")
		(sheetfile "som_power.kicad_sch")
		(attr smd)
		(fp_line
			(start -0.15 0.4)
			(end 0.15 0.4)
			(stroke
				(width 0.15)
				(type solid)
			)
			(layer "F.SilkS")
		)
		(fp_line
			(start -0.15 -0.4)
			(end 0.15 -0.4)
			(stroke
				(width 0.15)
				(type solid)
			)
			(layer "F.SilkS")
		)
		(fp_poly
			(pts
				(xy -1.25 -0.65) (xy 1.25 -0.65) (xy 1.25 0.65) (xy -1.25 0.65)
			)
			(stroke
				(width 0.05)
				(type solid)
			)
			(fill no)
			(layer "F.CrtYd")
		)
		(fp_poly
			(pts
				(xy -0.8 -0.4) (xy 0.8 -0.4) (xy 0.8 0.4) (xy -0.8 0.4)
			)
			(stroke
				(width 0.15)
				(type solid)
			)
			(fill no)
			(layer "F.Fab")
		)
		(fp_text user "License: Apache-2.0"
			(at -1.249999 5.9 0)
			(layer "F.Fab")
			(effects
				(font
					(size 0.7 0.7)
					(thickness 0.15)
				)
				(justify right top)
			)
		)
		(fp_text user "${REFERENCE}"
			(at -1.25 3.898 0)
			(layer "F.Fab")
			(effects
				(font
					(size 0.7 0.7)
					(thickness 0.15)
				)
				(justify right top)
			)
		)
		(fp_text user "Author: Antmicro"
			(at -1.25 4.9 0)
			(layer "F.Fab")
			(effects
				(font
					(size 0.7 0.7)
					(thickness 0.15)
				)
				(justify right top)
			)
		)
		(pad "1" smd roundrect
			(at -0.7 0 180)
			(size 0.8 1)
			(layers "F.Cu" "F.Mask" "F.Paste")
			(roundrect_rratio 0.2)
			(net 1096 "Net-(Q9-D)")
			(pintype "passive")
		)
		(pad "2" smd roundrect
			(at 0.7 0 180)
			(size 0.8 1)
			(layers "F.Cu" "F.Mask" "F.Paste")
			(roundrect_rratio 0.2)
			(net 213 "+5V_SOM")
			(pintype "passive")
		)
	)
	(footprint "antmicro-footprints:C_0402_1005Metric"
		(layer "F.Cu")
		(at 206 77.9 180)
		(descr "Capacitor SMD 0402")
		(tags "capacitor SMD 0402")
		(property "Reference" "C121"
			(at -3.730532 0.36 0)
			(layer "F.SilkS")
			(effects
				(font
					(size 0.7 0.7)
					(thickness 0.15)
				)
				(justify right top)
			)
		)
		(property "Value" "C_10u_0402"
			(at -1.022927 2.155213 0)
			(layer "F.Fab")
			(effects
				(font
					(size 0.7 0.7)
					(thickness 0.15)
				)
				(justify right top)
			)
		)
		(property "Datasheet" "https://www.yageo.com/en/Chart/Download/pdf/CC0402MRX5R5BB106"
			(at 0 0 0)
			(layer "F.Fab")
			(hide yes)
			(effects
				(font
					(size 1.27 1.27)
					(thickness 0.15)
				)
			)
		)
		(property "Description" "SMD Multilayer Ceramic Capacitor, 10 µF, 6.3 V, 0402 [1005 Metric], ± 20%, X5R, CC Series"
			(at 0 0 0)
			(layer "F.Fab")
			(hide yes)
			(effects
				(font
					(size 1.27 1.27)
					(thickness 0.15)
				)
			)
		)
		(property "MPN" "CC0402MRX5R5BB106"
			(at 0 0 180)
			(unlocked yes)
			(layer "F.Fab")
			(hide yes)
			(effects
				(font
					(size 1 1)
					(thickness 0.15)
				)
			)
		)
		(property "Manufacturer" "YAGEO"
			(at 0 0 180)
			(unlocked yes)
			(layer "F.Fab")
			(hide yes)
			(effects
				(font
					(size 1 1)
					(thickness 0.15)
				)
			)
		)
		(property "License" "Apache-2.0"
			(at 0 0 180)
			(unlocked yes)
			(layer "F.Fab")
			(hide yes)
			(effects
				(font
					(size 1 1)
					(thickness 0.15)
				)
			)
		)
		(property "Author" "Antmicro"
			(at 0 0 180)
			(unlocked yes)
			(layer "F.Fab")
			(hide yes)
			(effects
				(font
					(size 1 1)
					(thickness 0.15)
				)
			)
		)
		(property "Val" "10u"
			(at 0 0 180)
			(unlocked yes)
			(layer "F.Fab")
			(hide yes)
			(effects
				(font
					(size 1 1)
					(thickness 0.15)
				)
			)
		)
		(property "Voltage" ""
			(at 0 0 180)
			(unlocked yes)
			(layer "F.Fab")
			(hide yes)
			(effects
				(font
					(size 1 1)
					(thickness 0.15)
				)
			)
		)
		(property "Dielectric" ""
			(at 0 0 180)
			(unlocked yes)
			(layer "F.Fab")
			(hide yes)
			(effects
				(font
					(size 1 1)
					(thickness 0.15)
				)
			)
		)
		(sheetname "/USB Debug, PD/")
		(sheetfile "usb_debug_pd.kicad_sch")
		(attr smd)
		(fp_rect
			(start -0.925 -0.47)
			(end 0.925 0.47)
			(stroke
				(width 0.05)
				(type default)
			)
			(fill no)
			(layer "F.CrtYd")
		)
		(fp_line
			(start 0.504 0.248)
			(end -0.494 0.248)
			(stroke
				(width 0.15)
				(type solid)
			)
			(layer "F.Fab")
		)
		(fp_line
			(start 0.504 -0.25)
			(end 0.504 0.248)
			(stroke
				(width 0.15)
				(type solid)
			)
			(layer "F.Fab")
		)
		(fp_line
			(start -0.494 0.248)
			(end -0.494 -0.25)
			(stroke
				(width 0.15)
				(type solid)
			)
			(layer "F.Fab")
		)
		(fp_line
			(start -0.494 -0.25)
			(end 0.504 -0.25)
			(stroke
				(width 0.15)
				(type solid)
			)
			(layer "F.Fab")
		)
		(fp_text user "${REFERENCE}"
			(at -0.939 4.599 0)
			(layer "F.Fab")
			(effects
				(font
					(size 0.7 0.7)
					(thickness 0.15)
				)
				(justify right top)
			)
		)
		(fp_text user "Author: Antmicro"
			(at -0.939 3.399 0)
			(layer "F.Fab")
			(effects
				(font
					(size 0.7 0.7)
					(thickness 0.15)
				)
				(justify right top)
			)
		)
		(fp_text user "License: Apache-2.0"
			(at -0.939 5.799 0)
			(layer "F.Fab")
			(effects
				(font
					(size 0.7 0.7)
					(thickness 0.15)
				)
				(justify right top)
			)
		)
		(pad "1" smd roundrect
			(at -0.48 0 180)
			(size 0.59 0.64)
			(layers "F.Cu" "F.Mask" "F.Paste")
			(roundrect_rratio 0.25)
			(net 1 "GND")
			(pintype "passive")
		)
		(pad "2" smd roundrect
			(at 0.48 0 180)
			(size 0.59 0.64)
			(layers "F.Cu" "F.Mask" "F.Paste")
			(roundrect_rratio 0.25)
			(net 294 "/USB Debug, PD/PDC_LDO_3V3")
			(pintype "passive")
		)
	)
	(footprint "antmicro-footprints:Spacer_Drill4.45mm_H4mm_9774040960R"
		(locked yes)
		(layer "F.Cu")
		(at 76.930532 149.71 90)
		(property "Reference" "H5"
			(at -3.48 -3.6 90)
			(layer "F.SilkS")
			(effects
				(font
					(size 0.7 0.7)
					(thickness 0.15)
				)
				(justify left bottom)
			)
		)
		(property "Value" "Spacer_Drill4.45mm_H4mm_9774040960R"
			(at -3.95 5.05 90)
			(layer "F.Fab")
			(effects
				(font
					(size 0.7 0.7)
					(thickness 0.15)
				)
				(justify left bottom)
			)
		)
		(property "Datasheet" "https://www.we-online.com/components/products/datasheet/9774040960R.pdf"
			(at 0 0 90)
			(layer "F.Fab")
			(effects
				(font
					(size 0.7 0.7)
					(thickness 0.15)
				)
				(justify left bottom)
			)
		)
		(property "Description" "Spacer, SMT, Non Stop, Steel, Swage Round, 6 mm x 4 mm, 3.3 mm Internal, WA-SMST Series"
			(at 0 0 90)
			(layer "F.Fab")
			(effects
				(font
					(size 0.7 0.7)
					(thickness 0.15)
				)
				(justify left bottom)
			)
		)
		(property "Manufacturer" "Würth Elektronik"
			(at 0 0 90)
			(unlocked yes)
			(layer "F.Fab")
			(hide yes)
			(effects
				(font
					(size 1 1)
					(thickness 0.15)
				)
			)
		)
		(property "MPN" "9774040960R"
			(at 0 0 90)
			(unlocked yes)
			(layer "F.Fab")
			(hide yes)
			(effects
				(font
					(size 1 1)
					(thickness 0.15)
				)
			)
		)
		(property "Author" "Antmicro"
			(at 0 0 90)
			(unlocked yes)
			(layer "F.Fab")
			(hide yes)
			(effects
				(font
					(size 1 1)
					(thickness 0.15)
				)
			)
		)
		(property "License" "Apache-2.0"
			(at 0 0 90)
			(unlocked yes)
			(layer "F.Fab")
			(hide yes)
			(effects
				(font
					(size 1 1)
					(thickness 0.15)
				)
			)
		)
		(sheetname "/SoM_Power/")
		(sheetfile "som_power.kicad_sch")
		(attr smd)
		(fp_rect
			(start -3.95 -3.95)
			(end 3.95 3.95)
			(stroke
				(width 0.05)
				(type solid)
			)
			(fill no)
			(layer "F.CrtYd")
		)
		(fp_circle
			(center 0 0)
			(end 3.25 0)
			(stroke
				(width 0.05)
				(type solid)
			)
			(fill no)
			(layer "F.CrtYd")
		)
		(fp_circle
			(center 0 0)
			(end 2.564 0)
			(stroke
				(width 0.15)
				(type solid)
			)
			(fill no)
			(layer "F.Fab")
		)
		(fp_text user "License: Apache-2.0"
			(at -3.95 6.25 90)
			(layer "F.Fab")
			(effects
				(font
					(size 0.7 0.7)
					(thickness 0.15)
				)
				(justify left bottom)
			)
		)
		(fp_text user "${REFERENCE}"
			(at -3.95 7.45 90)
			(layer "F.Fab")
			(effects
				(font
					(size 0.7 0.7)
					(thickness 0.15)
				)
				(justify left bottom)
			)
		)
		(fp_text user "Author: Antmicro"
			(at -3.95 8.65 90)
			(layer "F.Fab")
			(effects
				(font
					(size 0.7 0.7)
					(thickness 0.15)
				)
				(justify left bottom)
			)
		)
		(pad "" smd custom
			(at -2.55 -0.55 212.5)
			(size 0.1 0.1)
			(layers "F.Paste")
			(options
				(clearance outline)
				(anchor circle)
			)
			(primitives
				(gr_arc
					(start 0 0)
					(mid 0.704278 1.28373)
					(end 0.608513 2.744826)
					(width 0.7)
				)
			)
		)
		(pad "" smd custom
			(at -0.55 2.55 302.5)
			(size 0.1 0.1)
			(layers "F.Paste")
			(options
				(clearance outline)
				(anchor circle)
			)
			(primitives
				(gr_arc
					(start 0 0)
					(mid 0.704278 1.28373)
					(end 0.608513 2.744826)
					(width 0.7)
				)
			)
		)
		(pad "" smd custom
			(at 0.55 -2.55 122.5)
			(size 0.1 0.1)
			(layers "F.Paste")
			(options
				(clearance outline)
				(anchor circle)
			)
			(primitives
				(gr_arc
					(start 0 0)
					(mid 0.704278 1.28373)
					(end 0.608513 2.744826)
					(width 0.7)
				)
			)
		)
		(pad "" smd custom
			(at 2.55 0.55 32.5)
			(size 0.1 0.1)
			(layers "F.Paste")
			(options
				(clearance outline)
				(anchor circle)
			)
			(primitives
				(gr_arc
					(start 0 0)
					(mid 0.704278 1.28373)
					(end 0.608513 2.744826)
					(width 0.7)
				)
			)
		)
		(pad "1" thru_hole circle
			(at 0 0 90)
			(size 7.4 7.4)
			(drill 4.45)
			(layers "*.Cu" "*.Mask")
			(remove_unused_layers no)
			(net 1 "GND")
			(pintype "passive")
		)
	)
	(footprint "antmicro-footprints:Conn_Hermaphroditic_Molex_203456-0003_mirrored"
		(locked yes)
		(layer "F.Cu")
		(at 116.530532 78.15)
		(descr "Mirrored version of: https://www.molex.com/content/dam/molex/molex-dot-com/products/automated/en-us/salesdrawingpdf/203/203456/2034560003_sd.pdf")
		(property "Reference" "J1"
			(at -32.25 -11.2 180)
			(layer "F.SilkS")
			(effects
				(font
					(size 0.7 0.7)
					(thickness 0.15)
				)
				(justify right top)
			)
		)
		(property "Value" "Hermaphroditic_Molex_203456-0003_CUSTOM_Jetson_AGX_Thor_H8mm"
			(at 0.1 12.9 0)
			(layer "F.Fab")
			(effects
				(font
					(size 0.7 0.7)
					(thickness 0.15)
				)
				(justify right top)
			)
		)
		(property "Datasheet" "https://www.molex.com/content/dam/molex/molex-dot-com/products/automated/en-us/salesdrawingpdf/203/203456/2034560003_sd.pdf?inline"
			(at 0.1 0.2 0)
			(layer "F.Fab")
			(hide yes)
			(effects
				(font
					(size 0.7 0.7)
					(thickness 0.15)
				)
				(justify right top)
			)
		)
		(property "Description" "Mirror Mezz Hermaphroditic Connector, 5.50mm Connector Height, BGA-Attach Mounting, 7 Pair, 11 Row, 699 Circuits, 0.76µm Gold Plating, without Pegs"
			(at 0.1 0.2 0)
			(layer "F.Fab")
			(hide yes)
			(effects
				(font
					(size 0.7 0.7)
					(thickness 0.15)
				)
				(justify right top)
			)
		)
		(property "MPN" "203456-0003"
			(at 0 0 0)
			(unlocked yes)
			(layer "F.Fab")
			(hide yes)
			(effects
				(font
					(size 1 1)
					(thickness 0.15)
				)
			)
		)
		(property "Manufacturer" "Molex"
			(at 0 0 0)
			(unlocked yes)
			(layer "F.Fab")
			(hide yes)
			(effects
				(font
					(size 1 1)
					(thickness 0.15)
				)
			)
		)
		(property "Author" "Antmicro"
			(at 0 0 0)
			(unlocked yes)
			(layer "F.Fab")
			(hide yes)
			(effects
				(font
					(size 1 1)
					(thickness 0.15)
				)
			)
		)
		(property "License" "Apache-2.0"
			(at 0 0 0)
			(unlocked yes)
			(layer "F.Fab")
			(hide yes)
			(effects
				(font
					(size 1 1)
					(thickness 0.15)
				)
			)
		)
		(sheetname "/SoM_IO/")
		(sheetfile "som_io.kicad_sch")
		(solder_mask_margin 0.05)
		(attr smd)
		(fp_line
			(start -32.25 -11.2)
			(end -32.25 -0.87)
			(stroke
				(width 0.15)
				(type default)
			)
			(layer "F.SilkS")
		)
		(fp_line
			(start -32.25 -0.87)
			(end -32.03 -0.87)
			(stroke
				(width 0.15)
				(type default)
			)
			(layer "F.SilkS")
		)
		(fp_line
			(start -32.25 0.47)
			(end -32.25 10.8)
			(stroke
				(width 0.15)
				(type default)
			)
			(layer "F.SilkS")
		)
		(fp_line
			(start -32.25 0.47)
			(end -32.03 0.47)
			(stroke
				(width 0.15)
				(type default)
			)
			(layer "F.SilkS")
		)
		(fp_line
			(start -32.25 10.8)
			(end 32.45 10.8)
			(stroke
				(width 0.15)
				(type solid)
			)
			(layer "F.SilkS")
		)
		(fp_line
			(start -32.03 0.47)
			(end -32.03 -0.87)
			(stroke
				(width 0.15)
				(type default)
			)
			(layer "F.SilkS")
		)
		(fp_line
			(start 32.23 -0.87)
			(end 32.45 -0.87)
			(stroke
				(width 0.15)
				(type default)
			)
			(layer "F.SilkS")
		)
		(fp_line
			(start 32.23 0.47)
			(end 32.23 -0.87)
			(stroke
				(width 0.15)
				(type default)
			)
			(layer "F.SilkS")
		)
		(fp_line
			(start 32.45 -11.2)
			(end -32.25 -11.2)
			(stroke
				(width 0.15)
				(type solid)
			)
			(layer "F.SilkS")
		)
		(fp_line
			(start 32.45 -0.87)
			(end 32.45 -11.2)
			(stroke
				(width 0.15)
				(type default)
			)
			(layer "F.SilkS")
		)
		(fp_line
			(start 32.45 0.47)
			(end 32.23 0.47)
			(stroke
				(width 0.15)
				(type default)
			)
			(layer "F.SilkS")
		)
		(fp_line
			(start 32.45 10.8)
			(end 32.45 0.47)
			(stroke
				(width 0.15)
				(type default)
			)
			(layer "F.SilkS")
		)
		(fp_circle
			(center -28.9 11.3)
			(end -28.85 11.3)
			(stroke
				(width 0.15)
				(type solid)
			)
			(fill no)
			(layer "F.SilkS")
		)
		(fp_rect
			(start -33.25 -12.2)
			(end 33.45 11.8)
			(stroke
				(width 0.05)
				(type solid)
			)
			(fill no)
			(layer "F.CrtYd")
		)
		(fp_line
			(start -32.25 -11.2)
			(end 32.45 -11.2)
			(stroke
				(width 0.15)
				(type solid)
			)
			(layer "F.Fab")
		)
		(fp_line
			(start -32.25 10.8)
			(end -32.25 -11.2)
			(stroke
				(width 0.15)
				(type solid)
			)
			(layer "F.Fab")
		)
		(fp_line
			(start 32.45 -11.2)
			(end 32.45 10.8)
			(stroke
				(width 0.15)
				(type solid)
			)
			(layer "F.Fab")
		)
		(fp_line
			(start 32.45 10.8)
			(end -32.25 10.8)
			(stroke
				(width 0.15)
				(type solid)
			)
			(layer "F.Fab")
		)
		(fp_text user "License: Apache-2.0"
			(at -33.25 16.2 0)
			(layer "F.Fab")
			(effects
				(font
					(size 0.7 0.7)
					(thickness 0.15)
				)
				(justify left bottom)
			)
		)
		(fp_text user "${REFERENCE}"
			(at -33.25 13.8 0)
			(layer "F.Fab")
			(effects
				(font
					(size 0.7 0.7)
					(thickness 0.15)
				)
				(justify left bottom)
			)
		)
		(fp_text user "Author: Antmicro"
			(at -33.25 15 0)
			(layer "F.Fab")
			(effects
				(font
					(size 0.7 0.7)
					(thickness 0.15)
				)
				(justify left bottom)
			)
		)
		(pad "A3" smd circle
			(at -28.4 7.5 90)
			(size 0.5 0.5)
			(layers "F.Cu" "F.Mask" "F.Paste")
			(net 683 "/SoM_Power/~{SOM_PRSNT}")
			(pinfunction "PRSNT0")
			(pintype "passive")
		)
		(pad "A4" smd circle
			(at -27.5 7.5 90)
			(size 0.5 0.5)
			(layers "F.Cu" "F.Mask" "F.Paste")
			(net 873 "unconnected-(J1I-FSI_GPIO32-PadA4)")
			(pinfunction "FSI_GPIO32")
			(pintype "bidirectional+no_connect")
		)
		(pad "A5" smd circle
			(at -26.6 7.5 90)
			(size 0.5 0.5)
			(layers "F.Cu" "F.Mask" "F.Paste")
			(net 877 "unconnected-(J1I-FSI_GPIO34-PadA5)")
			(pinfunction "FSI_GPIO34")
			(pintype "bidirectional+no_connect")
		)
		(pad "A6" smd circle
			(at -25.7 7.5 90)
			(size 0.5 0.5)
			(layers "F.Cu" "F.Mask" "F.Paste")
			(net 563 "Net-(J1A-UFS0_REF_CLK)")
			(pinfunction "UFS0_REF_CLK")
			(pintype "passive")
		)
		(pad "A7" smd circle
			(at -24.8 7.5 90)
			(size 0.5 0.5)
			(layers "F.Cu" "F.Mask" "F.Paste")
			(net 759 "unconnected-(J1H-GPIO29-PadA7)")
			(pinfunction "GPIO29")
			(pintype "bidirectional+no_connect")
		)
		(pad "A8" smd circle
			(at -23.9 7.5 90)
			(size 0.5 0.5)
			(layers "F.Cu" "F.Mask" "F.Paste")
			(net 104 "/M.2/~{PEWAKE}")
			(pinfunction "PEX_WAKE_N")
			(pintype "input")
		)
		(pad "A9" smd circle
			(at -23 7.5 90)
			(size 0.5 0.5)
			(layers "F.Cu" "F.Mask" "F.Paste")
			(net 1 "GND")
			(pinfunction "GND")
			(pintype "passive")
		)
		(pad "A10" smd circle
			(at -22.1 7.5 90)
			(size 0.5 0.5)
			(layers "F.Cu" "F.Mask" "F.Paste")
			(net 492 "/SoM_IO2/USB2.D+")
			(pinfunction "USB2_P")
			(pintype "bidirectional")
		)
		(pad "A11" smd circle
			(at -21.2 7.5 90)
			(size 0.5 0.5)
			(layers "F.Cu" "F.Mask" "F.Paste")
			(net 493 "/SoM_IO2/USB2.D-")
			(pinfunction "USB2_N")
			(pintype "bidirectional")
		)
		(pad "A12" smd circle
			(at -20.3 7.5 90)
			(size 0.5 0.5)
			(layers "F.Cu" "F.Mask" "F.Paste")
			(net 1 "GND")
			(pinfunction "GND")
			(pintype "passive")
		)
		(pad "A13" smd circle
			(at -19 7.5 90)
			(size 0.5 0.5)
			(layers "F.Cu" "F.Mask" "F.Paste")
			(net 1 "GND")
			(pinfunction "GND")
			(pintype "passive")
		)
		(pad "A14" smd circle
			(at -18.1 7.5 90)
			(size 0.5 0.5)
			(layers "F.Cu" "F.Mask" "F.Paste")
			(net 1258 "/SoM_IO2/DP2.TX0_C-")
			(pinfunction "DP2_D0_HDMI_D2_N")
			(pintype "output")
		)
		(pad "A15" smd circle
			(at -17.2 7.5 90)
			(size 0.5 0.5)
			(layers "F.Cu" "F.Mask" "F.Paste")
			(net 1254 "/SoM_IO2/DP2.TX0_C+")
			(pinfunction "DP2_D0_HDMI_D2_P")
			(pintype "output")
		)
		(pad "A16" smd circle
			(at -16.3 7.5 90)
			(size 0.5 0.5)
			(layers "F.Cu" "F.Mask" "F.Paste")
			(net 1 "GND")
			(pinfunction "GND")
			(pintype "passive")
		)
		(pad "A17" smd circle
			(at -15 7.5 90)
			(size 0.5 0.5)
			(layers "F.Cu" "F.Mask" "F.Paste")
			(net 1 "GND")
			(pinfunction "GND")
			(pintype "passive")
		)
		(pad "A18" smd circle
			(at -14.1 7.5 90)
			(size 0.5 0.5)
			(layers "F.Cu" "F.Mask" "F.Paste")
			(net 625 "/SoM_IO/SFP_LEDY_1V8")
			(pinfunction "GPIO34")
			(pintype "passive")
		)
		(pad "A19" smd circle
			(at -13.2 7.5 90)
			(size 0.5 0.5)
			(layers "F.Cu" "F.Mask" "F.Paste")
			(net 789 "/Expansion connector/DP2.HPD")
			(pinfunction "HPD2")
			(pintype "bidirectional")
		)
		(pad "A20" smd circle
			(at -12.3 7.5 90)
			(size 0.5 0.5)
			(layers "F.Cu" "F.Mask" "F.Paste")
			(net 1 "GND")
			(pinfunction "GND")
			(pintype "passive")
		)
		(pad "A21" smd circle
			(at -11 7.5 90)
			(size 0.5 0.5)
			(layers "F.Cu" "F.Mask" "F.Paste")
			(net 1 "GND")
			(pinfunction "GND")
			(pintype "passive")
		)
		(pad "A22" smd circle
			(at -10.1 7.5 90)
			(size 0.5 0.5)
			(layers "F.Cu" "F.Mask" "F.Paste")
			(net 299 "/SoM_IO2/USBSS1.RX+")
			(pinfunction "UPHY_RX1_P")
			(pintype "input")
		)
		(pad "A23" smd circle
			(at -9.2 7.5 90)
			(size 0.5 0.5)
			(layers "F.Cu" "F.Mask" "F.Paste")
			(net 324 "/SoM_IO2/USBSS1.RX-")
			(pinfunction "UPHY_RX1_N")
			(pintype "input")
		)
		(pad "A24" smd circle
			(at -8.3 7.5 90)
			(size 0.5 0.5)
			(layers "F.Cu" "F.Mask" "F.Paste")
			(net 1 "GND")
			(pinfunction "GND")
			(pintype "passive")
		)
		(pad "A25" smd circle
			(at -7 7.5 90)
			(size 0.5 0.5)
			(layers "F.Cu" "F.Mask" "F.Paste")
			(net 1 "GND")
			(pinfunction "GND")
			(pintype "passive")
		)
		(pad "A26" smd circle
			(at -6.1 7.5 90)
			(size 0.5 0.5)
			(layers "F.Cu" "F.Mask" "F.Paste")
			(net 681 "/M.2/PCIe_{C5x4}.RX3+")
			(pinfunction "UPHY_RX11_P")
			(pintype "input")
		)
		(pad "A27" smd circle
			(at -5.2 7.5 90)
			(size 0.5 0.5)
			(layers "F.Cu" "F.Mask" "F.Paste")
			(net 564 "/M.2/PCIe_{C5x4}.RX3-")
			(pinfunction "UPHY_RX11_N")
			(pintype "input")
		)
		(pad "A28" smd circle
			(at -4.3 7.5 90)
			(size 0.5 0.5)
			(layers "F.Cu" "F.Mask" "F.Paste")
			(net 1 "GND")
			(pinfunction "GND")
			(pintype "passive")
		)
		(pad "A29" smd circle
			(at -3 7.5 90)
			(size 0.5 0.5)
			(layers "F.Cu" "F.Mask" "F.Paste")
			(net 1 "GND")
			(pinfunction "GND")
			(pintype "passive")
		)
		(pad "A30" smd circle
			(at -2.1 7.5 90)
			(size 0.5 0.5)
			(layers "F.Cu" "F.Mask" "F.Paste")
			(net 772 "unconnected-(J1B-UPHY_RX15_P-PadA30)")
			(pinfunction "UPHY_RX15_P")
			(pintype "input+no_connect")
		)
		(pad "A31" smd circle
			(at -1.2 7.5 90)
			(size 0.5 0.5)
			(layers "F.Cu" "F.Mask" "F.Paste")
			(net 695 "unconnected-(J1B-UPHY_RX15_N-PadA31)")
			(pinfunction "UPHY_RX15_N")
			(pintype "input+no_connect")
		)
		(pad "A32" smd circle
			(at -0.3 7.5 90)
			(size 0.5 0.5)
			(layers "F.Cu" "F.Mask" "F.Paste")
			(net 1 "GND")
			(pinfunction "GND")
			(pintype "passive")
		)
		(pad "A33" smd circle
			(at 1 7.5 90)
			(size 0.5 0.5)
			(layers "F.Cu" "F.Mask" "F.Paste")
			(net 1 "GND")
			(pinfunction "GND")
			(pintype "passive")
		)
		(pad "A34" smd circle
			(at 1.9 7.5 90)
			(size 0.5 0.5)
			(layers "F.Cu" "F.Mask" "F.Paste")
			(net 1266 "/SoM_IO2/DP3.TX2_C+")
			(pinfunction "DP3_D2_HDMI_D0_P")
			(pintype "output")
		)
		(pad "A35" smd circle
			(at 2.8 7.5 90)
			(size 0.5 0.5)
			(layers "F.Cu" "F.Mask" "F.Paste")
			(net 1270 "/SoM_IO2/DP3.TX2_C-")
			(pinfunction "DP3_D2_HDMI_D0_N")
			(pintype "output")
		)
		(pad "A36" smd circle
			(at 3.7 7.5 90)
			(size 0.5 0.5)
			(layers "F.Cu" "F.Mask" "F.Paste")
			(net 1 "GND")
			(pinfunction "GND")
			(pintype "passive")
		)
		(pad "A37" smd circle
			(at 5 7.5 90)
			(size 0.5 0.5)
			(layers "F.Cu" "F.Mask" "F.Paste")
			(net 1 "GND")
			(pinfunction "GND")
			(pintype "passive")
		)
		(pad "A38" smd circle
			(at 5.9 7.5 90)
			(size 0.5 0.5)
			(layers "F.Cu" "F.Mask" "F.Paste")
			(net 1289 "unconnected-(J1K-GPIO43-PadA38)")
			(pinfunction "GPIO43")
			(pintype "passive+no_connect")
		)
		(pad "A39" smd circle
			(at 6.8 7.5 90)
			(size 0.5 0.5)
			(layers "F.Cu" "F.Mask" "F.Paste")
			(net 1291 "unconnected-(J1K-GPIO37-PadA39)")
			(pinfunction "GPIO37")
			(pintype "passive+no_connect")
		)
		(pad "A40" smd circle
			(at 7.7 7.5 90)
			(size 0.5 0.5)
			(layers "F.Cu" "F.Mask" "F.Paste")
			(net 1 "GND")
			(pinfunction "GND")
			(pintype "passive")
		)
		(pad "A41" smd circle
			(at 8.6 7.5 90)
			(size 0.5 0.5)
			(layers "F.Cu" "F.Mask" "F.Paste")
			(net 88 "/CSI/CAM0.CSI2_D0+")
			(pinfunction "CSI2_D0_P")
			(pintype "input")
		)
		(pad "A42" smd circle
			(at 9.5 7.5 90)
			(size 0.5 0.5)
			(layers "F.Cu" "F.Mask" "F.Paste")
			(net 64 "/CSI/CAM0.CSI2_D0-")
			(pinfunction "CSI2_D0_N")
			(pintype "input")
		)
		(pad "A43" smd circle
			(at 10.4 7.5 90)
			(size 0.5 0.5)
			(layers "F.Cu" "F.Mask" "F.Paste")
			(net 1 "GND")
			(pinfunction "GND")
			(pintype "passive")
		)
		(pad "A44" smd circle
			(at 11.3 7.5 90)
			(size 0.5 0.5)
			(layers "F.Cu" "F.Mask" "F.Paste")
			(net 124 "/CSI/CAM3.CSI7_D0+")
			(pinfunction "CSI7_D0_P")
			(pintype "input")
		)
		(pad "A45" smd circle
			(at 12.2 7.5 90)
			(size 0.5 0.5)
			(layers "F.Cu" "F.Mask" "F.Paste")
			(net 59 "/CSI/CAM3.CSI7_D0-")
			(pinfunction "CSI7_D0_N")
			(pintype "input")
		)
		(pad "A46" smd circle
			(at 13.1 7.5 90)
			(size 0.5 0.5)
			(layers "F.Cu" "F.Mask" "F.Paste")
			(net 1 "GND")
			(pinfunction "GND")
			(pintype "passive")
		)
		(pad "A47" smd circle
			(at 14 7.5 90)
			(size 0.5 0.5)
			(layers "F.Cu" "F.Mask" "F.Paste")
			(net 641 "unconnected-(J1D-I2C10_CLK-PadA47)")
			(pinfunction "I2C10_CLK")
			(pintype "bidirectional+no_connect")
		)
		(pad "A48" smd circle
			(at 14.9 7.5 90)
			(size 0.5 0.5)
			(layers "F.Cu" "F.Mask" "F.Paste")
			(net 671 "unconnected-(J1D-I2C10_DAT-PadA48)")
			(pinfunction "I2C10_DAT")
			(pintype "bidirectional+no_connect")
		)
		(pad "A49" smd circle
			(at 15.8 7.5 90)
			(size 0.5 0.5)
			(layers "F.Cu" "F.Mask" "F.Paste")
			(net 1 "GND")
			(pinfunction "GND")
			(pintype "passive")
		)
		(pad "A50" smd circle
			(at 16.7 7.5 90)
			(size 0.5 0.5)
			(layers "F.Cu" "F.Mask" "F.Paste")
			(net 617 "/SoM_IO2/DP0.TX2_C-")
			(pinfunction "DP0_D2_HDMI_D0_N")
			(pintype "output")
		)
		(pad "A51" smd circle
			(at 17.6 7.5 90)
			(size 0.5 0.5)
			(layers "F.Cu" "F.Mask" "F.Paste")
			(net 615 "/SoM_IO2/DP0.TX2_C+")
			(pinfunction "DP0_D2_HDMI_D0_P")
			(pintype "output")
		)
		(pad "A52" smd circle
			(at 18.5 7.5 90)
			(size 0.5 0.5)
			(layers "F.Cu" "F.Mask" "F.Paste")
			(net 1 "GND")
			(pinfunction "GND")
			(pintype "passive")
		)
		(pad "A53" smd circle
			(at 19.4 7.5 90)
			(size 0.5 0.5)
			(layers "F.Cu" "F.Mask" "F.Paste")
			(net 133 "/SoM_IO/I2C5_SCL_1V8")
			(pinfunction "I2C5_CLK")
			(pintype "bidirectional")
		)
		(pad "A54" smd circle
			(at 20.3 7.5 90)
			(size 0.5 0.5)
			(layers "F.Cu" "F.Mask" "F.Paste")
			(net 131 "/CSI/CAM_CTRL.VSYNC_CAM1")
			(pinfunction "GPIO46")
			(pintype "passive")
		)
		(pad "A55" smd circle
			(at 21.2 7.5 90)
			(size 0.5 0.5)
			(layers "F.Cu" "F.Mask" "F.Paste")
			(net 626 "unconnected-(J1D-I2C9_CLK-PadA55)")
			(pinfunction "I2C9_CLK")
			(pintype "bidirectional+no_connect")
		)
		(pad "A56" smd circle
			(at 22.1 7.5 90)
			(size 0.5 0.5)
			(layers "F.Cu" "F.Mask" "F.Paste")
			(net 69 "/Expansion connector/SPI1.MISO")
			(pinfunction "SPI1_MISO")
			(pintype "bidirectional")
		)
		(pad "A57" smd circle
			(at 23 7.5 90)
			(size 0.5 0.5)
			(layers "F.Cu" "F.Mask" "F.Paste")
			(net 158 "/Expansion connector/UART2.CTS")
			(pinfunction "UART2_CTS")
			(pintype "input")
		)
		(pad "A58" smd circle
			(at 23.9 7.5 90)
			(size 0.5 0.5)
			(layers "F.Cu" "F.Mask" "F.Paste")
			(net 878 "/SoM_IO/M2_E_W_DIS_2_1V8")
			(pinfunction "GPIO20")
			(pintype "passive")
		)
		(pad "A59" smd circle
			(at 24.8 7.5 90)
			(size 0.5 0.5)
			(layers "F.Cu" "F.Mask" "F.Paste")
			(net 487 "/Expansion connector/GPIO.USER_LED0")
			(pinfunction "GPIO05")
			(pintype "passive")
		)
		(pad "A60" smd circle
			(at 25.7 7.5 90)
			(size 0.5 0.5)
			(layers "F.Cu" "F.Mask" "F.Paste")
			(net 743 "/SoM_IO2/JTAG_TCK")
			(pinfunction "JTAG_TCK")
			(pintype "passive")
		)
		(pad "A61" smd circle
			(at 26.6 7.5 90)
			(size 0.5 0.5)
			(layers "F.Cu" "F.Mask" "F.Paste")
			(net 762 "Net-(J1A-SYSTEM_OC_N)")
			(pinfunction "SYSTEM_OC_N")
			(pintype "input")
		)
		(pad "A62" smd circle
			(at 27.5 7.5 90)
			(size 0.5 0.5)
			(layers "F.Cu" "F.Mask" "F.Paste")
			(net 1288 "unconnected-(J1K-GPIO17-PadA62)")
			(pinfunction "GPIO17")
			(pintype "passive+no_connect")
		)
		(pad "A63" smd circle
			(at 28.4 7.5 90)
			(size 0.5 0.5)
			(layers "F.Cu" "F.Mask" "F.Paste")
			(net 1 "GND")
			(pinfunction "GND")
			(pintype "passive")
		)
		(pad "B3" smd circle
			(at -28.2 6 90)
			(size 0.5 0.5)
			(layers "F.Cu" "F.Mask" "F.Paste")
			(net 12 "SYS_VIN_HV")
			(pinfunction "SYS_VIN_HV")
			(pintype "power_in")
		)
		(pad "B4" smd circle
			(at -27.3 6 90)
			(size 0.5 0.5)
			(layers "F.Cu" "F.Mask" "F.Paste")
			(net 1 "GND")
			(pinfunction "GND")
			(pintype "passive")
		)
		(pad "B5" smd circle
			(at -26.4 6 90)
			(size 0.5 0.5)
			(layers "F.Cu" "F.Mask" "F.Paste")
			(net 727 "unconnected-(J1G-FSI_GPIO26-PadB5)")
			(pinfunction "FSI_GPIO26")
			(pintype "passive+no_connect")
		)
		(pad "B6" smd circle
			(at -25.5 6 90)
			(size 0.5 0.5)
			(layers "F.Cu" "F.Mask" "F.Paste")
			(net 721 "unconnected-(J1I-FSI_GPIO30-PadB6)")
			(pinfunction "FSI_GPIO30")
			(pintype "passive+no_connect")
		)
		(pad "B7" smd circle
			(at -24.6 6 90)
			(size 0.5 0.5)
			(layers "F.Cu" "F.Mask" "F.Paste")
			(net 1 "GND")
			(pinfunction "GND")
			(pintype "passive")
		)
		(pad "B8" smd circle
			(at -23.7 6 90)
			(size 0.5 0.5)
			(layers "F.Cu" "F.Mask" "F.Paste")
			(net 764 "unconnected-(J1H-GPIO11-PadB8)")
			(pinfunction "GPIO11")
			(pintype "input+no_connect")
		)
		(pad "B9" smd circle
			(at -22.8 6 90)
			(size 0.5 0.5)
			(layers "F.Cu" "F.Mask" "F.Paste")
			(net 558 "unconnected-(J1G-FSI_GPIO20-PadB9)")
			(pinfunction "FSI_GPIO20")
			(pintype "input+no_connect")
		)
		(pad "B10" smd circle
			(at -21.9 6 90)
			(size 0.5 0.5)
			(layers "F.Cu" "F.Mask" "F.Paste")
			(net 795 "Net-(J1A-POWER_INT_N)")
			(pinfunction "POWER_INT_N")
			(pintype "input")
		)
		(pad "B11" smd circle
			(at -21 6 90)
			(size 0.5 0.5)
			(layers "F.Cu" "F.Mask" "F.Paste")
			(net 1 "GND")
			(pinfunction "GND")
			(pintype "passive")
		)
		(pad "B12" smd circle
			(at -20.1 6 90)
			(size 0.5 0.5)
			(layers "F.Cu" "F.Mask" "F.Paste")
			(net 797 "/Expansion connector/PCIe_{C3x2}.RX0+")
			(pinfunction "UPHY_RX6_P")
			(pintype "input")
		)
		(pad "B13" smd circle
			(at -19.2 6 90)
			(size 0.5 0.5)
			(layers "F.Cu" "F.Mask" "F.Paste")
			(net 752 "/Expansion connector/PCIe_{C3x2}.RX0-")
			(pinfunction "UPHY_RX6_N")
			(pintype "input")
		)
		(pad "B14" smd circle
			(at -18.3 6 90)
			(size 0.5 0.5)
			(layers "F.Cu" "F.Mask" "F.Paste")
			(net 1 "GND")
			(pinfunction "GND")
			(pintype "passive")
		)
		(pad "B15" smd circle
			(at -17 6 90)
			(size 0.5 0.5)
			(layers "F.Cu" "F.Mask" "F.Paste")
			(net 1 "GND")
			(pinfunction "GND")
			(pintype "passive")
		)
		(pad "B16" smd circle
			(at -16.1 6 90)
			(size 0.5 0.5)
			(layers "F.Cu" "F.Mask" "F.Paste")
			(net 651 "unconnected-(J1B-UPHY_RX16_P-PadB16)")
			(pinfunction "UPHY_RX16_P")
			(pintype "input+no_connect")
		)
		(pad "B17" smd circle
			(at -15.2 6 90)
			(size 0.5 0.5)
			(layers "F.Cu" "F.Mask" "F.Paste")
			(net 730 "unconnected-(J1B-UPHY_RX16_N-PadB17)")
			(pinfunction "UPHY_RX16_N")
			(pintype "input+no_connect")
		)
		(pad "B18" smd circle
			(at -14.3 6 90)
			(size 0.5 0.5)
			(layers "F.Cu" "F.Mask" "F.Paste")
			(net 1 "GND")
			(pinfunction "GND")
			(pintype "passive")
		)
		(pad "B19" smd circle
			(at -13 6 90)
			(size 0.5 0.5)
			(layers "F.Cu" "F.Mask" "F.Paste")
			(net 1 "GND")
			(pinfunction "GND")
			(pintype "passive")
		)
		(pad "B20" smd circle
			(at -12.1 6 90)
			(size 0.5 0.5)
			(layers "F.Cu" "F.Mask" "F.Paste")
			(net 637 "/Expansion connector/PCIe_{C2x1}.RX0-")
			(pinfunction "UPHY_RX4_N")
			(pintype "input")
		)
		(pad "B21" smd circle
			(at -11.2 6 90)
			(size 0.5 0.5)
			(layers "F.Cu" "F.Mask" "F.Paste")
			(net 790 "/Expansion connector/PCIe_{C2x1}.RX0+")
			(pinfunction "UPHY_RX4_P")
			(pintype "input")
		)
		(pad "B22" smd circle
			(at -10.3 6 90)
			(size 0.5 0.5)
			(layers "F.Cu" "F.Mask" "F.Paste")
			(net 1 "GND")
			(pinfunction "GND")
			(pintype "passive")
		)
		(pad "B23" smd circle
			(at -9 6 90)
			(size 0.5 0.5)
			(layers "F.Cu" "F.Mask" "F.Paste")
			(net 1 "GND")
			(pinfunction "GND")
			(pintype "passive")
		)
		(pad "B24" smd circle
			(at -8.1 6 90)
			(size 0.5 0.5)
			(layers "F.Cu" "F.Mask" "F.Paste")
			(net 620 "/M.2/PCIe_{C5x4}.RX1-")
			(pinfunction "UPHY_RX9_N")
			(pintype "input")
		)
		(pad "B25" smd circle
			(at -7.2 6 90)
			(size 0.5 0.5)
			(layers "F.Cu" "F.Mask" "F.Paste")
			(net 674 "/M.2/PCIe_{C5x4}.RX1+")
			(pinfunction "UPHY_RX9_P")
			(pintype "input")
		)
		(pad "B26" smd circle
			(at -6.3 6 90)
			(size 0.5 0.5)
			(layers "F.Cu" "F.Mask" "F.Paste")
			(net 1 "GND")
			(pinfunction "GND")
			(pintype "passive")
		)
		(pad "B27" smd circle
			(at -5 6 90)
			(size 0.5 0.5)
			(layers "F.Cu" "F.Mask" "F.Paste")
			(net 1 "GND")
			(pinfunction "GND")
			(pintype "passive")
		)
		(pad "B28" smd circle
			(at -4.1 6 90)
			(size 0.5 0.5)
			(layers "F.Cu" "F.Mask" "F.Paste")
			(net 667 "unconnected-(J1B-UPHY_RX13_N-PadB28)")
			(pinfunction "UPHY_RX13_N")
			(pintype "input+no_connect")
		)
		(pad "B29" smd circle
			(at -3.2 6 90)
			(size 0.5 0.5)
			(layers "F.Cu" "F.Mask" "F.Paste")
			(net 559 "unconnected-(J1B-UPHY_RX13_P-PadB29)")
			(pinfunction "UPHY_RX13_P")
			(pintype "input+no_connect")
		)
		(pad "B30" smd circle
			(at -2.3 6 90)
			(size 0.5 0.5)
			(layers "F.Cu" "F.Mask" "F.Paste")
			(net 1 "GND")
			(pinfunction "GND")
			(pintype "passive")
		)
		(pad "B31" smd circle
			(at -1 6 90)
			(size 0.5 0.5)
			(layers "F.Cu" "F.Mask" "F.Paste")
			(net 1 "GND")
			(pinfunction "GND")
			(pintype "power_in")
		)
		(pad "B32" smd circle
			(at -0.1 6 90)
			(size 0.5 0.5)
			(layers "F.Cu" "F.Mask" "F.Paste")
			(net 94 "/M.2/PCIe_{C1x1}.RX0-")
			(pinfunction "UPHY_RX3_N")
			(pintype "input")
		)
		(pad "B33" smd circle
			(at 0.8 6 90)
			(size 0.5 0.5)
			(layers "F.Cu" "F.Mask" "F.Paste")
			(net 130 "/M.2/PCIe_{C1x1}.RX0+")
			(pinfunction "UPHY_RX3_P")
			(pintype "input")
		)
		(pad "B34" smd circle
			(at 1.7 6 90)
			(size 0.5 0.5)
			(layers "F.Cu" "F.Mask" "F.Paste")
			(net 1 "GND")
			(pinfunction "GND")
			(pintype "passive")
		)
		(pad "B35" smd circle
			(at 3 6 90)
			(size 0.5 0.5)
			(layers "F.Cu" "F.Mask" "F.Paste")
			(net 1 "GND")
			(pinfunction "GND")
			(pintype "passive")
		)
		(pad "B36" smd circle
			(at 3.9 6 90)
			(size 0.5 0.5)
			(layers "F.Cu" "F.Mask" "F.Paste")
			(net 679 "/M.2/PCIe_{C1x1}.~{RST}")
			(pinfunction "PEX_C1_RST_N")
			(pintype "output")
		)
		(pad "B37" smd circle
			(at 4.8 6 90)
			(size 0.5 0.5)
			(layers "F.Cu" "F.Mask" "F.Paste")
			(net 137 "/M.2/PCIe_{C1x1}.~{CLKREQ}")
			(pinfunction "PEX_C1_CLKREQ_N")
			(pintype "bidirectional")
		)
		(pad "B38" smd circle
			(at 5.7 6 90)
			(size 0.5 0.5)
			(layers "F.Cu" "F.Mask" "F.Paste")
			(net 1 "GND")
			(pinfunction "GND")
			(pintype "passive")
		)
		(pad "B39" smd circle
			(at 7 6 90)
			(size 0.5 0.5)
			(layers "F.Cu" "F.Mask" "F.Paste")
			(net 1 "GND")
			(pinfunction "GND")
			(pintype "passive")
		)
		(pad "B40" smd circle
			(at 7.9 6 90)
			(size 0.5 0.5)
			(layers "F.Cu" "F.Mask" "F.Paste")
			(net 613 "unconnected-(J1G-FSI_GPIO02-PadB40)")
			(pinfunction "FSI_GPIO02")
			(pintype "passive+no_connect")
		)
		(pad "B41" smd circle
			(at 8.8 6 90)
			(size 0.5 0.5)
			(layers "F.Cu" "F.Mask" "F.Paste")
			(net 1 "GND")
			(pinfunction "GND")
			(pintype "passive")
		)
		(pad "B42" smd circle
			(at 9.7 6 90)
			(size 0.5 0.5)
			(layers "F.Cu" "F.Mask" "F.Paste")
			(net 68 "/CSI/CAM0.CSI2_CLK-")
			(pinfunction "CSI2_CLK_N")
			(pintype "input")
		)
		(pad "B43" smd circle
			(at 10.6 6 90)
			(size 0.5 0.5)
			(layers "F.Cu" "F.Mask" "F.Paste")
			(net 249 "/CSI/CAM0.CSI2_CLK+")
			(pinfunction "CSI2_CLK_P")
			(pintype "input")
		)
		(pad "B44" smd circle
			(at 11.5 6 90)
			(size 0.5 0.5)
			(layers "F.Cu" "F.Mask" "F.Paste")
			(net 1 "GND")
			(pinfunction "GND")
			(pintype "passive")
		)
		(pad "B45" smd circle
			(at 12.4 6 90)
			(size 0.5 0.5)
			(layers "F.Cu" "F.Mask" "F.Paste")
			(net 92 "unconnected-(J1F-CSI7_CLK_P-PadB45)")
			(pinfunction "CSI7_CLK_P")
			(pintype "input+no_connect")
		)
		(pad "B46" smd circle
			(at 13.3 6 90)
			(size 0.5 0.5)
			(layers "F.Cu" "F.Mask" "F.Paste")
			(net 73 "unconnected-(J1F-CSI7_CLK_N-PadB46)")
			(pinfunction "CSI7_CLK_N")
			(pintype "input+no_connect")
		)
		(pad "B47" smd circle
			(at 14.2 6 90)
			(size 0.5 0.5)
			(layers "F.Cu" "F.Mask" "F.Paste")
			(net 1 "GND")
			(pinfunction "GND")
			(pintype "passive")
		)
		(pad "B48" smd circle
			(at 15.1 6 90)
			(size 0.5 0.5)
			(layers "F.Cu" "F.Mask" "F.Paste")
			(net 647 "unconnected-(J1G-FSI_GPIO16-PadB48)")
			(pinfunction "FSI_GPIO16")
			(pintype "passive+no_connect")
		)
		(pad "B49" smd circle
			(at 16 6 90)
			(size 0.5 0.5)
			(layers "F.Cu" "F.Mask" "F.Paste")
			(net 718 "unconnected-(J1G-FSI_GPIO17-PadB49)")
			(pinfunction "FSI_GPIO17")
			(pintype "passive+no_connect")
		)
		(pad "B50" smd circle
			(at 16.9 6 90)
			(size 0.5 0.5)
			(layers "F.Cu" "F.Mask" "F.Paste")
			(net 1 "GND")
			(pinfunction "GND")
			(pintype "passive")
		)
		(pad "B51" smd circle
			(at 17.8 6 90)
			(size 0.5 0.5)
			(layers "F.Cu" "F.Mask" "F.Paste")
			(net 596 "/SoM_IO2/DP0.TX1_C+")
			(pinfunction "DP0_D1_HDMI_D1_P")
			(pintype "output")
		)
		(pad "B52" smd circle
			(at 18.7 6 90)
			(size 0.5 0.5)
			(layers "F.Cu" "F.Mask" "F.Paste")
			(net 597 "/SoM_IO2/DP0.TX1_C-")
			(pinfunction "DP0_D1_HDMI_D1_N")
			(pintype "output")
		)
		(pad "B53" smd circle
			(at 19.6 6 90)
			(size 0.5 0.5)
			(layers "F.Cu" "F.Mask" "F.Paste")
			(net 1 "GND")
			(pinfunction "GND")
			(pintype "passive")
		)
		(pad "B54" smd circle
			(at 20.5 6 90)
			(size 0.5 0.5)
			(layers "F.Cu" "F.Mask" "F.Paste")
			(net 155 "/CSI/CAM_CTRL.VSYNC_CAM0")
			(pinfunction "GPIO45")
			(pintype "passive")
		)
		(pad "B55" smd circle
			(at 21.4 6 90)
			(size 0.5 0.5)
			(layers "F.Cu" "F.Mask" "F.Paste")
			(net 704 "Net-(J1A-GPIO30)")
			(pinfunction "GPIO30")
			(pintype "passive")
		)
		(pad "B56" smd circle
			(at 22.3 6 90)
			(size 0.5 0.5)
			(layers "F.Cu" "F.Mask" "F.Paste")
			(net 364 "/Expansion connector/SPI1.~{CS1}")
			(pinfunction "SPI1_CS1_N")
			(pintype "bidirectional")
		)
		(pad "B57" smd circle
			(at 23.2 6 90)
			(size 0.5 0.5)
			(layers "F.Cu" "F.Mask" "F.Paste")
			(net 1 "GND")
			(pinfunction "GND")
			(pintype "passive")
		)
		(pad "B58" smd circle
			(at 24.1 6 90)
			(size 0.5 0.5)
			(layers "F.Cu" "F.Mask" "F.Paste")
			(net 341 "/Expansion connector/FMC_PRESENT")
			(pinfunction "GPIO21")
			(pintype "passive")
		)
		(pad "B59" smd circle
			(at 25 6 90)
			(size 0.5 0.5)
			(layers "F.Cu" "F.Mask" "F.Paste")
			(net 342 "/Expansion connector/FMC_PG_C2M")
			(pinfunction "GPIO04")
			(pintype "passive")
		)
		(pad "B60" smd circle
			(at 25.9 6 90)
			(size 0.5 0.5)
			(layers "F.Cu" "F.Mask" "F.Paste")
			(net 715 "/SoM_IO2/JTAG_TDI")
			(pinfunction "JTAG_TDI")
			(pintype "passive")
		)
		(pad "B61" smd circle
			(at 26.8 6 90)
			(size 0.5 0.5)
			(layers "F.Cu" "F.Mask" "F.Paste")
			(net 701 "/Expansion connector/CAN3.DIN")
			(pinfunction "CAN3_DIN")
			(pintype "input")
		)
		(pad "B62" smd circle
			(at 27.7 6 90)
			(size 0.5 0.5)
			(layers "F.Cu" "F.Mask" "F.Paste")
			(net 371 "/Expansion connector/GPIO.USER_LED1")
			(pinfunction "GPIO08")
			(pintype "passive")
		)
		(pad "B63" smd circle
			(at 28.6 6 90)
			(size 0.5 0.5)
			(layers "F.Cu" "F.Mask" "F.Paste")
			(net 12 "SYS_VIN_HV")
			(pinfunction "SYS_VIN_HV")
			(pintype "passive")
		)
		(pad "C1" smd circle
			(at -30.2 4.5 90)
			(size 0.5 0.5)
			(layers "F.Cu" "F.Mask" "F.Paste")
			(net 12 "SYS_VIN_HV")
			(pinfunction "SYS_VIN_HV")
			(pintype "passive")
		)
		(pad "C2" smd circle
			(at -29.3 4.5 90)
			(size 0.5 0.5)
			(layers "F.Cu" "F.Mask" "F.Paste")
			(net 12 "SYS_VIN_HV")
			(pinfunction "SYS_VIN_HV")
			(pintype "passive")
		)
		(pad "C3" smd circle
			(at -28.4 4.5 90)
			(size 0.5 0.5)
			(layers "F.Cu" "F.Mask" "F.Paste")
			(net 1 "GND")
			(pinfunction "GND")
			(pintype "passive")
		)
		(pad "C4" smd circle
			(at -27.5 4.5 90)
			(size 0.5 0.5)
			(layers "F.Cu" "F.Mask" "F.Paste")
			(net 67 "/CSI/CAM_CTRL.VSYNC_CAM2")
			(pinfunction "GPIO47")
			(pintype "passive")
		)
		(pad "C5" smd circle
			(at -26.6 4.5 90)
			(size 0.5 0.5)
			(layers "F.Cu" "F.Mask" "F.Paste")
			(net 560 "unconnected-(J1H-GPIO40-PadC5)")
			(pinfunction "GPIO40")
			(pintype "output+no_connect")
		)
		(pad "C6" smd circle
			(at -25.7 4.5 90)
			(size 0.5 0.5)
			(layers "F.Cu" "F.Mask" "F.Paste")
			(net 796 "Net-(J1A-UFS0_RST_N)")
			(pinfunction "UFS0_RST_N")
			(pintype "passive")
		)
		(pad "C7" smd circle
			(at -24.8 4.5 90)
			(size 0.5 0.5)
			(layers "F.Cu" "F.Mask" "F.Paste")
			(net 72 "/SoM_IO/I2S_{M.2}.SDOUT")
			(pinfunction "I2S1_SDOUT")
			(pintype "output")
		)
		(pad "C8" smd circle
			(at -23.9 4.5 90)
			(size 0.5 0.5)
			(layers "F.Cu" "F.Mask" "F.Paste")
			(net 588 "unconnected-(J1C-PEX_C4_CLKREQ_N-PadC8)")
			(pinfunction "PEX_C4_CLKREQ_N")
			(pintype "bidirectional+no_connect")
		)
		(pad "C9" smd circle
			(at -23 4.5 90)
			(size 0.5 0.5)
			(layers "F.Cu" "F.Mask" "F.Paste")
			(net 1 "GND")
			(pinfunction "GND")
			(pintype "passive")
		)
		(pad "C10" smd circle
			(at -22.1 4.5 90)
			(size 0.5 0.5)
			(layers "F.Cu" "F.Mask" "F.Paste")
			(net 140 "/SoM_IO2/USB1.D-")
			(pinfunction "USB1_N")
			(pintype "bidirectional")
		)
		(pad "C11" smd circle
			(at -21.2 4.5 90)
			(size 0.5 0.5)
			(layers "F.Cu" "F.Mask" "F.Paste")
			(net 55 "/SoM_IO2/USB1.D+")
			(pinfunction "USB1_P")
			(pintype "bidirectional")
		)
		(pad "C12" smd circle
			(at -20.3 4.5 90)
			(size 0.5 0.5)
			(layers "F.Cu" "F.Mask" "F.Paste")
			(net 1 "GND")
			(pinfunction "GND")
			(pintype "passive")
		)
		(pad "C13" smd circle
			(at -19 4.5 90)
			(size 0.5 0.5)
			(layers "F.Cu" "F.Mask" "F.Paste")
			(net 1 "GND")
			(pinfunction "GND")
			(pintype "passive")
		)
		(pad "C14" smd circle
			(at -18.1 4.5 90)
			(size 0.5 0.5)
			(layers "F.Cu" "F.Mask" "F.Paste")
			(net 1260 "/SoM_IO2/DP2.TX2_C-")
			(pinfunction "DP2_D2_HDMI_D0_N")
			(pintype "output")
		)
		(pad "C15" smd circle
			(at -17.2 4.5 90)
			(size 0.5 0.5)
			(layers "F.Cu" "F.Mask" "F.Paste")
			(net 1256 "/SoM_IO2/DP2.TX2_C+")
			(pinfunction "DP2_D2_HDMI_D0_P")
			(pintype "output")
		)
		(pad "C16" smd circle
			(at -16.3 4.5 90)
			(size 0.5 0.5)
			(layers "F.Cu" "F.Mask" "F.Paste")
			(net 1 "GND")
			(pinfunction "GND")
			(pintype "passive")
		)
		(pad "C17" smd circle
			(at -15 4.5 90)
			(size 0.5 0.5)
			(layers "F.Cu" "F.Mask" "F.Paste")
			(net 1 "GND")
			(pinfunction "GND")
			(pintype "passive")
		)
		(pad "C18" smd circle
			(at -14.1 4.5 90)
			(size 0.5 0.5)
			(layers "F.Cu" "F.Mask" "F.Paste")
			(net 781 "/Expansion connector/DP1.HPD")
			(pinfunction "HPD1")
			(pintype "bidirectional")
		)
		(pad "C19" smd circle
			(at -13.2 4.5 90)
			(size 0.5 0.5)
			(layers "F.Cu" "F.Mask" "F.Paste")
			(net 574 "/Expansion connector/DP3.HPD")
			(pinfunction "HPD3")
			(pintype "bidirectional")
		)
		(pad "C20" smd circle
			(at -12.3 4.5 90)
			(size 0.5 0.5)
			(layers "F.Cu" "F.Mask" "F.Paste")
			(net 1 "GND")
			(pinfunction "GND")
			(pintype "passive")
		)
		(pad "C21" smd circle
			(at -11 4.5 90)
			(size 0.5 0.5)
			(layers "F.Cu" "F.Mask" "F.Paste")
			(net 1 "GND")
			(pinfunction "GND")
			(pintype "passive")
		)
		(pad "C22" smd circle
			(at -10.1 4.5 90)
			(size 0.5 0.5)
			(layers "F.Cu" "F.Mask" "F.Paste")
			(net 623 "/SoM_IO2/USBSS2.RX-")
			(pinfunction "UPHY_RX2_N")
			(pintype "input")
		)
		(pad "C23" smd circle
			(at -9.2 4.5 90)
			(size 0.5 0.5)
			(layers "F.Cu" "F.Mask" "F.Paste")
			(net 770 "/SoM_IO2/USBSS2.RX+")
			(pinfunction "UPHY_RX2_P")
			(pintype "input")
		)
		(pad "C24" smd circle
			(at -8.3 4.5 90)
			(size 0.5 0.5)
			(layers "F.Cu" "F.Mask" "F.Paste")
			(net 1 "GND")
			(pinfunction "GND")
			(pintype "passive")
		)
		(pad "C25" smd circle
			(at -7 4.5 90)
			(size 0.5 0.5)
			(layers "F.Cu" "F.Mask" "F.Paste")
			(net 1 "GND")
			(pinfunction "GND")
			(pintype "passive")
		)
		(pad "C26" smd circle
			(at -6.1 4.5 90)
			(size 0.5 0.5)
			(layers "F.Cu" "F.Mask" "F.Paste")
			(net 552 "/M.2/PCIe_{C5x4}.RX2-")
			(pinfunction "UPHY_RX10_N")
			(pintype "input")
		)
		(pad "C27" smd circle
			(at -5.2 4.5 90)
			(size 0.5 0.5)
			(layers "F.Cu" "F.Mask" "F.Paste")
			(net 731 "/M.2/PCIe_{C5x4}.RX2+")
			(pinfunction "UPHY_RX10_P")
			(pintype "input")
		)
		(pad "C28" smd circle
			(at -4.3 4.5 90)
			(size 0.5 0.5)
			(layers "F.Cu" "F.Mask" "F.Paste")
			(net 1 "GND")
			(pinfunction "GND")
			(pintype "passive")
		)
		(pad "C29" smd circle
			(at -3 4.5 90)
			(size 0.5 0.5)
			(layers "F.Cu" "F.Mask" "F.Paste")
			(net 1 "GND")
			(pinfunction "GND")
			(pintype "passive")
		)
		(pad "C30" smd circle
			(at -2.1 4.5 90)
			(size 0.5 0.5)
			(layers "F.Cu" "F.Mask" "F.Paste")
			(net 697 "unconnected-(J1B-UPHY_RX14_N-PadC30)")
			(pinfunction "UPHY_RX14_N")
			(pintype "input+no_connect")
		)
		(pad "C31" smd circle
			(at -1.2 4.5 90)
			(size 0.5 0.5)
			(layers "F.Cu" "F.Mask" "F.Paste")
			(net 573 "unconnected-(J1B-UPHY_RX14_P-PadC31)")
			(pinfunction "UPHY_RX14_P")
			(pintype "input+no_connect")
		)
		(pad "C32" smd circle
			(at -0.3 4.5 90)
			(size 0.5 0.5)
			(layers "F.Cu" "F.Mask" "F.Paste")
			(net 1 "GND")
			(pinfunction "GND")
			(pintype "passive")
		)
		(pad "C33" smd circle
			(at 1 4.5 90)
			(size 0.5 0.5)
			(layers "F.Cu" "F.Mask" "F.Paste")
			(net 1 "GND")
			(pinfunction "GND")
			(pintype "passive")
		)
		(pad "C34" smd circle
			(at 1.9 4.5 90)
			(size 0.5 0.5)
			(layers "F.Cu" "F.Mask" "F.Paste")
			(net 598 "/Recovery USB/USBSS0.RX+")
			(pinfunction "UPHY_RX0_P")
			(pintype "input")
		)
		(pad "C35" smd circle
			(at 2.8 4.5 90)
			(size 0.5 0.5)
			(layers "F.Cu" "F.Mask" "F.Paste")
			(net 622 "/Recovery USB/USBSS0.RX-")
			(pinfunction "UPHY_RX0_N")
			(pintype "input")
		)
		(pad "C36" smd circle
			(at 3.7 4.5 90)
			(size 0.5 0.5)
			(layers "F.Cu" "F.Mask" "F.Paste")
			(net 1 "GND")
			(pinfunction "GND")
			(pintype "passive")
		)
		(pad "C37" smd circle
			(at 5 4.5 90)
			(size 0.5 0.5)
			(layers "F.Cu" "F.Mask" "F.Paste")
			(net 1 "GND")
			(pinfunction "GND")
			(pintype "passive")
		)
		(pad "C38" smd circle
			(at 5.9 4.5 90)
			(size 0.5 0.5)
			(layers "F.Cu" "F.Mask" "F.Paste")
			(net 692 "/SoM_IO/~{USBC2_INT}_1V8")
			(pinfunction "GPIO32")
			(pintype "passive")
		)
		(pad "C39" smd circle
			(at 6.8 4.5 90)
			(size 0.5 0.5)
			(layers "F.Cu" "F.Mask" "F.Paste")
			(net 906 "/SoM_IO/M2_E_W_DIS_1_1V8")
			(pinfunction "GPIO18")
			(pintype "passive")
		)
		(pad "C40" smd circle
			(at 7.7 4.5 90)
			(size 0.5 0.5)
			(layers "F.Cu" "F.Mask" "F.Paste")
			(net 1 "GND")
			(pinfunction "GND")
			(pintype "passive")
		)
		(pad "C41" smd circle
			(at 8.6 4.5 90)
			(size 0.5 0.5)
			(layers "F.Cu" "F.Mask" "F.Paste")
			(net 170 "/CSI/CAM0.CSI2_D1-")
			(pinfunction "CSI2_D1_N")
			(pintype "input")
		)
		(pad "C42" smd circle
			(at 9.5 4.5 90)
			(size 0.5 0.5)
			(layers "F.Cu" "F.Mask" "F.Paste")
			(net 89 "/CSI/CAM0.CSI2_D1+")
			(pinfunction "CSI2_D1_P")
			(pintype "input")
		)
		(pad "C43" smd circle
			(at 10.4 4.5 90)
			(size 0.5 0.5)
			(layers "F.Cu" "F.Mask" "F.Paste")
			(net 1 "GND")
			(pinfunction "GND")
			(pintype "passive")
		)
		(pad "C44" smd circle
			(at 11.3 4.5 90)
			(size 0.5 0.5)
			(layers "F.Cu" "F.Mask" "F.Paste")
			(net 58 "unconnected-(J1F-CSI5_CLK_P-PadC44)")
			(pinfunction "CSI5_CLK_P")
			(pintype "input+no_connect")
		)
		(pad "C45" smd circle
			(at 12.2 4.5 90)
			(size 0.5 0.5)
			(layers "F.Cu" "F.Mask" "F.Paste")
			(net 127 "unconnected-(J1F-CSI5_CLK_N-PadC45)")
			(pinfunction "CSI5_CLK_N")
			(pintype "input+no_connect")
		)
		(pad "C46" smd circle
			(at 13.1 4.5 90)
			(size 0.5 0.5)
			(layers "F.Cu" "F.Mask" "F.Paste")
			(net 1 "GND")
			(pinfunction "GND")
			(pintype "passive")
		)
		(pad "C47" smd circle
			(at 14 4.5 90)
			(size 0.5 0.5)
			(layers "F.Cu" "F.Mask" "F.Paste")
			(net 102 "/CSI/CAM3.CSI7_D1+")
			(pinfunction "CSI7_D1_P")
			(pintype "input")
		)
		(pad "C48" smd circle
			(at 14.9 4.5 90)
			(size 0.5 0.5)
			(layers "F.Cu" "F.Mask" "F.Paste")
			(net 86 "/CSI/CAM3.CSI7_D1-")
			(pinfunction "CSI7_D1_N")
			(pintype "input")
		)
		(pad "C49" smd circle
			(at 15.8 4.5 90)
			(size 0.5 0.5)
			(layers "F.Cu" "F.Mask" "F.Paste")
			(net 1 "GND")
			(pinfunction "GND")
			(pintype "passive")
		)
		(pad "C50" smd circle
			(at 16.7 4.5 90)
			(size 0.5 0.5)
			(layers "F.Cu" "F.Mask" "F.Paste")
			(net 799 "/SoM_IO2/DP0.TX3_C-")
			(pinfunction "DP0_D3_HDMI_CK_N")
			(pintype "output")
		)
		(pad "C51" smd circle
			(at 17.6 4.5 90)
			(size 0.5 0.5)
			(layers "F.Cu" "F.Mask" "F.Paste")
			(net 746 "/SoM_IO2/DP0.TX3_C+")
			(pinfunction "DP0_D3_HDMI_CK_P")
			(pintype "output")
		)
		(pad "C52" smd circle
			(at 18.5 4.5 90)
			(size 0.5 0.5)
			(layers "F.Cu" "F.Mask" "F.Paste")
			(net 1 "GND")
			(pinfunction "GND")
			(pintype "passive")
		)
		(pad "C53" smd circle
			(at 19.4 4.5 90)
			(size 0.5 0.5)
			(layers "F.Cu" "F.Mask" "F.Paste")
			(net 112 "/SoM_IO/I2C5_SDA_1V8")
			(pinfunction "I2C5_DAT")
			(pintype "bidirectional")
		)
		(pad "C54" smd circle
			(at 20.3 4.5 90)
			(size 0.5 0.5)
			(layers "F.Cu" "F.Mask" "F.Paste")
			(net 750 "unconnected-(J1I-GPIO33-PadC54)")
			(pinfunction "GPIO33")
			(pintype "bidirectional+no_connect")
		)
		(pad "C55" smd circle
			(at 21.2 4.5 90)
			(size 0.5 0.5)
			(layers "F.Cu" "F.Mask" "F.Paste")
			(net 907 "Net-(J1A-GPIO39)")
			(pinfunction "GPIO39")
			(pintype "passive")
		)
		(pad "C56" smd circle
			(at 22.1 4.5 90)
			(size 0.5 0.5)
			(layers "F.Cu" "F.Mask" "F.Paste")
			(net 51 "/Expansion connector/UART2.RX")
			(pinfunction "UART2_RX")
			(pintype "input")
		)
		(pad "C57" smd circle
			(at 23 4.5 90)
			(size 0.5 0.5)
			(layers "F.Cu" "F.Mask" "F.Paste")
			(net 438 "/Expansion connector/SPI3.~{CS0}")
			(pinfunction "SPI3_CS0_N")
			(pintype "bidirectional")
		)
		(pad "C58" smd circle
			(at 23.9 4.5 90)
			(size 0.5 0.5)
			(layers "F.Cu" "F.Mask" "F.Paste")
			(net 61 "/Expansion connector/UART2.TX")
			(pinfunction "UART2_TX")
			(pintype "output")
		)
		(pad "C59" smd circle
			(at 24.8 4.5 90)
			(size 0.5 0.5)
			(layers "F.Cu" "F.Mask" "F.Paste")
			(net 773 "unconnected-(J1H-I2S3_SCLK-PadC59)")
			(pinfunction "I2S3_SCLK")
			(pintype "bidirectional+no_connect")
		)
		(pad "C60" smd circle
			(at 25.7 4.5 90)
			(size 0.5 0.5)
			(layers "F.Cu" "F.Mask" "F.Paste")
			(net 556 "unconnected-(J1H-I2S3_FS-PadC60)")
			(pinfunction "I2S3_FS")
			(pintype "bidirectional+no_connect")
		)
		(pad "C61" smd circle
			(at 26.6 4.5 90)
			(size 0.5 0.5)
			(layers "F.Cu" "F.Mask" "F.Paste")
			(net 448 "/Expansion connector/GPIO.USER_BTN0")
			(pinfunction "GPIO09")
			(pintype "passive")
		)
		(pad "C62" smd circle
			(at 27.5 4.5 90)
			(size 0.5 0.5)
			(layers "F.Cu" "F.Mask" "F.Paste")
			(net 1 "GND")
			(pinfunction "GND")
			(pintype "passive")
		)
		(pad "C63" smd circle
			(at 28.4 4.5 90)
			(size 0.5 0.5)
			(layers "F.Cu" "F.Mask" "F.Paste")
			(net 12 "SYS_VIN_HV")
			(pinfunction "SYS_VIN_HV")
			(pintype "passive")
		)
		(pad "C64" smd circle
			(at 29.3 4.5 90)
			(size 0.5 0.5)
			(layers "F.Cu" "F.Mask" "F.Paste")
			(net 12 "SYS_VIN_HV")
			(pinfunction "SYS_VIN_HV")
			(pintype "passive")
		)
		(pad "C65" smd circle
			(at 30.2 4.5 90)
			(size 0.5 0.5)
			(layers "F.Cu" "F.Mask" "F.Paste")
			(net 12 "SYS_VIN_HV")
			(pinfunction "SYS_VIN_HV")
			(pintype "passive")
		)
		(pad "D1" smd circle
			(at -30 3 90)
			(size 0.5 0.5)
			(layers "F.Cu" "F.Mask" "F.Paste")
			(net 12 "SYS_VIN_HV")
			(pinfunction "SYS_VIN_HV")
			(pintype "passive")
		)
		(pad "D2" smd circle
			(at -29.1 3 90)
			(size 0.5 0.5)
			(layers "F.Cu" "F.Mask" "F.Paste")
			(net 12 "SYS_VIN_HV")
			(pinfunction "SYS_VIN_HV")
			(pintype "passive")
		)
		(pad "D3" smd circle
			(at -28.2 3 90)
			(size 0.5 0.5)
			(layers "F.Cu" "F.Mask" "F.Paste")
			(net 12 "SYS_VIN_HV")
			(pinfunction "SYS_VIN_HV")
			(pintype "passive")
		)
		(pad "D4" smd circle
			(at -27.3 3 90)
			(size 0.5 0.5)
			(layers "F.Cu" "F.Mask" "F.Paste")
			(net 1 "GND")
			(pinfunction "GND")
			(pintype "passive")
		)
		(pad "D5" smd circle
			(at -26.4 3 90)
			(size 0.5 0.5)
			(layers "F.Cu" "F.Mask" "F.Paste")
			(net 47 "/CSI/CAM_CTRL.VSYNC_CAM3")
			(pinfunction "GPIO48")
			(pintype "passive")
		)
		(pad "D6" smd circle
			(at -25.5 3 90)
			(size 0.5 0.5)
			(layers "F.Cu" "F.Mask" "F.Paste")
			(net 918 "unconnected-(J1I-FSI_GPIO33-PadD6)")
			(pinfunction "FSI_GPIO33")
			(pintype "bidirectional+no_connect")
		)
		(pad "D7" smd circle
			(at -24.6 3 90)
			(size 0.5 0.5)
			(layers "F.Cu" "F.Mask" "F.Paste")
			(net 1 "GND")
			(pinfunction "GND")
			(pintype "passive")
		)
		(pad "D8" smd circle
			(at -23.7 3 90)
			(size 0.5 0.5)
			(layers "F.Cu" "F.Mask" "F.Paste")
			(net 150 "/SoM_IO/I2S_{M.2}.FS")
			(pinfunction "I2S1_FS")
			(pintype "bidirectional")
		)
		(pad "D9" smd circle
			(at -22.8 3 90)
			(size 0.5 0.5)
			(layers "F.Cu" "F.Mask" "F.Paste")
			(net 767 "unconnected-(J1G-FSI_GPIO25-PadD9)")
			(pinfunction "FSI_GPIO25")
			(pintype "bidirectional+no_connect")
		)
		(pad "D10" smd circle
			(at -21.9 3 90)
			(size 0.5 0.5)
			(layers "F.Cu" "F.Mask" "F.Paste")
			(net 554 "/Expansion connector/PCIe_{C2x1}.~{RST}")
			(pinfunction "PEX_C2_RST_N")
			(pintype "output")
		)
		(pad "D11" smd circle
			(at -21 3 90)
			(size 0.5 0.5)
			(layers "F.Cu" "F.Mask" "F.Paste")
			(net 1 "GND")
			(pinfunction "GND")
			(pintype "passive")
		)
		(pad "D12" smd circle
			(at -20.1 3 90)
			(size 0.5 0.5)
			(layers "F.Cu" "F.Mask" "F.Paste")
			(net 782 "/Expansion connector/PCIe_{C3x2}.RX1+")
			(pinfunction "UPHY_RX7_P")
			(pintype "input")
		)
		(pad "D13" smd circle
			(at -19.2 3 90)
			(size 0.5 0.5)
			(layers "F.Cu" "F.Mask" "F.Paste")
			(net 722 "/Expansion connector/PCIe_{C3x2}.RX1-")
			(pinfunction "UPHY_RX7_N")
			(pintype "input")
		)
		(pad "D14" smd circle
			(at -18.3 3 90)
			(size 0.5 0.5)
			(layers "F.Cu" "F.Mask" "F.Paste")
			(net 1 "GND")
			(pinfunction "GND")
			(pintype "passive")
		)
		(pad "D15" smd circle
			(at -17 3 90)
			(size 0.5 0.5)
			(layers "F.Cu" "F.Mask" "F.Paste")
			(net 1 "GND")
			(pinfunction "GND")
			(pintype "passive")
		)
		(pad "D16" smd circle
			(at -16.1 3 90)
			(size 0.5 0.5)
			(layers "F.Cu" "F.Mask" "F.Paste")
			(net 1252 "/SoM_IO2/DP1.AUX_C+")
			(pinfunction "DP_AUX_CH1_P")
			(pintype "bidirectional")
		)
		(pad "D17" smd circle
			(at -15.2 3 90)
			(size 0.5 0.5)
			(layers "F.Cu" "F.Mask" "F.Paste")
			(net 1253 "/SoM_IO2/DP1.AUX_C-")
			(pinfunction "DP_AUX_CH1_N")
			(pintype "bidirectional")
		)
		(pad "D18" smd circle
			(at -14.3 3 90)
			(size 0.5 0.5)
			(layers "F.Cu" "F.Mask" "F.Paste")
			(net 1 "GND")
			(pinfunction "GND")
			(pintype "passive")
		)
		(pad "D19" smd circle
			(at -13 3 90)
			(size 0.5 0.5)
			(layers "F.Cu" "F.Mask" "F.Paste")
			(net 1 "GND")
			(pinfunction "GND")
			(pintype "passive")
		)
		(pad "D20" smd circle
			(at -12.1 3 90)
			(size 0.5 0.5)
			(layers "F.Cu" "F.Mask" "F.Paste")
			(net 638 "unconnected-(J1B-UPHY_RX5_P-PadD20)")
			(pinfunction "UPHY_RX5_P")
			(pintype "input+no_connect")
		)
		(pad "D21" smd circle
			(at -11.2 3 90)
			(size 0.5 0.5)
			(layers "F.Cu" "F.Mask" "F.Paste")
			(net 608 "unconnected-(J1B-UPHY_RX5_N-PadD21)")
			(pinfunction "UPHY_RX5_N")
			(pintype "input+no_connect")
		)
		(pad "D22" smd circle
			(at -10.3 3 90)
			(size 0.5 0.5)
			(layers "F.Cu" "F.Mask" "F.Paste")
			(net 1 "GND")
			(pinfunction "GND")
			(pintype "passive")
		)
		(pad "D23" smd circle
			(at -9 3 90)
			(size 0.5 0.5)
			(layers "F.Cu" "F.Mask" "F.Paste")
			(net 1 "GND")
			(pinfunction "GND")
			(pintype "passive")
		)
		(pad "D24" smd circle
			(at -8.1 3 90)
			(size 0.5 0.5)
			(layers "F.Cu" "F.Mask" "F.Paste")
			(net 725 "/M.2/PCIe_{C5x4}.RX0+")
			(pinfunction "UPHY_RX8_P")
			(pintype "input")
		)
		(pad "D25" smd circle
			(at -7.2 3 90)
			(size 0.5 0.5)
			(layers "F.Cu" "F.Mask" "F.Paste")
			(net 669 "/M.2/PCIe_{C5x4}.RX0-")
			(pinfunction "UPHY_RX8_N")
			(pintype "input")
		)
		(pad "D26" smd circle
			(at -6.3 3 90)
			(size 0.5 0.5)
			(layers "F.Cu" "F.Mask" "F.Paste")
			(net 1 "GND")
			(pinfunction "GND")
			(pintype "passive")
		)
		(pad "D27" smd circle
			(at -5 3 90)
			(size 0.5 0.5)
			(layers "F.Cu" "F.Mask" "F.Paste")
			(net 1 "GND")
			(pinfunction "GND")
			(pintype "passive")
		)
		(pad "D28" smd circle
			(at -4.1 3 90)
			(size 0.5 0.5)
			(layers "F.Cu" "F.Mask" "F.Paste")
			(net 101 "/SFP/SFI.RX+")
			(pinfunction "UPHY_RX12_P")
			(pintype "input")
		)
		(pad "D29" smd circle
			(at -3.2 3 90)
			(size 0.5 0.5)
			(layers "F.Cu" "F.Mask" "F.Paste")
			(net 147 "/SFP/SFI.RX-")
			(pinfunction "UPHY_RX12_N")
			(pintype "input")
		)
		(pad "D30" smd circle
			(at -2.3 3 90)
			(size 0.5 0.5)
			(layers "F.Cu" "F.Mask" "F.Paste")
			(net 1 "GND")
			(pinfunction "GND")
			(pintype "passive")
		)
		(pad "D31" smd circle
			(at -1 3 90)
			(size 0.5 0.5)
			(layers "F.Cu" "F.Mask" "F.Paste")
			(net 1 "GND")
			(pinfunction "GND")
			(pintype "passive")
		)
		(pad "D32" smd circle
			(at -0.1 3 90)
			(size 0.5 0.5)
			(layers "F.Cu" "F.Mask" "F.Paste")
			(net 1268 "/SoM_IO2/DP3.TX0_C-")
			(pinfunction "DP3_D0_HDMI_D2_N")
			(pintype "output")
		)
		(pad "D33" smd circle
			(at 0.8 3 90)
			(size 0.5 0.5)
			(layers "F.Cu" "F.Mask" "F.Paste")
			(net 1264 "/SoM_IO2/DP3.TX0_C+")
			(pinfunction "DP3_D0_HDMI_D2_P")
			(pintype "output")
		)
		(pad "D34" smd circle
			(at 1.7 3 90)
			(size 0.5 0.5)
			(layers "F.Cu" "F.Mask" "F.Paste")
			(net 1 "GND")
			(pinfunction "GND")
			(pintype "passive")
		)
		(pad "D35" smd circle
			(at 3 3 90)
			(size 0.5 0.5)
			(layers "F.Cu" "F.Mask" "F.Paste")
			(net 1 "GND")
			(pinfunction "GND")
			(pintype "passive")
		)
		(pad "D36" smd circle
			(at 3.9 3 90)
			(size 0.5 0.5)
			(layers "F.Cu" "F.Mask" "F.Paste")
			(net 636 "unconnected-(J1G-FSI_GPIO11-PadD36)")
			(pinfunction "FSI_GPIO11")
			(pintype "passive+no_connect")
		)
		(pad "D37" smd circle
			(at 4.8 3 90)
			(size 0.5 0.5)
			(layers "F.Cu" "F.Mask" "F.Paste")
			(net 32 "Net-(D1-C)")
			(pinfunction "PMIC_BBATT")
			(pintype "power_in")
		)
		(pad "D38" smd circle
			(at 5.7 3 90)
			(size 0.5 0.5)
			(layers "F.Cu" "F.Mask" "F.Paste")
			(net 1 "GND")
			(pinfunction "GND")
			(pintype "passive")
		)
		(pad "D39" smd circle
			(at 7 3 90)
			(size 0.5 0.5)
			(layers "F.Cu" "F.Mask" "F.Paste")
			(net 1 "GND")
			(pinfunction "GND")
			(pintype "passive")
		)
		(pad "D40" smd circle
			(at 7.9 3 90)
			(size 0.5 0.5)
			(layers "F.Cu" "F.Mask" "F.Paste")
			(net 724 "unconnected-(J1G-FSI_GPIO01-PadD40)")
			(pinfunction "FSI_GPIO01")
			(pintype "passive+no_connect")
		)
		(pad "D41" smd circle
			(at 8.8 3 90)
			(size 0.5 0.5)
			(layers "F.Cu" "F.Mask" "F.Paste")
			(net 1 "GND")
			(pinfunction "GND")
			(pintype "passive")
		)
		(pad "D42" smd circle
			(at 9.7 3 90)
			(size 0.5 0.5)
			(layers "F.Cu" "F.Mask" "F.Paste")
			(net 125 "/CSI/CAM2.CSI5_D0+")
			(pinfunction "CSI5_D0_P")
			(pintype "input")
		)
		(pad "D43" smd circle
			(at 10.6 3 90)
			(size 0.5 0.5)
			(layers "F.Cu" "F.Mask" "F.Paste")
			(net 128 "/CSI/CAM2.CSI5_D0-")
			(pinfunction "CSI5_D0_N")
			(pintype "input")
		)
		(pad "D44" smd circle
			(at 11.5 3 90)
			(size 0.5 0.5)
			(layers "F.Cu" "F.Mask" "F.Paste")
			(net 1 "GND")
			(pinfunction "GND")
			(pintype "passive")
		)
		(pad "D45" smd circle
			(at 12.4 3 90)
			(size 0.5 0.5)
			(layers "F.Cu" "F.Mask" "F.Paste")
			(net 79 "/CSI/CAM2.CSI5_D1-")
			(pinfunction "CSI5_D1_N")
			(pintype "input")
		)
		(pad "D46" smd circle
			(at 13.3 3 90)
			(size 0.5 0.5)
			(layers "F.Cu" "F.Mask" "F.Paste")
			(net 163 "/CSI/CAM2.CSI5_D1+")
			(pinfunction "CSI5_D1_P")
			(pintype "input")
		)
		(pad "D47" smd circle
			(at 14.2 3 90)
			(size 0.5 0.5)
			(layers "F.Cu" "F.Mask" "F.Paste")
			(net 1 "GND")
			(pinfunction "GND")
			(pintype "passive")
		)
		(pad "D48" smd circle
			(at 15.1 3 90)
			(size 0.5 0.5)
			(layers "F.Cu" "F.Mask" "F.Paste")
			(net 676 "/M.2/PCIe_{C1x1}.CLK-")
			(pinfunction "UPHY_REFCLK6_N")
			(pintype "output")
		)
		(pad "D49" smd circle
			(at 16 3 90)
			(size 0.5 0.5)
			(layers "F.Cu" "F.Mask" "F.Paste")
			(net 589 "/M.2/PCIe_{C1x1}.CLK+")
			(pinfunction "UPHY_REFCLK6_P")
			(pintype "output")
		)
		(pad "D50" smd circle
			(at 16.9 3 90)
			(size 0.5 0.5)
			(layers "F.Cu" "F.Mask" "F.Paste")
			(net 1 "GND")
			(pinfunction "GND")
			(pintype "passive")
		)
		(pad "D51" smd circle
			(at 17.8 3 90)
			(size 0.5 0.5)
			(layers "F.Cu" "F.Mask" "F.Paste")
			(net 523 "/SoM_IO2/DP0.TX0_C+")
			(pinfunction "DP0_D0_HDMI_D2_P")
			(pintype "output")
		)
		(pad "D52" smd circle
			(at 18.7 3 90)
			(size 0.5 0.5)
			(layers "F.Cu" "F.Mask" "F.Paste")
			(net 575 "/SoM_IO2/DP0.TX0_C-")
			(pinfunction "DP0_D0_HDMI_D2_N")
			(pintype "output")
		)
		(pad "D53" smd circle
			(at 19.6 3 90)
			(size 0.5 0.5)
			(layers "F.Cu" "F.Mask" "F.Paste")
			(net 1 "GND")
			(pinfunction "GND")
			(pintype "passive")
		)
		(pad "D54" smd circle
			(at 20.5 3 90)
			(size 0.5 0.5)
			(layers "F.Cu" "F.Mask" "F.Paste")
			(net 908 "unconnected-(J1I-GPIO03-PadD54)")
			(pinfunction "GPIO03")
			(pintype "output+no_connect")
		)
		(pad "D55" smd circle
			(at 21.4 3 90)
			(size 0.5 0.5)
			(layers "F.Cu" "F.Mask" "F.Paste")
			(net 65 "/Expansion connector/SPI1.MOSI")
			(pinfunction "SPI1_MOSI")
			(pintype "bidirectional")
		)
		(pad "D56" smd circle
			(at 22.3 3 90)
			(size 0.5 0.5)
			(layers "F.Cu" "F.Mask" "F.Paste")
			(net 75 "/Expansion connector/SPI3.MISO")
			(pinfunction "SPI3_MISO")
			(pintype "bidirectional")
		)
		(pad "D57" smd circle
			(at 23.2 3 90)
			(size 0.5 0.5)
			(layers "F.Cu" "F.Mask" "F.Paste")
			(net 1 "GND")
			(pinfunction "GND")
			(pintype "passive")
		)
		(pad "D58" smd circle
			(at 24.1 3 90)
			(size 0.5 0.5)
			(layers "F.Cu" "F.Mask" "F.Paste")
			(net 688 "/SoM_IO2/JTAG_TDO")
			(pinfunction "JTAG_TDO")
			(pintype "passive")
		)
		(pad "D59" smd circle
			(at 25 3 90)
			(size 0.5 0.5)
			(layers "F.Cu" "F.Mask" "F.Paste")
			(net 600 "/Expansion connector/CAN2.DOUT")
			(pinfunction "CAN2_DOUT")
			(pintype "output")
		)
		(pad "D60" smd circle
			(at 25.9 3 90)
			(size 0.5 0.5)
			(layers "F.Cu" "F.Mask" "F.Paste")
			(net 409 "/Expansion connector/SPI2.~{CS0}")
			(pinfunction "SPI2_CS0_N")
			(pintype "bidirectional")
		)
		(pad "D61" smd circle
			(at 26.8 3 90)
			(size 0.5 0.5)
			(layers "F.Cu" "F.Mask" "F.Paste")
			(net 983 "/CSI/I2C_{CAM}.SCL")
			(pinfunction "I2C4_CLK")
			(pintype "bidirectional")
		)
		(pad "D62" smd circle
			(at 27.7 3 90)
			(size 0.5 0.5)
			(layers "F.Cu" "F.Mask" "F.Paste")
			(net 109 "/Expansion connector/SPI2.MISO")
			(pinfunction "SPI2_MISO")
			(pintype "bidirectional")
		)
		(pad "D63" smd circle
			(at 28.6 3 90)
			(size 0.5 0.5)
			(layers "F.Cu" "F.Mask" "F.Paste")
			(net 1 "GND")
			(pinfunction "GND")
			(pintype "passive")
		)
		(pad "D64" smd circle
			(at 29.5 3 90)
			(size 0.5 0.5)
			(layers "F.Cu" "F.Mask" "F.Paste")
			(net 12 "SYS_VIN_HV")
			(pinfunction "SYS_VIN_HV")
			(pintype "passive")
		)
		(pad "D65" smd circle
			(at 30.4 3 90)
			(size 0.5 0.5)
			(layers "F.Cu" "F.Mask" "F.Paste")
			(net 12 "SYS_VIN_HV")
			(pinfunction "SYS_VIN_HV")
			(pintype "passive")
		)
		(pad "E1" smd circle
			(at -30.2 1.5 90)
			(size 0.5 0.5)
			(layers "F.Cu" "F.Mask" "F.Paste")
			(net 12 "SYS_VIN_HV")
			(pinfunction "SYS_VIN_HV")
			(pintype "passive")
		)
		(pad "E2" smd circle
			(at -29.3 1.5 90)
			(size 0.5 0.5)
			(layers "F.Cu" "F.Mask" "F.Paste")
			(net 12 "SYS_VIN_HV")
			(pinfunction "SYS_VIN_HV")
			(pintype "passive")
		)
		(pad "E3" smd circle
			(at -28.4 1.5 90)
			(size 0.5 0.5)
			(layers "F.Cu" "F.Mask" "F.Paste")
			(net 1 "GND")
			(pinfunction "GND")
			(pintype "passive")
		)
		(pad "E4" smd circle
			(at -27.5 1.5 90)
			(size 0.5 0.5)
			(layers "F.Cu" "F.Mask" "F.Paste")
			(net 146 "/Expansion connector/I2S2.FS")
			(pinfunction "I2S2_FS")
			(pintype "bidirectional")
		)
		(pad "E5" smd circle
			(at -26.6 1.5 90)
			(size 0.5 0.5)
			(layers "F.Cu" "F.Mask" "F.Paste")
			(net 1292 "/SoM_IO/GPIO_EXP_IRQ_1V8")
			(pinfunction "GPIO44")
			(pintype "passive")
		)
		(pad "E6" smd circle
			(at -25.7 1.5 90)
			(size 0.5 0.5)
			(layers "F.Cu" "F.Mask" "F.Paste")
			(net 882 "unconnected-(J1I-SGMII0_MDC-PadE6)")
			(pinfunction "SGMII0_MDC")
			(pintype "output+no_connect")
		)
		(pad "E7" smd circle
			(at -24.8 1.5 90)
			(size 0.5 0.5)
			(layers "F.Cu" "F.Mask" "F.Paste")
			(net 670 "unconnected-(J1I-SGMII0_MDIO-PadE7)")
			(pinfunction "SGMII0_MDIO")
			(pintype "bidirectional+no_connect")
		)
		(pad "E8" smd circle
			(at -23.9 1.5 90)
			(size 0.5 0.5)
			(layers "F.Cu" "F.Mask" "F.Paste")
			(net 740 "unconnected-(J1I-FSI_GPIO35-PadE8)")
			(pinfunction "FSI_GPIO35")
			(pintype "bidirectional+no_connect")
		)
		(pad "E9" smd circle
			(at -23 1.5 90)
			(size 0.5 0.5)
			(layers "F.Cu" "F.Mask" "F.Paste")
			(net 1 "GND")
			(pinfunction "GND")
			(pintype "passive")
		)
		(pad "E10" smd circle
			(at -22.1 1.5 90)
			(size 0.5 0.5)
			(layers "F.Cu" "F.Mask" "F.Paste")
			(net 686 "unconnected-(J1H-GPIO12-PadE10)")
			(pinfunction "GPIO12")
			(pintype "bidirectional+no_connect")
		)
		(pad "E11" smd circle
			(at -21.2 1.5 90)
			(size 0.5 0.5)
			(layers "F.Cu" "F.Mask" "F.Paste")
			(net 694 "/Expansion connector/PCIe_{C2x1}.~{CLKREQ}")
			(pinfunction "PEX_C2_CLKREQ_N")
			(pintype "bidirectional")
		)
		(pad "E12" smd circle
			(at -20.3 1.5 90)
			(size 0.5 0.5)
			(layers "F.Cu" "F.Mask" "F.Paste")
			(net 1 "GND")
			(pinfunction "GND")
			(pintype "passive")
		)
		(pad "E13" smd circle
			(at -19 1.5 90)
			(size 0.5 0.5)
			(layers "F.Cu" "F.Mask" "F.Paste")
			(net 1 "GND")
			(pinfunction "GND")
			(pintype "passive")
		)
		(pad "E14" smd circle
			(at -18.1 1.5 90)
			(size 0.5 0.5)
			(layers "F.Cu" "F.Mask" "F.Paste")
			(net 668 "/SoM_IO2/PCIe_{C2x1}R_CLK-")
			(pinfunction "UPHY_REFCLK5_N")
			(pintype "bidirectional")
		)
		(pad "E15" smd circle
			(at -17.2 1.5 90)
			(size 0.5 0.5)
			(layers "F.Cu" "F.Mask" "F.Paste")
			(net 720 "/SoM_IO2/PCIe_{C2x1}R_CLK+")
			(pinfunction "UPHY_REFCLK5_P")
			(pintype "bidirectional")
		)
		(pad "E16" smd circle
			(at -16.3 1.5 90)
			(size 0.5 0.5)
			(layers "F.Cu" "F.Mask" "F.Paste")
			(net 1 "GND")
			(pinfunction "GND")
			(pintype "passive")
		)
		(pad "E17" smd circle
			(at -15 1.5 90)
			(size 0.5 0.5)
			(layers "F.Cu" "F.Mask" "F.Paste")
			(net 1 "GND")
			(pinfunction "GND")
			(pintype "passive")
		)
		(pad "E18" smd circle
			(at -14.1 1.5 90)
			(size 0.5 0.5)
			(layers "F.Cu" "F.Mask" "F.Paste")
			(net 1263 "/SoM_IO2/DP2.AUX_C-")
			(pinfunction "DP_AUX_CH2_N")
			(pintype "bidirectional")
		)
		(pad "E19" smd circle
			(at -13.2 1.5 90)
			(size 0.5 0.5)
			(layers "F.Cu" "F.Mask" "F.Paste")
			(net 1262 "/SoM_IO2/DP2.AUX_C+")
			(pinfunction "DP_AUX_CH2_P")
			(pintype "bidirectional")
		)
		(pad "E20" smd circle
			(at -12.3 1.5 90)
			(size 0.5 0.5)
			(layers "F.Cu" "F.Mask" "F.Paste")
			(net 1 "GND")
			(pinfunction "GND")
			(pintype "passive")
		)
		(pad "E21" smd circle
			(at -11 1.5 90)
			(size 0.5 0.5)
			(layers "F.Cu" "F.Mask" "F.Paste")
			(net 1 "GND")
			(pinfunction "GND")
			(pintype "passive")
		)
		(pad "E22" smd circle
			(at -10.1 1.5 90)
			(size 0.5 0.5)
			(layers "F.Cu" "F.Mask" "F.Paste")
			(net 732 "/Expansion connector/PCIe_{C3x2}.CLK-")
			(pinfunction "UPHY_REFCLK4_N")
			(pintype "output")
		)
		(pad "E23" smd circle
			(at -9.2 1.5 90)
			(size 0.5 0.5)
			(layers "F.Cu" "F.Mask" "F.Paste")
			(net 699 "/Expansion connector/PCIe_{C3x2}.CLK+")
			(pinfunction "UPHY_REFCLK4_P")
			(pintype "output")
		)
		(pad "E24" smd circle
			(at -8.3 1.5 90)
			(size 0.5 0.5)
			(layers "F.Cu" "F.Mask" "F.Paste")
			(net 1 "GND")
			(pinfunction "GND")
			(pintype "passive")
		)
		(pad "E25" smd circle
			(at -7 1.5 90)
			(size 0.5 0.5)
			(layers "F.Cu" "F.Mask" "F.Paste")
			(net 1 "GND")
			(pinfunction "GND")
			(pintype "passive")
		)
		(pad "E26" smd circle
			(at -6.1 1.5 90)
			(size 0.5 0.5)
			(layers "F.Cu" "F.Mask" "F.Paste")
			(net 842 "/Expansion connector/I2C7.SDA")
			(pinfunction "I2C7_DAT")
			(pintype "bidirectional")
		)
		(pad "E27" smd circle
			(at -5.2 1.5 90)
			(size 0.5 0.5)
			(layers "F.Cu" "F.Mask" "F.Paste")
			(net 866 "/Expansion connector/I2C7.SCL")
			(pinfunction "I2C7_CLK")
			(pintype "bidirectional")
		)
		(pad "E28" smd circle
			(at -4.3 1.5 90)
			(size 0.5 0.5)
			(layers "F.Cu" "F.Mask" "F.Paste")
			(net 1 "GND")
			(pinfunction "GND")
			(pintype "passive")
		)
		(pad "E29" smd circle
			(at -3 1.5 90)
			(size 0.5 0.5)
			(layers "F.Cu" "F.Mask" "F.Paste")
			(net 1 "GND")
			(pinfunction "GND")
			(pintype "passive")
		)
		(pad "E30" smd circle
			(at -2.1 1.5 90)
			(size 0.5 0.5)
			(layers "F.Cu" "F.Mask" "F.Paste")
			(net 568 "unconnected-(J1G-FSI_GPIO24-PadE30)")
			(pinfunction "FSI_GPIO24")
			(pintype "passive+no_connect")
		)
		(pad "E31" smd circle
			(at -1.2 1.5 90)
			(size 0.5 0.5)
			(layers "F.Cu" "F.Mask" "F.Paste")
			(net 711 "unconnected-(J1G-FSI_GPIO23-PadE31)")
			(pinfunction "FSI_GPIO23")
			(pintype "passive+no_connect")
		)
		(pad "E32" smd circle
			(at -0.3 1.5 90)
			(size 0.5 0.5)
			(layers "F.Cu" "F.Mask" "F.Paste")
			(net 1 "GND")
			(pinfunction "GND")
			(pintype "passive")
		)
		(pad "E33" smd circle
			(at 1 1.5 90)
			(size 0.5 0.5)
			(layers "F.Cu" "F.Mask" "F.Paste")
			(net 1 "GND")
			(pinfunction "GND")
			(pintype "passive")
		)
		(pad "E34" smd circle
			(at 1.9 1.5 90)
			(size 0.5 0.5)
			(layers "F.Cu" "F.Mask" "F.Paste")
			(net 710 "unconnected-(J1I-FSI_GPIO15-PadE34)")
			(pinfunction "FSI_GPIO15")
			(pintype "passive+no_connect")
		)
		(pad "E35" smd circle
			(at 2.8 1.5 90)
			(size 0.5 0.5)
			(layers "F.Cu" "F.Mask" "F.Paste")
			(net 785 "unconnected-(J1I-FSI_GPIO14-PadE35)")
			(pinfunction "FSI_GPIO14")
			(pintype "passive+no_connect")
		)
		(pad "E36" smd circle
			(at 3.7 1.5 90)
			(size 0.5 0.5)
			(layers "F.Cu" "F.Mask" "F.Paste")
			(net 1 "GND")
			(pinfunction "GND")
			(pintype "passive")
		)
		(pad "E37" smd circle
			(at 5 1.5 90)
			(size 0.5 0.5)
			(layers "F.Cu" "F.Mask" "F.Paste")
			(net 1 "GND")
			(pinfunction "GND")
			(pintype "passive")
		)
		(pad "E38" smd circle
			(at 5.9 1.5 90)
			(size 0.5 0.5)
			(layers "F.Cu" "F.Mask" "F.Paste")
			(net 153 "/CSI/CAM1.CSI0_D1-")
			(pinfunction "CSI0_D1_N")
			(pintype "input")
		)
		(pad "E39" smd circle
			(at 6.8 1.5 90)
			(size 0.5 0.5)
			(layers "F.Cu" "F.Mask" "F.Paste")
			(net 54 "/CSI/CAM1.CSI0_D1+")
			(pinfunction "CSI0_D1_P")
			(pintype "input")
		)
		(pad "E40" smd circle
			(at 7.7 1.5 90)
			(size 0.5 0.5)
			(layers "F.Cu" "F.Mask" "F.Paste")
			(net 1 "GND")
			(pinfunction "GND")
			(pintype "passive")
		)
		(pad "E41" smd circle
			(at 8.6 1.5 90)
			(size 0.5 0.5)
			(layers "F.Cu" "F.Mask" "F.Paste")
			(net 113 "/CSI/CAM1.CSI0_D0-")
			(pinfunction "CSI0_D0_N")
			(pintype "input")
		)
		(pad "E42" smd circle
			(at 9.5 1.5 90)
			(size 0.5 0.5)
			(layers "F.Cu" "F.Mask" "F.Paste")
			(net 157 "/CSI/CAM1.CSI0_D0+")
			(pinfunction "CSI0_D0_P")
			(pintype "input")
		)
		(pad "E43" smd circle
			(at 10.4 1.5 90)
			(size 0.5 0.5)
			(layers "F.Cu" "F.Mask" "F.Paste")
			(net 1 "GND")
			(pinfunction "GND")
			(pintype "passive")
		)
		(pad "E44" smd circle
			(at 11.3 1.5 90)
			(size 0.5 0.5)
			(layers "F.Cu" "F.Mask" "F.Paste")
			(net 63 "/CSI/CAM0.CSI3_D0-")
			(pinfunction "CSI3_D0_N")
			(pintype "input")
		)
		(pad "E45" smd circle
			(at 12.2 1.5 90)
			(size 0.5 0.5)
			(layers "F.Cu" "F.Mask" "F.Paste")
			(net 52 "/CSI/CAM0.CSI3_D0+")
			(pinfunction "CSI3_D0_P")
			(pintype "input")
		)
		(pad "E46" smd circle
			(at 13.1 1.5 90)
			(size 0.5 0.5)
			(layers "F.Cu" "F.Mask" "F.Paste")
			(net 1 "GND")
			(pinfunction "GND")
			(pintype "passive")
		)
		(pad "E47" smd circle
			(at 14 1.5 90)
			(size 0.5 0.5)
			(layers "F.Cu" "F.Mask" "F.Paste")
			(net 87 "/CSI/CAM2.CSI4_D1+")
			(pinfunction "CSI4_D1_P")
			(pintype "input")
		)
		(pad "E48" smd circle
			(at 14.9 1.5 90)
			(size 0.5 0.5)
			(layers "F.Cu" "F.Mask" "F.Paste")
			(net 162 "/CSI/CAM2.CSI4_D1-")
			(pinfunction "CSI4_D1_N")
			(pintype "input")
		)
		(pad "E49" smd circle
			(at 15.8 1.5 90)
			(size 0.5 0.5)
			(layers "F.Cu" "F.Mask" "F.Paste")
			(net 1 "GND")
			(pinfunction "GND")
			(pintype "passive")
		)
		(pad "E50" smd circle
			(at 16.7 1.5 90)
			(size 0.5 0.5)
			(layers "F.Cu" "F.Mask" "F.Paste")
			(net 798 "unconnected-(J1I-FSI_GPIO19-PadE50)")
			(pinfunction "FSI_GPIO19")
			(pintype "bidirectional+no_connect")
		)
		(pad "E51" smd circle
			(at 17.6 1.5 90)
			(size 0.5 0.5)
			(layers "F.Cu" "F.Mask" "F.Paste")
			(net 735 "unconnected-(J1I-FSI_GPIO18-PadE51)")
			(pinfunction "FSI_GPIO18")
			(pintype "output+no_connect")
		)
		(pad "E52" smd circle
			(at 18.5 1.5 90)
			(size 0.5 0.5)
			(layers "F.Cu" "F.Mask" "F.Paste")
			(net 1 "GND")
			(pinfunction "GND")
			(pintype "passive")
		)
		(pad "E53" smd circle
			(at 19.4 1.5 90)
			(size 0.5 0.5)
			(layers "F.Cu" "F.Mask" "F.Paste")
			(net 145 "/SoM_IO/I2C3_SDA_1V8")
			(pinfunction "I2C3_DAT")
			(pintype "bidirectional")
		)
		(pad "E54" smd circle
			(at 20.3 1.5 90)
			(size 0.5 0.5)
			(layers "F.Cu" "F.Mask" "F.Paste")
			(net 100 "/Peripherals/FAN_TACH")
			(pinfunction "FAN_TACH")
			(pintype "input")
		)
		(pad "E55" smd circle
			(at 21.2 1.5 90)
			(size 0.5 0.5)
			(layers "F.Cu" "F.Mask" "F.Paste")
			(net 292 "/Expansion connector/SPI1.~{CS0}")
			(pinfunction "SPI1_CS0_N")
			(pintype "bidirectional")
		)
		(pad "E56" smd circle
			(at 22.1 1.5 90)
			(size 0.5 0.5)
			(layers "F.Cu" "F.Mask" "F.Paste")
			(net 405 "/Expansion connector/SPI3.~{CS1}")
			(pinfunction "SPI3_CS1_N")
			(pintype "bidirectional")
		)
		(pad "E57" smd circle
			(at 23 1.5 90)
			(size 0.5 0.5)
			(layers "F.Cu" "F.Mask" "F.Paste")
			(net 1 "GND")
			(pinfunction "GND")
			(pintype "passive")
		)
		(pad "E58" smd circle
			(at 23.9 1.5 90)
			(size 0.5 0.5)
			(layers "F.Cu" "F.Mask" "F.Paste")
			(net 706 "/SoM_IO2/JTAG_TMS")
			(pinfunction "JTAG_TMS")
			(pintype "passive")
		)
		(pad "E59" smd circle
			(at 24.8 1.5 90)
			(size 0.5 0.5)
			(layers "F.Cu" "F.Mask" "F.Paste")
			(net 1295 "unconnected-(J1K-GPIO38-PadE59)")
			(pinfunction "GPIO38")
			(pintype "passive+no_connect")
		)
		(pad "E60" smd circle
			(at 25.7 1.5 90)
			(size 0.5 0.5)
			(layers "F.Cu" "F.Mask" "F.Paste")
			(net 981 "/CSI/I2C_{CAM}.SDA")
			(pinfunction "I2C4_DAT")
			(pintype "bidirectional")
		)
		(pad "E61" smd circle
			(at 26.6 1.5 90)
			(size 0.5 0.5)
			(layers "F.Cu" "F.Mask" "F.Paste")
			(net 393 "/Expansion connector/SPI2.SCK")
			(pinfunction "SPI2_CLK")
			(pintype "bidirectional")
		)
		(pad "E62" smd circle
			(at 27.5 1.5 90)
			(size 0.5 0.5)
			(layers "F.Cu" "F.Mask" "F.Paste")
			(net 1 "GND")
			(pinfunction "GND")
			(pintype "passive")
		)
		(pad "E63" smd circle
			(at 28.4 1.5 90)
			(size 0.5 0.5)
			(layers "F.Cu" "F.Mask" "F.Paste")
			(net 12 "SYS_VIN_HV")
			(pinfunction "SYS_VIN_HV")
			(pintype "passive")
		)
		(pad "E64" smd circle
			(at 29.3 1.5 90)
			(size 0.5 0.5)
			(layers "F.Cu" "F.Mask" "F.Paste")
			(net 12 "SYS_VIN_HV")
			(pinfunction "SYS_VIN_HV")
			(pintype "passive")
		)
		(pad "E65" smd circle
			(at 30.2 1.5 90)
			(size 0.5 0.5)
			(layers "F.Cu" "F.Mask" "F.Paste")
			(net 12 "SYS_VIN_HV")
			(pinfunction "SYS_VIN_HV")
			(pintype "passive")
		)
		(pad "F1" smd circle
			(at -30 0 90)
			(size 0.5 0.5)
			(layers "F.Cu" "F.Mask" "F.Paste")
			(net 12 "SYS_VIN_HV")
			(pinfunction "SYS_VIN_HV")
			(pintype "passive")
		)
		(pad "F2" smd circle
			(at -29.1 0 90)
			(size 0.5 0.5)
			(layers "F.Cu" "F.Mask" "F.Paste")
			(net 12 "SYS_VIN_HV")
			(pinfunction "SYS_VIN_HV")
			(pintype "passive")
		)
		(pad "F3" smd circle
			(at -28.2 0 90)
			(size 0.5 0.5)
			(layers "F.Cu" "F.Mask" "F.Paste")
			(net 12 "SYS_VIN_HV")
			(pinfunction "SYS_VIN_HV")
			(pintype "passive")
		)
		(pad "F4" smd circle
			(at -27.3 0 90)
			(size 0.5 0.5)
			(layers "F.Cu" "F.Mask" "F.Paste")
			(net 1 "GND")
			(pinfunction "GND")
			(pintype "passive")
		)
		(pad "F5" smd circle
			(at -26.4 0 90)
			(size 0.5 0.5)
			(layers "F.Cu" "F.Mask" "F.Paste")
			(net 172 "/Expansion connector/I2S2.SDOUT")
			(pinfunction "I2S2_DOUT")
			(pintype "output")
		)
		(pad "F6" smd circle
			(at -25.5 0 90)
			(size 0.5 0.5)
			(layers "F.Cu" "F.Mask" "F.Paste")
			(net 168 "/Expansion connector/I2S2.SDIN")
			(pinfunction "I2S2_DIN")
			(pintype "input")
		)
		(pad "F7" smd circle
			(at -24.6 0 90)
			(size 0.5 0.5)
			(layers "F.Cu" "F.Mask" "F.Paste")
			(net 1 "GND")
			(pinfunction "GND")
			(pintype "passive")
		)
		(pad "F8" smd circle
			(at -23.7 0 90)
			(size 0.5 0.5)
			(layers "F.Cu" "F.Mask" "F.Paste")
			(net 703 "unconnected-(J1I-FSI_GPIO31-PadF8)")
			(pinfunction "FSI_GPIO31")
			(pintype "bidirectional+no_connect")
		)
		(pad "F9" smd circle
			(at -22.8 0 90)
			(size 0.5 0.5)
			(layers "F.Cu" "F.Mask" "F.Paste")
			(net 689 "/SoM_IO/USBC2_PEN_1V8")
			(pinfunction "GPIO16")
			(pintype "passive")
		)
		(pad "F10" smd circle
			(at -21.9 0 90)
			(size 0.5 0.5)
			(layers "F.Cu" "F.Mask" "F.Paste")
			(net 1242 "/SoM_IO/USBC2_ID_1V8")
			(pinfunction "GPIO15")
			(pintype "passive")
		)
		(pad "F11" smd circle
			(at -21 0 90)
			(size 0.5 0.5)
			(layers "F.Cu" "F.Mask" "F.Paste")
			(net 1 "GND")
			(pinfunction "GND")
			(pintype "passive")
		)
		(pad "F12" smd circle
			(at -20.1 0 90)
			(size 0.5 0.5)
			(layers "F.Cu" "F.Mask" "F.Paste")
			(net 766 "/Recovery USB/USB0.D+")
			(pinfunction "USB0_P")
			(pintype "bidirectional")
		)
		(pad "F13" smd circle
			(at -19.2 0 90)
			(size 0.5 0.5)
			(layers "F.Cu" "F.Mask" "F.Paste")
			(net 698 "/Recovery USB/USB0.D-")
			(pinfunction "USB0_N")
			(pintype "bidirectional")
		)
		(pad "F14" smd circle
			(at -18.3 0 90)
			(size 0.5 0.5)
			(layers "F.Cu" "F.Mask" "F.Paste")
			(net 1 "GND")
			(pinfunction "GND")
			(pintype "passive")
		)
		(pad "F15" smd circle
			(at -17 0 90)
			(size 0.5 0.5)
			(layers "F.Cu" "F.Mask" "F.Paste")
			(net 1 "GND")
			(pinfunction "GND")
			(pintype "passive")
		)
		(pad "F16" smd circle
			(at -16.1 0 90)
			(size 0.5 0.5)
			(layers "F.Cu" "F.Mask" "F.Paste")
			(net 791 "unconnected-(J1C-UPHY_REFCLK0_P-PadF16)")
			(pinfunction "UPHY_REFCLK0_P")
			(pintype "output+no_connect")
		)
		(pad "F17" smd circle
			(at -15.2 0 90)
			(size 0.5 0.5)
			(layers "F.Cu" "F.Mask" "F.Paste")
			(net 614 "unconnected-(J1C-UPHY_REFCLK0_N-PadF17)")
			(pinfunction "UPHY_REFCLK0_N")
			(pintype "output+no_connect")
		)
		(pad "F18" smd circle
			(at -14.3 0 90)
			(size 0.5 0.5)
			(layers "F.Cu" "F.Mask" "F.Paste")
			(net 1 "GND")
			(pinfunction "GND")
			(pintype "passive")
		)
		(pad "F19" smd circle
			(at -13 0 90)
			(size 0.5 0.5)
			(layers "F.Cu" "F.Mask" "F.Paste")
			(net 1 "GND")
			(pinfunction "GND")
			(pintype "passive")
		)
		(pad "F20" smd circle
			(at -12.1 0 90)
			(size 0.5 0.5)
			(layers "F.Cu" "F.Mask" "F.Paste")
			(net 1272 "/SoM_IO2/DP3.AUX_C+")
			(pinfunction "DP_AUX_CH3_P")
			(pintype "bidirectional")
		)
		(pad "F21" smd circle
			(at -11.2 0 90)
			(size 0.5 0.5)
			(layers "F.Cu" "F.Mask" "F.Paste")
			(net 1273 "/SoM_IO2/DP3.AUX_C-")
			(pinfunction "DP_AUX_CH3_N")
			(pintype "bidirectional")
		)
		(pad "F22" smd circle
			(at -10.3 0 90)
			(size 0.5 0.5)
			(layers "F.Cu" "F.Mask" "F.Paste")
			(net 1 "GND")
			(pinfunction "GND")
			(pintype "passive")
		)
		(pad "F23" smd circle
			(at -9 0 90)
			(size 0.5 0.5)
			(layers "F.Cu" "F.Mask" "F.Paste")
			(net 1 "GND")
			(pinfunction "GND")
			(pintype "passive")
		)
		(pad "F24" smd circle
			(at -8.1 0 90)
			(size 0.5 0.5)
			(layers "F.Cu" "F.Mask" "F.Paste")
			(net 646 "unconnected-(J1C-UPHY_REFCLK1_P-PadF24)")
			(pinfunction "UPHY_REFCLK1_P")
			(pintype "bidirectional+no_connect")
		)
		(pad "F25" smd circle
			(at -7.2 0 90)
			(size 0.5 0.5)
			(layers "F.Cu" "F.Mask" "F.Paste")
			(net 778 "unconnected-(J1C-UPHY_REFCLK1_N-PadF25)")
			(pinfunction "UPHY_REFCLK1_N")
			(pintype "bidirectional+no_connect")
		)
		(pad "F26" smd circle
			(at -6.3 0 90)
			(size 0.5 0.5)
			(layers "F.Cu" "F.Mask" "F.Paste")
			(net 1 "GND")
			(pinfunction "GND")
			(pintype "passive")
		)
		(pad "F27" smd circle
			(at -5 0 90)
			(size 0.5 0.5)
			(layers "F.Cu" "F.Mask" "F.Paste")
			(net 1 "GND")
			(pinfunction "GND")
			(pintype "passive")
		)
		(pad "F28" smd circle
			(at -4.1 0 90)
			(size 0.5 0.5)
			(layers "F.Cu" "F.Mask" "F.Paste")
			(net 171 "/SoM_IO2/SFI_REFCLK-")
			(pinfunction "UPHY_REFCLK2_P")
			(pintype "output")
		)
		(pad "F29" smd circle
			(at -3.2 0 90)
			(size 0.5 0.5)
			(layers "F.Cu" "F.Mask" "F.Paste")
			(net 169 "/SoM_IO2/SFI_REFCLK+")
			(pinfunction "UPHY_REFCLK2_N")
			(pintype "output")
		)
		(pad "F30" smd circle
			(at -2.3 0 90)
			(size 0.5 0.5)
			(layers "F.Cu" "F.Mask" "F.Paste")
			(net 1 "GND")
			(pinfunction "GND")
			(pintype "passive")
		)
		(pad "F31" smd circle
			(at -1 0 90)
			(size 0.5 0.5)
			(layers "F.Cu" "F.Mask" "F.Paste")
			(net 1 "GND")
			(pinfunction "GND")
			(pintype "passive")
		)
		(pad "F32" smd circle
			(at -0.1 0 90)
			(size 0.5 0.5)
			(layers "F.Cu" "F.Mask" "F.Paste")
			(net 584 "/M.2/PCIe_{C5x4}.CLK+")
			(pinfunction "UPHY_REFCLK3_P")
			(pintype "bidirectional")
		)
		(pad "F33" smd circle
			(at 0.8 0 90)
			(size 0.5 0.5)
			(layers "F.Cu" "F.Mask" "F.Paste")
			(net 592 "/M.2/PCIe_{C5x4}.CLK-")
			(pinfunction "UPHY_REFCLK3_N")
			(pintype "bidirectional")
		)
		(pad "F34" smd circle
			(at 1.7 0 90)
			(size 0.5 0.5)
			(layers "F.Cu" "F.Mask" "F.Paste")
			(net 1 "GND")
			(pinfunction "GND")
			(pintype "passive")
		)
		(pad "F35" smd circle
			(at 3 0 90)
			(size 0.5 0.5)
			(layers "F.Cu" "F.Mask" "F.Paste")
			(net 1 "GND")
			(pinfunction "GND")
			(pintype "passive")
		)
		(pad "F36" smd circle
			(at 3.9 0 90)
			(size 0.5 0.5)
			(layers "F.Cu" "F.Mask" "F.Paste")
			(net 749 "unconnected-(J1I-FSI_GPIO13-PadF36)")
			(pinfunction "FSI_GPIO13")
			(pintype "passive+no_connect")
		)
		(pad "F37" smd circle
			(at 4.8 0 90)
			(size 0.5 0.5)
			(layers "F.Cu" "F.Mask" "F.Paste")
			(net 716 "unconnected-(J1I-FSI_GPIO12-PadF37)")
			(pinfunction "FSI_GPIO12")
			(pintype "passive+no_connect")
		)
		(pad "F38" smd circle
			(at 5.7 0 90)
			(size 0.5 0.5)
			(layers "F.Cu" "F.Mask" "F.Paste")
			(net 1 "GND")
			(pinfunction "GND")
			(pintype "passive")
		)
		(pad "F39" smd circle
			(at 7 0 90)
			(size 0.5 0.5)
			(layers "F.Cu" "F.Mask" "F.Paste")
			(net 1 "GND")
			(pinfunction "GND")
			(pintype "passive")
		)
		(pad "F40" smd circle
			(at 7.9 0 90)
			(size 0.5 0.5)
			(layers "F.Cu" "F.Mask" "F.Paste")
			(net 579 "unconnected-(J1G-FSI_GPIO00-PadF40)")
			(pinfunction "FSI_GPIO00")
			(pintype "passive+no_connect")
		)
		(pad "F41" smd circle
			(at 8.8 0 90)
			(size 0.5 0.5)
			(layers "F.Cu" "F.Mask" "F.Paste")
			(net 1 "GND")
			(pinfunction "GND")
			(pintype "passive")
		)
		(pad "F42" smd circle
			(at 9.7 0 90)
			(size 0.5 0.5)
			(layers "F.Cu" "F.Mask" "F.Paste")
			(net 66 "/CSI/CAM1.CSI0_CLK-")
			(pinfunction "CSI0_CLK_N")
			(pintype "input")
		)
		(pad "F43" smd circle
			(at 10.6 0 90)
			(size 0.5 0.5)
			(layers "F.Cu" "F.Mask" "F.Paste")
			(net 136 "/CSI/CAM1.CSI0_CLK+")
			(pinfunction "CSI0_CLK_P")
			(pintype "input")
		)
		(pad "F44" smd circle
			(at 11.5 0 90)
			(size 0.5 0.5)
			(layers "F.Cu" "F.Mask" "F.Paste")
			(net 1 "GND")
			(pinfunction "GND")
			(pintype "passive")
		)
		(pad "F45" smd circle
			(at 12.4 0 90)
			(size 0.5 0.5)
			(layers "F.Cu" "F.Mask" "F.Paste")
			(net 166 "unconnected-(J1F-CSI3_CLK_N-PadF45)")
			(pinfunction "CSI3_CLK_N")
			(pintype "input+no_connect")
		)
		(pad "F46" smd circle
			(at 13.3 0 90)
			(size 0.5 0.5)
			(layers "F.Cu" "F.Mask" "F.Paste")
			(net 129 "unconnected-(J1F-CSI3_CLK_P-PadF46)")
			(pinfunction "CSI3_CLK_P")
			(pintype "input+no_connect")
		)
		(pad "F47" smd circle
			(at 14.2 0 90)
			(size 0.5 0.5)
			(layers "F.Cu" "F.Mask" "F.Paste")
			(net 1 "GND")
			(pinfunction "GND")
			(pintype "passive")
		)
		(pad "F48" smd circle
			(at 15.1 0 90)
			(size 0.5 0.5)
			(layers "F.Cu" "F.Mask" "F.Paste")
			(net 160 "/CSI/CAM2.CSI4_CLK+")
			(pinfunction "CSI4_CLK_P")
			(pintype "input")
		)
		(pad "F49" smd circle
			(at 16 0 90)
			(size 0.5 0.5)
			(layers "F.Cu" "F.Mask" "F.Paste")
			(net 84 "/CSI/CAM2.CSI4_CLK-")
			(pinfunction "CSI4_CLK_N")
			(pintype "input")
		)
		(pad "F50" smd circle
			(at 16.9 0 90)
			(size 0.5 0.5)
			(layers "F.Cu" "F.Mask" "F.Paste")
			(net 1 "GND")
			(pinfunction "GND")
			(pintype "passive")
		)
		(pad "F51" smd circle
			(at 17.8 0 90)
			(size 0.5 0.5)
			(layers "F.Cu" "F.Mask" "F.Paste")
			(net 856 "/Expansion connector/I2C8.SDA")
			(pinfunction "I2C8_DAT")
			(pintype "bidirectional")
		)
		(pad "F52" smd circle
			(at 18.7 0 90)
			(size 0.5 0.5)
			(layers "F.Cu" "F.Mask" "F.Paste")
			(net 857 "/Expansion connector/I2C8.SCL")
			(pinfunction "I2C8_CLK")
			(pintype "bidirectional")
		)
		(pad "F53" smd circle
			(at 19.6 0 90)
			(size 0.5 0.5)
			(layers "F.Cu" "F.Mask" "F.Paste")
			(net 60 "/SoM_IO/I2C3_SCL_1V8")
			(pinfunction "I2C3_CLK")
			(pintype "bidirectional")
		)
		(pad "F54" smd circle
			(at 20.5 0 90)
			(size 0.5 0.5)
			(layers "F.Cu" "F.Mask" "F.Paste")
			(net 595 "unconnected-(J1C-GPIO22-PadF54)")
			(pinfunction "GPIO22")
			(pintype "passive+no_connect")
		)
		(pad "F55" smd circle
			(at 21.4 0 90)
			(size 0.5 0.5)
			(layers "F.Cu" "F.Mask" "F.Paste")
			(net 305 "/Expansion connector/SPI3.SCK")
			(pinfunction "SPI3_CLK")
			(pintype "bidirectional")
		)
		(pad "F56" smd circle
			(at 22.3 0 90)
			(size 0.5 0.5)
			(layers "F.Cu" "F.Mask" "F.Paste")
			(net 643 "/SoM_IO/SFP_LEDG_1V8")
			(pinfunction "GPIO36")
			(pintype "passive")
		)
		(pad "F57" smd circle
			(at 23.2 0 90)
			(size 0.5 0.5)
			(layers "F.Cu" "F.Mask" "F.Paste")
			(net 1 "GND")
			(pinfunction "GND")
			(pintype "passive")
		)
		(pad "F58" smd circle
			(at 24.1 0 90)
			(size 0.5 0.5)
			(layers "F.Cu" "F.Mask" "F.Paste")
			(net 690 "/Expansion connector/CAN2.DIN")
			(pinfunction "CAN2_DIN")
			(pintype "input")
		)
		(pad "F59" smd circle
			(at 25 0 90)
			(size 0.5 0.5)
			(layers "F.Cu" "F.Mask" "F.Paste")
			(net 1290 "unconnected-(J1K-GPIO42-PadF59)")
			(pinfunction "GPIO42")
			(pintype "passive+no_connect")
		)
		(pad "F60" smd circle
			(at 25.9 0 90)
			(size 0.5 0.5)
			(layers "F.Cu" "F.Mask" "F.Paste")
			(net 173 "/Expansion connector/SPI2.MOSI")
			(pinfunction "SPI2_MOSI")
			(pintype "bidirectional")
		)
		(pad "F61" smd circle
			(at 26.8 0 90)
			(size 0.5 0.5)
			(layers "F.Cu" "F.Mask" "F.Paste")
			(net 678 "Net-(J1A-VCOMP_ALERT_N)")
			(pinfunction "VCOMP_ALERT_N")
			(pintype "bidirectional")
		)
		(pad "F62" smd circle
			(at 27.7 0 90)
			(size 0.5 0.5)
			(layers "F.Cu" "F.Mask" "F.Paste")
			(net 1 "GND")
			(pinfunction "GND")
			(pintype "passive")
		)
		(pad "F63" smd circle
			(at 28.6 0 90)
			(size 0.5 0.5)
			(layers "F.Cu" "F.Mask" "F.Paste")
			(net 12 "SYS_VIN_HV")
			(pinfunction "SYS_VIN_HV")
			(pintype "passive")
		)
		(pad "F64" smd circle
			(at 29.5 0 90)
			(size 0.5 0.5)
			(layers "F.Cu" "F.Mask" "F.Paste")
			(net 12 "SYS_VIN_HV")
			(pinfunction "SYS_VIN_HV")
			(pintype "passive")
		)
		(pad "F65" smd circle
			(at 30.4 0 90)
			(size 0.5 0.5)
			(layers "F.Cu" "F.Mask" "F.Paste")
			(net 12 "SYS_VIN_HV")
			(pinfunction "SYS_VIN_HV")
			(pintype "passive")
		)
		(pad "G1" smd circle
			(at -30.2 -1.5 90)
			(size 0.5 0.5)
			(layers "F.Cu" "F.Mask" "F.Paste")
			(net 12 "SYS_VIN_HV")
			(pinfunction "SYS_VIN_HV")
			(pintype "passive")
		)
		(pad "G2" smd circle
			(at -29.3 -1.5 90)
			(size 0.5 0.5)
			(layers "F.Cu" "F.Mask" "F.Paste")
			(net 12 "SYS_VIN_HV")
			(pinfunction "SYS_VIN_HV")
			(pintype "passive")
		)
		(pad "G3" smd circle
			(at -28.4 -1.5 90)
			(size 0.5 0.5)
			(layers "F.Cu" "F.Mask" "F.Paste")
			(net 1 "GND")
			(pinfunction "GND")
			(pintype "passive")
		)
		(pad "G4" smd circle
			(at -27.5 -1.5 90)
			(size 0.5 0.5)
			(layers "F.Cu" "F.Mask" "F.Paste")
			(net 120 "/Expansion connector/I2S2.CLK")
			(pinfunction "I2S2_CLK")
			(pintype "bidirectional")
		)
		(pad "G5" smd circle
			(at -26.6 -1.5 90)
			(size 0.5 0.5)
			(layers "F.Cu" "F.Mask" "F.Paste")
			(net 739 "Net-(J1A-GPIO56)")
			(pinfunction "GPIO56")
			(pintype "passive")
		)
		(pad "G6" smd circle
			(at -25.7 -1.5 90)
			(size 0.5 0.5)
			(layers "F.Cu" "F.Mask" "F.Paste")
			(net 57 "/SFP/MOD_ABS")
			(pinfunction "GPIO49")
			(pintype "passive")
		)
		(pad "G7" smd circle
			(at -24.8 -1.5 90)
			(size 0.5 0.5)
			(layers "F.Cu" "F.Mask" "F.Paste")
			(net 356 "/Expansion connector/GPIO.USER_BTN1")
			(pinfunction "GPIO13")
			(pintype "passive")
		)
		(pad "G8" smd circle
			(at -23.9 -1.5 90)
			(size 0.5 0.5)
			(layers "F.Cu" "F.Mask" "F.Paste")
			(net 565 "/Expansion connector/PCIe_{C3x2}.~{CLKREQ}")
			(pinfunction "PEX_C3_CLKREQ_N")
			(pintype "bidirectional")
		)
		(pad "G9" smd circle
			(at -23 -1.5 90)
			(size 0.5 0.5)
			(layers "F.Cu" "F.Mask" "F.Paste")
			(net 1 "GND")
			(pinfunction "GND")
			(pintype "passive")
		)
		(pad "G10" smd circle
			(at -22.1 -1.5 90)
			(size 0.5 0.5)
			(layers "F.Cu" "F.Mask" "F.Paste")
			(net 642 "/M.2/USB3.D-")
			(pinfunction "USB3_N")
			(pintype "bidirectional")
		)
		(pad "G11" smd circle
			(at -21.2 -1.5 90)
			(size 0.5 0.5)
			(layers "F.Cu" "F.Mask" "F.Paste")
			(net 653 "/M.2/USB3.D+")
			(pinfunction "USB3_P")
			(pintype "bidirectional")
		)
		(pad "G12" smd circle
			(at -20.3 -1.5 90)
			(size 0.5 0.5)
			(layers "F.Cu" "F.Mask" "F.Paste")
			(net 1 "GND")
			(pinfunction "GND")
			(pintype "passive")
		)
		(pad "G13" smd circle
			(at -19 -1.5 90)
			(size 0.5 0.5)
			(layers "F.Cu" "F.Mask" "F.Paste")
			(net 1 "GND")
			(pinfunction "GND")
			(pintype "passive")
		)
		(pad "G14" smd circle
			(at -18.1 -1.5 90)
			(size 0.5 0.5)
			(layers "F.Cu" "F.Mask" "F.Paste")
			(net 1261 "/SoM_IO2/DP2.TX3_C-")
			(pinfunction "DP2_D3_HDMI_CK_N")
			(pintype "output")
		)
		(pad "G15" smd circle
			(at -17.2 -1.5 90)
			(size 0.5 0.5)
			(layers "F.Cu" "F.Mask" "F.Paste")
			(net 1257 "/SoM_IO2/DP2.TX3_C+")
			(pinfunction "DP2_D3_HDMI_CK_P")
			(pintype "output")
		)
		(pad "G16" smd circle
			(at -16.3 -1.5 90)
			(size 0.5 0.5)
			(layers "F.Cu" "F.Mask" "F.Paste")
			(net 1 "GND")
			(pinfunction "GND")
			(pintype "passive")
		)
		(pad "G17" smd circle
			(at -15 -1.5 90)
			(size 0.5 0.5)
			(layers "F.Cu" "F.Mask" "F.Paste")
			(net 1 "GND")
			(pinfunction "GND")
			(pintype "passive")
		)
		(pad "G18" smd circle
			(at -14.1 -1.5 90)
			(size 0.5 0.5)
			(layers "F.Cu" "F.Mask" "F.Paste")
			(net 111 "/Expansion connector/I2S3.FS")
			(pinfunction "GPIO57")
			(pintype "passive")
		)
		(pad "G19" smd circle
			(at -13.2 -1.5 90)
			(size 0.5 0.5)
			(layers "F.Cu" "F.Mask" "F.Paste")
			(net 114 "/Expansion connector/I2S3.SDIN")
			(pinfunction "GPIO58")
			(pintype "passive")
		)
		(pad "G20" smd circle
			(at -12.3 -1.5 90)
			(size 0.5 0.5)
			(layers "F.Cu" "F.Mask" "F.Paste")
			(net 1 "GND")
			(pinfunction "GND")
			(pintype "passive")
		)
		(pad "G21" smd circle
			(at -11 -1.5 90)
			(size 0.5 0.5)
			(layers "F.Cu" "F.Mask" "F.Paste")
			(net 1 "GND")
			(pinfunction "GND")
			(pintype "passive")
		)
		(pad "G22" smd circle
			(at -10.1 -1.5 90)
			(size 0.5 0.5)
			(layers "F.Cu" "F.Mask" "F.Paste")
			(net 662 "/SoM_IO2/USBSS2.TX-")
			(pinfunction "UPHY_TX2_N")
			(pintype "output")
		)
		(pad "G23" smd circle
			(at -9.2 -1.5 90)
			(size 0.5 0.5)
			(layers "F.Cu" "F.Mask" "F.Paste")
			(net 684 "/SoM_IO2/USBSS2.TX+")
			(pinfunction "UPHY_TX2_P")
			(pintype "output")
		)
		(pad "G24" smd circle
			(at -8.3 -1.5 90)
			(size 0.5 0.5)
			(layers "F.Cu" "F.Mask" "F.Paste")
			(net 1 "GND")
			(pinfunction "GND")
			(pintype "passive")
		)
		(pad "G25" smd circle
			(at -7 -1.5 90)
			(size 0.5 0.5)
			(layers "F.Cu" "F.Mask" "F.Paste")
			(net 1 "GND")
			(pinfunction "GND")
			(pintype "passive")
		)
		(pad "G26" smd circle
			(at -6.1 -1.5 90)
			(size 0.5 0.5)
			(layers "F.Cu" "F.Mask" "F.Paste")
			(net 435 "/M.2/PCIe_{C5x4}.TX2-")
			(pinfunction "UPHY_TX10_N")
			(pintype "output")
		)
		(pad "G27" smd circle
			(at -5.2 -1.5 90)
			(size 0.5 0.5)
			(layers "F.Cu" "F.Mask" "F.Paste")
			(net 400 "/M.2/PCIe_{C5x4}.TX2+")
			(pinfunction "UPHY_TX10_P")
			(pintype "output")
		)
		(pad "G28" smd circle
			(at -4.3 -1.5 90)
			(size 0.5 0.5)
			(layers "F.Cu" "F.Mask" "F.Paste")
			(net 1 "GND")
			(pinfunction "GND")
			(pintype "passive")
		)
		(pad "G29" smd circle
			(at -3 -1.5 90)
			(size 0.5 0.5)
			(layers "F.Cu" "F.Mask" "F.Paste")
			(net 1 "GND")
			(pinfunction "GND")
			(pintype "passive")
		)
		(pad "G30" smd circle
			(at -2.1 -1.5 90)
			(size 0.5 0.5)
			(layers "F.Cu" "F.Mask" "F.Paste")
			(net 604 "unconnected-(J1B-UPHY_TX14_N-PadG30)")
			(pinfunction "UPHY_TX14_N")
			(pintype "output+no_connect")
		)
		(pad "G31" smd circle
			(at -1.2 -1.5 90)
			(size 0.5 0.5)
			(layers "F.Cu" "F.Mask" "F.Paste")
			(net 693 "unconnected-(J1B-UPHY_TX14_P-PadG31)")
			(pinfunction "UPHY_TX14_P")
			(pintype "output+no_connect")
		)
		(pad "G32" smd circle
			(at -0.3 -1.5 90)
			(size 0.5 0.5)
			(layers "F.Cu" "F.Mask" "F.Paste")
			(net 1 "GND")
			(pinfunction "GND")
			(pintype "passive")
		)
		(pad "G33" smd circle
			(at 1 -1.5 90)
			(size 0.5 0.5)
			(layers "F.Cu" "F.Mask" "F.Paste")
			(net 1 "GND")
			(pinfunction "GND")
			(pintype "passive")
		)
		(pad "G34" smd circle
			(at 1.9 -1.5 90)
			(size 0.5 0.5)
			(layers "F.Cu" "F.Mask" "F.Paste")
			(net 16 "/M.2/PCIe_{C1x1}.TX0-")
			(pinfunction "UPHY_TX3_N")
			(pintype "output")
		)
		(pad "G35" smd circle
			(at 2.8 -1.5 90)
			(size 0.5 0.5)
			(layers "F.Cu" "F.Mask" "F.Paste")
			(net 15 "/M.2/PCIe_{C1x1}.TX0+")
			(pinfunction "UPHY_TX3_P")
			(pintype "output")
		)
		(pad "G36" smd circle
			(at 3.7 -1.5 90)
			(size 0.5 0.5)
			(layers "F.Cu" "F.Mask" "F.Paste")
			(net 1 "GND")
			(pinfunction "GND")
			(pintype "passive")
		)
		(pad "G37" smd circle
			(at 5 -1.5 90)
			(size 0.5 0.5)
			(layers "F.Cu" "F.Mask" "F.Paste")
			(net 1 "GND")
			(pinfunction "GND")
			(pintype "passive")
		)
		(pad "G38" smd circle
			(at 5.9 -1.5 90)
			(size 0.5 0.5)
			(layers "F.Cu" "F.Mask" "F.Paste")
			(net 142 "/Expansion connector/CAN0.DOUT")
			(pinfunction "CAN0_DOUT")
			(pintype "output")
		)
		(pad "G39" smd circle
			(at 6.8 -1.5 90)
			(size 0.5 0.5)
			(layers "F.Cu" "F.Mask" "F.Paste")
			(net 105 "/Expansion connector/CAN0.DIN")
			(pinfunction "CAN0_DIN")
			(pintype "input")
		)
		(pad "G40" smd circle
			(at 7.7 -1.5 90)
			(size 0.5 0.5)
			(layers "F.Cu" "F.Mask" "F.Paste")
			(net 1 "GND")
			(pinfunction "GND")
			(pintype "passive")
		)
		(pad "G41" smd circle
			(at 8.6 -1.5 90)
			(size 0.5 0.5)
			(layers "F.Cu" "F.Mask" "F.Paste")
			(net 77 "/CSI/CAM1.CSI1_D0+")
			(pinfunction "CSI1_D0_P")
			(pintype "input")
		)
		(pad "G42" smd circle
			(at 9.5 -1.5 90)
			(size 0.5 0.5)
			(layers "F.Cu" "F.Mask" "F.Paste")
			(net 134 "/CSI/CAM1.CSI1_D0-")
			(pinfunction "CSI1_D0_N")
			(pintype "input")
		)
		(pad "G43" smd circle
			(at 10.4 -1.5 90)
			(size 0.5 0.5)
			(layers "F.Cu" "F.Mask" "F.Paste")
			(net 1 "GND")
			(pinfunction "GND")
			(pintype "passive")
		)
		(pad "G44" smd circle
			(at 11.3 -1.5 90)
			(size 0.5 0.5)
			(layers "F.Cu" "F.Mask" "F.Paste")
			(net 161 "/CSI/CAM0.CSI3_D1+")
			(pinfunction "CSI3_D1_P")
			(pintype "input")
		)
		(pad "G45" smd circle
			(at 12.2 -1.5 90)
			(size 0.5 0.5)
			(layers "F.Cu" "F.Mask" "F.Paste")
			(net 154 "/CSI/CAM0.CSI3_D1-")
			(pinfunction "CSI3_D1_N")
			(pintype "input")
		)
		(pad "G46" smd circle
			(at 13.1 -1.5 90)
			(size 0.5 0.5)
			(layers "F.Cu" "F.Mask" "F.Paste")
			(net 1 "GND")
			(pinfunction "GND")
			(pintype "passive")
		)
		(pad "G47" smd circle
			(at 14 -1.5 90)
			(size 0.5 0.5)
			(layers "F.Cu" "F.Mask" "F.Paste")
			(net 122 "/CSI/CAM2.CSI4_D0-")
			(pinfunction "CSI4_D0_N")
			(pintype "input")
		)
		(pad "G48" smd circle
			(at 14.9 -1.5 90)
			(size 0.5 0.5)
			(layers "F.Cu" "F.Mask" "F.Paste")
			(net 144 "/CSI/CAM2.CSI4_D0+")
			(pinfunction "CSI4_D0_P")
			(pintype "input")
		)
		(pad "G49" smd circle
			(at 15.8 -1.5 90)
			(size 0.5 0.5)
			(layers "F.Cu" "F.Mask" "F.Paste")
			(net 1 "GND")
			(pinfunction "GND")
			(pintype "passive")
		)
		(pad "G50" smd circle
			(at 16.7 -1.5 90)
			(size 0.5 0.5)
			(layers "F.Cu" "F.Mask" "F.Paste")
			(net 1249 "/SoM_IO2/DP1.TX1_C-")
			(pinfunction "DP1_D1_HDMI_D1_N")
			(pintype "output")
		)
		(pad "G51" smd circle
			(at 17.6 -1.5 90)
			(size 0.5 0.5)
			(layers "F.Cu" "F.Mask" "F.Paste")
			(net 1209 "/SoM_IO2/DP1.TX1_C+")
			(pinfunction "DP1_D1_HDMI_D1_P")
			(pintype "output")
		)
		(pad "G52" smd circle
			(at 18.5 -1.5 90)
			(size 0.5 0.5)
			(layers "F.Cu" "F.Mask" "F.Paste")
			(net 1 "GND")
			(pinfunction "GND")
			(pintype "passive")
		)
		(pad "G53" smd circle
			(at 19.4 -1.5 90)
			(size 0.5 0.5)
			(layers "F.Cu" "F.Mask" "F.Paste")
			(net 1088 "/SoM_IO2/DP0.AUX_C+")
			(pinfunction "DP_AUX_CH0_P")
			(pintype "bidirectional")
		)
		(pad "G54" smd circle
			(at 20.3 -1.5 90)
			(size 0.5 0.5)
			(layers "F.Cu" "F.Mask" "F.Paste")
			(net 1112 "/SoM_IO2/DP0.AUX_C-")
			(pinfunction "DP_AUX_CH0_N")
			(pintype "bidirectional")
		)
		(pad "G55" smd circle
			(at 21.2 -1.5 90)
			(size 0.5 0.5)
			(layers "F.Cu" "F.Mask" "F.Paste")
			(net 747 "unconnected-(J1C-GPIO23-PadG55)")
			(pinfunction "GPIO23")
			(pintype "passive+no_connect")
		)
		(pad "G56" smd circle
			(at 22.1 -1.5 90)
			(size 0.5 0.5)
			(layers "F.Cu" "F.Mask" "F.Paste")
			(net 49 "/Expansion connector/SPI3.MOSI")
			(pinfunction "SPI3_MOSI")
			(pintype "bidirectional")
		)
		(pad "G57" smd circle
			(at 23 -1.5 90)
			(size 0.5 0.5)
			(layers "F.Cu" "F.Mask" "F.Paste")
			(net 1 "GND")
			(pinfunction "GND")
			(pintype "passive")
		)
		(pad "G58" smd circle
			(at 23.9 -1.5 90)
			(size 0.5 0.5)
			(layers "F.Cu" "F.Mask" "F.Paste")
			(net 82 "/Expansion connector/UART2.RTS")
			(pinfunction "UART2_RTS")
			(pintype "output")
		)
		(pad "G59" smd circle
			(at 24.8 -1.5 90)
			(size 0.5 0.5)
			(layers "F.Cu" "F.Mask" "F.Paste")
			(net 673 "Net-(J1A-THERM_SHDN_REQ_N)")
			(pinfunction "THERM_SHDN_REQ_N")
			(pintype "output")
		)
		(pad "G60" smd circle
			(at 25.7 -1.5 90)
			(size 0.5 0.5)
			(layers "F.Cu" "F.Mask" "F.Paste")
			(net 652 "/SoM_IO2/NVDBG_SEL")
			(pinfunction "NVDBG_SEL")
			(pintype "passive")
		)
		(pad "G61" smd circle
			(at 26.6 -1.5 90)
			(size 0.5 0.5)
			(layers "F.Cu" "F.Mask" "F.Paste")
			(net 627 "/SoM_IO2/JTAG_TRST_N")
			(pinfunction "JTAG_TRST_N")
			(pintype "passive")
		)
		(pad "G62" smd circle
			(at 27.5 -1.5 90)
			(size 0.5 0.5)
			(layers "F.Cu" "F.Mask" "F.Paste")
			(net 1 "GND")
			(pinfunction "GND")
			(pintype "passive")
		)
		(pad "G63" smd circle
			(at 28.4 -1.5 90)
			(size 0.5 0.5)
			(layers "F.Cu" "F.Mask" "F.Paste")
			(net 12 "SYS_VIN_HV")
			(pinfunction "SYS_VIN_HV")
			(pintype "passive")
		)
		(pad "G64" smd circle
			(at 29.3 -1.5 90)
			(size 0.5 0.5)
			(layers "F.Cu" "F.Mask" "F.Paste")
			(net 12 "SYS_VIN_HV")
			(pinfunction "SYS_VIN_HV")
			(pintype "passive")
		)
		(pad "G65" smd circle
			(at 30.2 -1.5 90)
			(size 0.5 0.5)
			(layers "F.Cu" "F.Mask" "F.Paste")
			(net 12 "SYS_VIN_HV")
			(pinfunction "SYS_VIN_HV")
			(pintype "passive")
		)
		(pad "H1" smd circle
			(at -30 -3 90)
			(size 0.5 0.5)
			(layers "F.Cu" "F.Mask" "F.Paste")
			(net 12 "SYS_VIN_HV")
			(pinfunction "SYS_VIN_HV")
			(pintype "passive")
		)
		(pad "H2" smd circle
			(at -29.1 -3 90)
			(size 0.5 0.5)
			(layers "F.Cu" "F.Mask" "F.Paste")
			(net 12 "SYS_VIN_HV")
			(pinfunction "SYS_VIN_HV")
			(pintype "passive")
		)
		(pad "H3" smd circle
			(at -28.2 -3 90)
			(size 0.5 0.5)
			(layers "F.Cu" "F.Mask" "F.Paste")
			(net 12 "SYS_VIN_HV")
			(pinfunction "SYS_VIN_HV")
			(pintype "passive")
		)
		(pad "H4" smd circle
			(at -27.3 -3 90)
			(size 0.5 0.5)
			(layers "F.Cu" "F.Mask" "F.Paste")
			(net 1 "GND")
			(pinfunction "GND")
			(pintype "passive")
		)
		(pad "H5" smd circle
			(at -26.4 -3 90)
			(size 0.5 0.5)
			(layers "F.Cu" "F.Mask" "F.Paste")
			(net 464 "/Expansion connector/GPIO.20")
			(pinfunction "GPIO59")
			(pintype "passive")
		)
		(pad "H6" smd circle
			(at -25.5 -3 90)
			(size 0.5 0.5)
			(layers "F.Cu" "F.Mask" "F.Paste")
			(net 687 "unconnected-(J1I-UART4_RX-PadH6)")
			(pinfunction "UART4_RX")
			(pintype "input+no_connect")
		)
		(pad "H7" smd circle
			(at -24.6 -3 90)
			(size 0.5 0.5)
			(layers "F.Cu" "F.Mask" "F.Paste")
			(net 1 "GND")
			(pinfunction "GND")
			(pintype "passive")
		)
		(pad "H8" smd circle
			(at -23.7 -3 90)
			(size 0.5 0.5)
			(layers "F.Cu" "F.Mask" "F.Paste")
			(net 76 "/SoM_IO/I2S_{M.2}.SDIN")
			(pinfunction "I2S1_SDIN")
			(pintype "input")
		)
		(pad "H9" smd circle
			(at -22.8 -3 90)
			(size 0.5 0.5)
			(layers "F.Cu" "F.Mask" "F.Paste")
			(net 362 "/Expansion connector/GPIO.MCLK01")
			(pinfunction "MCLK01")
			(pintype "output")
		)
		(pad "H10" smd circle
			(at -21.9 -3 90)
			(size 0.5 0.5)
			(layers "F.Cu" "F.Mask" "F.Paste")
			(net 714 "unconnected-(J1C-PEX_C4_RST_N-PadH10)")
			(pinfunction "PEX_C4_RST_N")
			(pintype "output+no_connect")
		)
		(pad "H11" smd circle
			(at -21 -3 90)
			(size 0.5 0.5)
			(layers "F.Cu" "F.Mask" "F.Paste")
			(net 1 "GND")
			(pinfunction "GND")
			(pintype "passive")
		)
		(pad "H12" smd circle
			(at -20.1 -3 90)
			(size 0.5 0.5)
			(layers "F.Cu" "F.Mask" "F.Paste")
			(net 467 "/Expansion connector/PCIe_{C3x2}.TX1+")
			(pinfunction "UPHY_TX7_P")
			(pintype "output")
		)
		(pad "H13" smd circle
			(at -19.2 -3 90)
			(size 0.5 0.5)
			(layers "F.Cu" "F.Mask" "F.Paste")
			(net 519 "/Expansion connector/PCIe_{C3x2}.TX1-")
			(pinfunction "UPHY_TX7_N")
			(pintype "output")
		)
		(pad "H14" smd circle
			(at -18.3 -3 90)
			(size 0.5 0.5)
			(layers "F.Cu" "F.Mask" "F.Paste")
			(net 1 "GND")
			(pinfunction "GND")
			(pintype "passive")
		)
		(pad "H15" smd circle
			(at -17 -3 90)
			(size 0.5 0.5)
			(layers "F.Cu" "F.Mask" "F.Paste")
			(net 1 "GND")
			(pinfunction "GND")
			(pintype "passive")
		)
		(pad "H16" smd circle
			(at -16.1 -3 90)
			(size 0.5 0.5)
			(layers "F.Cu" "F.Mask" "F.Paste")
			(net 165 "/Expansion connector/I2S3.CLK")
			(pinfunction "GPIO61")
			(pintype "passive")
		)
		(pad "H17" smd circle
			(at -15.2 -3 90)
			(size 0.5 0.5)
			(layers "F.Cu" "F.Mask" "F.Paste")
			(net 141 "/Expansion connector/I2S3.SDOUT")
			(pinfunction "GPIO62")
			(pintype "passive")
		)
		(pad "H18" smd circle
			(at -14.3 -3 90)
			(size 0.5 0.5)
			(layers "F.Cu" "F.Mask" "F.Paste")
			(net 1 "GND")
			(pinfunction "GND")
			(pintype "passive")
		)
		(pad "H19" smd circle
			(at -13 -3 90)
			(size 0.5 0.5)
			(layers "F.Cu" "F.Mask" "F.Paste")
			(net 1 "GND")
			(pinfunction "GND")
			(pintype "passive")
		)
		(pad "H20" smd circle
			(at -12.1 -3 90)
			(size 0.5 0.5)
			(layers "F.Cu" "F.Mask" "F.Paste")
			(net 768 "unconnected-(J1B-UPHY_TX5_P-PadH20)")
			(pinfunction "UPHY_TX5_P")
			(pintype "output+no_connect")
		)
		(pad "H21" smd circle
			(at -11.2 -3 90)
			(size 0.5 0.5)
			(layers "F.Cu" "F.Mask" "F.Paste")
			(net 672 "unconnected-(J1B-UPHY_TX5_N-PadH21)")
			(pinfunction "UPHY_TX5_N")
			(pintype "output+no_connect")
		)
		(pad "H22" smd circle
			(at -10.3 -3 90)
			(size 0.5 0.5)
			(layers "F.Cu" "F.Mask" "F.Paste")
			(net 1 "GND")
			(pinfunction "GND")
			(pintype "passive")
		)
		(pad "H23" smd circle
			(at -9 -3 90)
			(size 0.5 0.5)
			(layers "F.Cu" "F.Mask" "F.Paste")
			(net 1 "GND")
			(pinfunction "GND")
			(pintype "passive")
		)
		(pad "H24" smd circle
			(at -8.1 -3 90)
			(size 0.5 0.5)
			(layers "F.Cu" "F.Mask" "F.Paste")
			(net 382 "/M.2/PCIe_{C5x4}.TX0+")
			(pinfunction "UPHY_TX8_P")
			(pintype "output")
		)
		(pad "H25" smd circle
			(at -7.2 -3 90)
			(size 0.5 0.5)
			(layers "F.Cu" "F.Mask" "F.Paste")
			(net 411 "/M.2/PCIe_{C5x4}.TX0-")
			(pinfunction "UPHY_TX8_N")
			(pintype "output")
		)
		(pad "H26" smd circle
			(at -6.3 -3 90)
			(size 0.5 0.5)
			(layers "F.Cu" "F.Mask" "F.Paste")
			(net 1 "GND")
			(pinfunction "GND")
			(pintype "passive")
		)
		(pad "H27" smd circle
			(at -5 -3 90)
			(size 0.5 0.5)
			(layers "F.Cu" "F.Mask" "F.Paste")
			(net 1 "GND")
			(pinfunction "GND")
			(pintype "passive")
		)
		(pad "H28" smd circle
			(at -4.1 -3 90)
			(size 0.5 0.5)
			(layers "F.Cu" "F.Mask" "F.Paste")
			(net 106 "/SFP/SFI.TX+")
			(pinfunction "UPHY_TX12_P")
			(pintype "output")
		)
		(pad "H29" smd circle
			(at -3.2 -3 90)
			(size 0.5 0.5)
			(layers "F.Cu" "F.Mask" "F.Paste")
			(net 132 "/SFP/SFI.TX-")
			(pinfunction "UPHY_TX12_N")
			(pintype "output")
		)
		(pad "H30" smd circle
			(at -2.3 -3 90)
			(size 0.5 0.5)
			(layers "F.Cu" "F.Mask" "F.Paste")
			(net 1 "GND")
			(pinfunction "GND")
			(pintype "passive")
		)
		(pad "H31" smd circle
			(at -1 -3 90)
			(size 0.5 0.5)
			(layers "F.Cu" "F.Mask" "F.Paste")
			(net 1 "GND")
			(pinfunction "GND")
			(pintype "passive")
		)
		(pad "H32" smd circle
			(at -0.1 -3 90)
			(size 0.5 0.5)
			(layers "F.Cu" "F.Mask" "F.Paste")
			(net 1267 "/SoM_IO2/DP3.TX3_C+")
			(pinfunction "DP3_D3_HDMI_CK_P")
			(pintype "output")
		)
		(pad "H33" smd circle
			(at 0.8 -3 90)
			(size 0.5 0.5)
			(layers "F.Cu" "F.Mask" "F.Paste")
			(net 1271 "/SoM_IO2/DP3.TX3_C-")
			(pinfunction "DP3_D3_HDMI_CK_N")
			(pintype "output")
		)
		(pad "H34" smd circle
			(at 1.7 -3 90)
			(size 0.5 0.5)
			(layers "F.Cu" "F.Mask" "F.Paste")
			(net 1 "GND")
			(pinfunction "GND")
			(pintype "passive")
		)
		(pad "H35" smd circle
			(at 3 -3 90)
			(size 0.5 0.5)
			(layers "F.Cu" "F.Mask" "F.Paste")
			(net 1 "GND")
			(pinfunction "GND")
			(pintype "passive")
		)
		(pad "H36" smd circle
			(at 3.9 -3 90)
			(size 0.5 0.5)
			(layers "F.Cu" "F.Mask" "F.Paste")
			(net 50 "/Expansion connector/CAN1.DIN")
			(pinfunction "CAN1_DIN")
			(pintype "input")
		)
		(pad "H37" smd circle
			(at 4.8 -3 90)
			(size 0.5 0.5)
			(layers "F.Cu" "F.Mask" "F.Paste")
			(net 81 "/Expansion connector/CAN1.DOUT")
			(pinfunction "CAN1_DOUT")
			(pintype "output")
		)
		(pad "H38" smd circle
			(at 5.7 -3 90)
			(size 0.5 0.5)
			(layers "F.Cu" "F.Mask" "F.Paste")
			(net 1 "GND")
			(pinfunction "GND")
			(pintype "passive")
		)
		(pad "H39" smd circle
			(at 7 -3 90)
			(size 0.5 0.5)
			(layers "F.Cu" "F.Mask" "F.Paste")
			(net 1 "GND")
			(pinfunction "GND")
			(pintype "passive")
		)
		(pad "H40" smd circle
			(at 7.9 -3 90)
			(size 0.5 0.5)
			(layers "F.Cu" "F.Mask" "F.Paste")
			(net 99 "unconnected-(J1A-MID1-PadH40)")
			(pinfunction "MID1")
			(pintype "passive+no_connect")
		)
		(pad "H41" smd circle
			(at 8.8 -3 90)
			(size 0.5 0.5)
			(layers "F.Cu" "F.Mask" "F.Paste")
			(net 1 "GND")
			(pinfunction "GND")
			(pintype "passive")
		)
		(pad "H42" smd circle
			(at 9.7 -3 90)
			(size 0.5 0.5)
			(layers "F.Cu" "F.Mask" "F.Paste")
			(net 83 "unconnected-(J1F-CSI1_CLK_N-PadH42)")
			(pinfunction "CSI1_CLK_N")
			(pintype "input+no_connect")
		)
		(pad "H43" smd circle
			(at 10.6 -3 90)
			(size 0.5 0.5)
			(layers "F.Cu" "F.Mask" "F.Paste")
			(net 159 "unconnected-(J1F-CSI1_CLK_P-PadH43)")
			(pinfunction "CSI1_CLK_P")
			(pintype "input+no_connect")
		)
		(pad "H44" smd circle
			(at 11.5 -3 90)
			(size 0.5 0.5)
			(layers "F.Cu" "F.Mask" "F.Paste")
			(net 1 "GND")
			(pinfunction "GND")
			(pintype "passive")
		)
		(pad "H45" smd circle
			(at 12.4 -3 90)
			(size 0.5 0.5)
			(layers "F.Cu" "F.Mask" "F.Paste")
			(net 62 "/CSI/CAM3.CSI6_D1-")
			(pinfunction "CSI6_D1_N")
			(pintype "input")
		)
		(pad "H46" smd circle
			(at 13.3 -3 90)
			(size 0.5 0.5)
			(layers "F.Cu" "F.Mask" "F.Paste")
			(net 70 "/CSI/CAM3.CSI6_D1+")
			(pinfunction "CSI6_D1_P")
			(pintype "input")
		)
		(pad "H47" smd circle
			(at 14.2 -3 90)
			(size 0.5 0.5)
			(layers "F.Cu" "F.Mask" "F.Paste")
			(net 1 "GND")
			(pinfunction "GND")
			(pintype "passive")
		)
		(pad "H48" smd circle
			(at 15.1 -3 90)
			(size 0.5 0.5)
			(layers "F.Cu" "F.Mask" "F.Paste")
			(net 1248 "/SoM_IO2/DP1.TX0_C-")
			(pinfunction "DP1_D0_HDMI_D2_N")
			(pintype "output")
		)
		(pad "H49" smd circle
			(at 16 -3 90)
			(size 0.5 0.5)
			(layers "F.Cu" "F.Mask" "F.Paste")
			(net 1191 "/SoM_IO2/DP1.TX0_C+")
			(pinfunction "DP1_D0_HDMI_D2_P")
			(pintype "output")
		)
		(pad "H50" smd circle
			(at 16.9 -3 90)
			(size 0.5 0.5)
			(layers "F.Cu" "F.Mask" "F.Paste")
			(net 1 "GND")
			(pinfunction "GND")
			(pintype "passive")
		)
		(pad "H51" smd circle
			(at 17.8 -3 90)
			(size 0.5 0.5)
			(layers "F.Cu" "F.Mask" "F.Paste")
			(net 899 "unconnected-(J1C-GPIO26-PadH51)")
			(pinfunction "GPIO26")
			(pintype "passive+no_connect")
		)
		(pad "H52" smd circle
			(at 18.7 -3 90)
			(size 0.5 0.5)
			(layers "F.Cu" "F.Mask" "F.Paste")
			(net 319 "/Expansion connector/FMC_PRSNT_M2C_L")
			(pinfunction "GPIO27")
			(pintype "passive")
		)
		(pad "H53" smd circle
			(at 19.6 -3 90)
			(size 0.5 0.5)
			(layers "F.Cu" "F.Mask" "F.Paste")
			(net 321 "/Expansion connector/GPIO.MCLK03")
			(pinfunction "MCLK03")
			(pintype "passive")
		)
		(pad "H54" smd circle
			(at 20.5 -3 90)
			(size 0.5 0.5)
			(layers "F.Cu" "F.Mask" "F.Paste")
			(net 243 "/SoM_IO/UART1.CTS")
			(pinfunction "UART1_CTS")
			(pintype "input")
		)
		(pad "H55" smd circle
			(at 21.4 -3 90)
			(size 0.5 0.5)
			(layers "F.Cu" "F.Mask" "F.Paste")
			(net 555 "unconnected-(J1D-MCLK04-PadH55)")
			(pinfunction "MCLK04")
			(pintype "bidirectional+no_connect")
		)
		(pad "H56" smd circle
			(at 22.3 -3 90)
			(size 0.5 0.5)
			(layers "F.Cu" "F.Mask" "F.Paste")
			(net 1 "GND")
			(pinfunction "GND")
			(pintype "passive")
		)
		(pad "H57" smd circle
			(at 23.2 -3 90)
			(size 0.5 0.5)
			(layers "F.Cu" "F.Mask" "F.Paste")
			(net 121 "/Expansion connector/UART5.CTS")
			(pinfunction "UART5_CTS")
			(pintype "input")
		)
		(pad "H58" smd circle
			(at 24.1 -3 90)
			(size 0.5 0.5)
			(layers "F.Cu" "F.Mask" "F.Paste")
			(net 151 "/Expansion connector/UART5.RX")
			(pinfunction "UART5_RX")
			(pintype "input")
		)
		(pad "H59" smd circle
			(at 25 -3 90)
			(size 0.5 0.5)
			(layers "F.Cu" "F.Mask" "F.Paste")
			(net 606 "/SoM_IO2/NVJTAG_SEL")
			(pinfunction "NVJTAG_SEL")
			(pintype "passive")
		)
		(pad "H60" smd circle
			(at 25.9 -3 90)
			(size 0.5 0.5)
			(layers "F.Cu" "F.Mask" "F.Paste")
			(net 758 "Net-(J1A-GPIO31)")
			(pinfunction "GPIO31")
			(pintype "passive")
		)
		(pad "H61" smd circle
			(at 26.8 -3 90)
			(size 0.5 0.5)
			(layers "F.Cu" "F.Mask" "F.Paste")
			(net 783 "/Expansion connector/CAN3.DOUT")
			(pinfunction "CAN3_DOUT")
			(pintype "output")
		)
		(pad "H62" smd circle
			(at 27.7 -3 90)
			(size 0.5 0.5)
			(layers "F.Cu" "F.Mask" "F.Paste")
			(net 496 "/SoM_IO/UART3_DEBUG_TX_1V8")
			(pinfunction "UART3_TX_DEBUG")
			(pintype "output")
		)
		(pad "H63" smd circle
			(at 28.6 -3 90)
			(size 0.5 0.5)
			(layers "F.Cu" "F.Mask" "F.Paste")
			(net 1 "GND")
			(pinfunction "GND")
			(pintype "passive")
		)
		(pad "H64" smd circle
			(at 29.5 -3 90)
			(size 0.5 0.5)
			(layers "F.Cu" "F.Mask" "F.Paste")
			(net 12 "SYS_VIN_HV")
			(pinfunction "SYS_VIN_HV")
			(pintype "passive")
		)
		(pad "H65" smd circle
			(at 30.4 -3 90)
			(size 0.5 0.5)
			(layers "F.Cu" "F.Mask" "F.Paste")
			(net 12 "SYS_VIN_HV")
			(pinfunction "SYS_VIN_HV")
			(pintype "passive")
		)
		(pad "J1" smd circle
			(at -30.2 -4.5 90)
			(size 0.5 0.5)
			(layers "F.Cu" "F.Mask" "F.Paste")
			(net 12 "SYS_VIN_HV")
			(pinfunction "SYS_VIN_HV")
			(pintype "passive")
		)
		(pad "J2" smd circle
			(at -29.3 -4.5 90)
			(size 0.5 0.5)
			(layers "F.Cu" "F.Mask" "F.Paste")
			(net 12 "SYS_VIN_HV")
			(pinfunction "SYS_VIN_HV")
			(pintype "passive")
		)
		(pad "J3" smd circle
			(at -28.4 -4.5 90)
			(size 0.5 0.5)
			(layers "F.Cu" "F.Mask" "F.Paste")
			(net 1 "GND")
			(pinfunction "GND")
			(pintype "passive")
		)
		(pad "J4" smd circle
			(at -27.5 -4.5 90)
			(size 0.5 0.5)
			(layers "F.Cu" "F.Mask" "F.Paste")
			(net 330 "/Expansion connector/FMC_PG_M2C")
			(pinfunction "GPIO01")
			(pintype "passive")
		)
		(pad "J5" smd circle
			(at -26.6 -4.5 90)
			(size 0.5 0.5)
			(layers "F.Cu" "F.Mask" "F.Paste")
			(net 861 "/Expansion connector/GPIO.27")
			(pinfunction "GPIO63")
			(pintype "passive")
		)
		(pad "J6" smd circle
			(at -25.7 -4.5 90)
			(size 0.5 0.5)
			(layers "F.Cu" "F.Mask" "F.Paste")
			(net 1244 "/SoM_IO/USBC2_VBUS_DET_1V8")
			(pinfunction "GPIO64")
			(pintype "passive")
		)
		(pad "J7" smd circle
			(at -24.8 -4.5 90)
			(size 0.5 0.5)
			(layers "F.Cu" "F.Mask" "F.Paste")
			(net 780 "/SoM_IO/~{PDC_I2C1_IRQ}_1V8")
			(pinfunction "GPIO65")
			(pintype "passive")
		)
		(pad "J8" smd circle
			(at -23.9 -4.5 90)
			(size 0.5 0.5)
			(layers "F.Cu" "F.Mask" "F.Paste")
			(net 1 "GND")
			(pinfunction "GND")
			(pintype "passive")
		)
		(pad "J9" smd circle
			(at -23 -4.5 90)
			(size 0.5 0.5)
			(layers "F.Cu" "F.Mask" "F.Paste")
			(net 569 "/Expansion connector/PCIe_{C3x2}.~{RST}")
			(pinfunction "PEX_C3_RST_N")
			(pintype "output")
		)
		(pad "J10" smd circle
			(at -22.1 -4.5 90)
			(size 0.5 0.5)
			(layers "F.Cu" "F.Mask" "F.Paste")
			(net 755 "unconnected-(J1G-FSI_GPIO21-PadJ10)")
			(pinfunction "FSI_GPIO21")
			(pintype "passive+no_connect")
		)
		(pad "J11" smd circle
			(at -21.2 -4.5 90)
			(size 0.5 0.5)
			(layers "F.Cu" "F.Mask" "F.Paste")
			(net 314 "unconnected-(J1D-FSI_GPIO29-PadJ11)")
			(pinfunction "FSI_GPIO29")
			(pintype "passive+no_connect")
		)
		(pad "J12" smd circle
			(at -20.3 -4.5 90)
			(size 0.5 0.5)
			(layers "F.Cu" "F.Mask" "F.Paste")
			(net 1 "GND")
			(pinfunction "GND")
			(pintype "passive")
		)
		(pad "J13" smd circle
			(at -19 -4.5 90)
			(size 0.5 0.5)
			(layers "F.Cu" "F.Mask" "F.Paste")
			(net 1 "GND")
			(pinfunction "GND")
			(pintype "passive")
		)
		(pad "J14" smd circle
			(at -18.1 -4.5 90)
			(size 0.5 0.5)
			(layers "F.Cu" "F.Mask" "F.Paste")
			(net 1255 "/SoM_IO2/DP2.TX1_C+")
			(pinfunction "DP2_D1_HDMI_D1_P")
			(pintype "output")
		)
		(pad "J15" smd circle
			(at -17.2 -4.5 90)
			(size 0.5 0.5)
			(layers "F.Cu" "F.Mask" "F.Paste")
			(net 1259 "/SoM_IO2/DP2.TX1_C-")
			(pinfunction "DP2_D1_HDMI_D1_N")
			(pintype "output")
		)
		(pad "J16" smd circle
			(at -16.3 -4.5 90)
			(size 0.5 0.5)
			(layers "F.Cu" "F.Mask" "F.Paste")
			(net 1 "GND")
			(pinfunction "GND")
			(pintype "passive")
		)
		(pad "J17" smd circle
			(at -15 -4.5 90)
			(size 0.5 0.5)
			(layers "F.Cu" "F.Mask" "F.Paste")
			(net 1 "GND")
			(pinfunction "GND")
			(pintype "passive")
		)
		(pad "J18" smd circle
			(at -14.1 -4.5 90)
			(size 0.5 0.5)
			(layers "F.Cu" "F.Mask" "F.Paste")
			(net 849 "/Expansion connector/GPIO.18")
			(pinfunction "GPIO50")
			(pintype "passive")
		)
		(pad "J19" smd circle
			(at -13.2 -4.5 90)
			(size 0.5 0.5)
			(layers "F.Cu" "F.Mask" "F.Paste")
			(net 1294 "unconnected-(J1K-GPIO67-PadJ19)")
			(pinfunction "GPIO67")
			(pintype "passive+no_connect")
		)
		(pad "J20" smd circle
			(at -12.3 -4.5 90)
			(size 0.5 0.5)
			(layers "F.Cu" "F.Mask" "F.Paste")
			(net 1 "GND")
			(pinfunction "GND")
			(pintype "passive")
		)
		(pad "J21" smd circle
			(at -11 -4.5 90)
			(size 0.5 0.5)
			(layers "F.Cu" "F.Mask" "F.Paste")
			(net 1 "GND")
			(pinfunction "GND")
			(pintype "passive")
		)
		(pad "J22" smd circle
			(at -10.1 -4.5 90)
			(size 0.5 0.5)
			(layers "F.Cu" "F.Mask" "F.Paste")
			(net 311 "/SoM_IO2/USBSS1.TX+")
			(pinfunction "UPHY_TX1_P")
			(pintype "output")
		)
		(pad "J23" smd circle
			(at -9.2 -4.5 90)
			(size 0.5 0.5)
			(layers "F.Cu" "F.Mask" "F.Paste")
			(net 329 "/SoM_IO2/USBSS1.TX-")
			(pinfunction "UPHY_TX1_N")
			(pintype "output")
		)
		(pad "J24" smd circle
			(at -8.3 -4.5 90)
			(size 0.5 0.5)
			(layers "F.Cu" "F.Mask" "F.Paste")
			(net 1 "GND")
			(pinfunction "GND")
			(pintype "passive")
		)
		(pad "J25" smd circle
			(at -7 -4.5 90)
			(size 0.5 0.5)
			(layers "F.Cu" "F.Mask" "F.Paste")
			(net 1 "GND")
			(pinfunction "GND")
			(pintype "passive")
		)
		(pad "J26" smd circle
			(at -6.1 -4.5 90)
			(size 0.5 0.5)
			(layers "F.Cu" "F.Mask" "F.Paste")
			(net 410 "/M.2/PCIe_{C5x4}.TX3+")
			(pinfunction "UPHY_TX11_P")
			(pintype "output")
		)
		(pad "J27" smd circle
			(at -5.2 -4.5 90)
			(size 0.5 0.5)
			(layers "F.Cu" "F.Mask" "F.Paste")
			(net 439 "/M.2/PCIe_{C5x4}.TX3-")
			(pinfunction "UPHY_TX11_N")
			(pintype "output")
		)
		(pad "J28" smd circle
			(at -4.3 -4.5 90)
			(size 0.5 0.5)
			(layers "F.Cu" "F.Mask" "F.Paste")
			(net 1 "GND")
			(pinfunction "GND")
			(pintype "passive")
		)
		(pad "J29" smd circle
			(at -3 -4.5 90)
			(size 0.5 0.5)
			(layers "F.Cu" "F.Mask" "F.Paste")
			(net 1 "GND")
			(pinfunction "GND")
			(pintype "passive")
		)
		(pad "J30" smd circle
			(at -2.1 -4.5 90)
			(size 0.5 0.5)
			(layers "F.Cu" "F.Mask" "F.Paste")
			(net 582 "unconnected-(J1B-UPHY_TX15_P-PadJ30)")
			(pinfunction "UPHY_TX15_P")
			(pintype "output+no_connect")
		)
		(pad "J31" smd circle
			(at -1.2 -4.5 90)
			(size 0.5 0.5)
			(layers "F.Cu" "F.Mask" "F.Paste")
			(net 581 "unconnected-(J1B-UPHY_TX15_N-PadJ31)")
			(pinfunction "UPHY_TX15_N")
			(pintype "output+no_connect")
		)
		(pad "J32" smd circle
			(at -0.3 -4.5 90)
			(size 0.5 0.5)
			(layers "F.Cu" "F.Mask" "F.Paste")
			(net 1 "GND")
			(pinfunction "GND")
			(pintype "passive")
		)
		(pad "J33" smd circle
			(at 1 -4.5 90)
			(size 0.5 0.5)
			(layers "F.Cu" "F.Mask" "F.Paste")
			(net 1 "GND")
			(pinfunction "GND")
			(pintype "passive")
		)
		(pad "J34" smd circle
			(at 1.9 -4.5 90)
			(size 0.5 0.5)
			(layers "F.Cu" "F.Mask" "F.Paste")
			(net 1269 "/SoM_IO2/DP3.TX1_C-")
			(pinfunction "DP3_D1_HDMI_D1_N")
			(pintype "output")
		)
		(pad "J35" smd circle
			(at 2.8 -4.5 90)
			(size 0.5 0.5)
			(layers "F.Cu" "F.Mask" "F.Paste")
			(net 1265 "/SoM_IO2/DP3.TX1_C+")
			(pinfunction "DP3_D1_HDMI_D1_P")
			(pintype "output")
		)
		(pad "J36" smd circle
			(at 3.7 -4.5 90)
			(size 0.5 0.5)
			(layers "F.Cu" "F.Mask" "F.Paste")
			(net 1 "GND")
			(pinfunction "GND")
			(pintype "passive")
		)
		(pad "J37" smd circle
			(at 5 -4.5 90)
			(size 0.5 0.5)
			(layers "F.Cu" "F.Mask" "F.Paste")
			(net 1 "GND")
			(pinfunction "GND")
			(pintype "passive")
		)
		(pad "J38" smd circle
			(at 5.9 -4.5 90)
			(size 0.5 0.5)
			(layers "F.Cu" "F.Mask" "F.Paste")
			(net 779 "unconnected-(J1G-FSI_GPIO05-PadJ38)")
			(pinfunction "FSI_GPIO05")
			(pintype "passive+no_connect")
		)
		(pad "J39" smd circle
			(at 6.8 -4.5 90)
			(size 0.5 0.5)
			(layers "F.Cu" "F.Mask" "F.Paste")
			(net 774 "unconnected-(J1G-FSI_GPIO06-PadJ39)")
			(pinfunction "FSI_GPIO06")
			(pintype "passive+no_connect")
		)
		(pad "J40" smd circle
			(at 7.7 -4.5 90)
			(size 0.5 0.5)
			(layers "F.Cu" "F.Mask" "F.Paste")
			(net 1 "GND")
			(pinfunction "GND")
			(pintype "passive")
		)
		(pad "J41" smd circle
			(at 8.6 -4.5 90)
			(size 0.5 0.5)
			(layers "F.Cu" "F.Mask" "F.Paste")
			(net 93 "/CSI/CAM1.CSI1_D1+")
			(pinfunction "CSI1_D1_P")
			(pintype "input")
		)
		(pad "J42" smd circle
			(at 9.5 -4.5 90)
			(size 0.5 0.5)
			(layers "F.Cu" "F.Mask" "F.Paste")
			(net 143 "/CSI/CAM1.CSI1_D1-")
			(pinfunction "CSI1_D1_N")
			(pintype "input")
		)
		(pad "J43" smd circle
			(at 10.4 -4.5 90)
			(size 0.5 0.5)
			(layers "F.Cu" "F.Mask" "F.Paste")
			(net 1 "GND")
			(pinfunction "GND")
			(pintype "passive")
		)
		(pad "J44" smd circle
			(at 11.3 -4.5 90)
			(size 0.5 0.5)
			(layers "F.Cu" "F.Mask" "F.Paste")
			(net 53 "/CSI/CAM3.CSI6_CLK+")
			(pinfunction "CSI6_CLK_P")
			(pintype "input")
		)
		(pad "J45" smd circle
			(at 12.2 -4.5 90)
			(size 0.5 0.5)
			(layers "F.Cu" "F.Mask" "F.Paste")
			(net 116 "/CSI/CAM3.CSI6_CLK-")
			(pinfunction "CSI6_CLK_N")
			(pintype "input")
		)
		(pad "J46" smd circle
			(at 13.1 -4.5 90)
			(size 0.5 0.5)
			(layers "F.Cu" "F.Mask" "F.Paste")
			(net 1 "GND")
			(pinfunction "GND")
			(pintype "passive")
		)
		(pad "J47" smd circle
			(at 14 -4.5 90)
			(size 0.5 0.5)
			(layers "F.Cu" "F.Mask" "F.Paste")
			(net 1223 "/SoM_IO2/DP1.TX2_C+")
			(pinfunction "DP1_D2_HDMI_D0_P")
			(pintype "output")
		)
		(pad "J48" smd circle
			(at 14.9 -4.5 90)
			(size 0.5 0.5)
			(layers "F.Cu" "F.Mask" "F.Paste")
			(net 1250 "/SoM_IO2/DP1.TX2_C-")
			(pinfunction "DP1_D2_HDMI_D0_N")
			(pintype "output")
		)
		(pad "J49" smd circle
			(at 15.8 -4.5 90)
			(size 0.5 0.5)
			(layers "F.Cu" "F.Mask" "F.Paste")
			(net 1 "GND")
			(pinfunction "GND")
			(pintype "passive")
		)
		(pad "J50" smd circle
			(at 16.7 -4.5 90)
			(size 0.5 0.5)
			(layers "F.Cu" "F.Mask" "F.Paste")
			(net 497 "unconnected-(J1E-HDMI_CEC-PadJ50)")
			(pinfunction "HDMI_CEC")
			(pintype "bidirectional+no_connect")
		)
		(pad "J51" smd circle
			(at 17.6 -4.5 90)
			(size 0.5 0.5)
			(layers "F.Cu" "F.Mask" "F.Paste")
			(net 723 "unconnected-(J1I-GPIO24-PadJ51)")
			(pinfunction "GPIO24")
			(pintype "bidirectional+no_connect")
		)
		(pad "J52" smd circle
			(at 18.5 -4.5 90)
			(size 0.5 0.5)
			(layers "F.Cu" "F.Mask" "F.Paste")
			(net 317 "/SoM_IO/I2C0_SCL_1V8")
			(pinfunction "I2C0_CLK")
			(pintype "bidirectional")
		)
		(pad "J53" smd circle
			(at 19.4 -4.5 90)
			(size 0.5 0.5)
			(layers "F.Cu" "F.Mask" "F.Paste")
			(net 331 "/SoM_IO/I2C0_SDA_1V8")
			(pinfunction "I2C0_DAT")
			(pintype "bidirectional")
		)
		(pad "J54" smd circle
			(at 20.3 -4.5 90)
			(size 0.5 0.5)
			(layers "F.Cu" "F.Mask" "F.Paste")
			(net 416 "/Expansion connector/GPIO.MCLK02")
			(pinfunction "MCLK02")
			(pintype "bidirectional")
		)
		(pad "J55" smd circle
			(at 21.2 -4.5 90)
			(size 0.5 0.5)
			(layers "F.Cu" "F.Mask" "F.Paste")
			(net 624 "unconnected-(J1D-I2C9_DAT-PadJ55)")
			(pinfunction "I2C9_DAT")
			(pintype "bidirectional+no_connect")
		)
		(pad "J56" smd circle
			(at 22.1 -4.5 90)
			(size 0.5 0.5)
			(layers "F.Cu" "F.Mask" "F.Paste")
			(net 1 "GND")
			(pinfunction "GND")
			(pintype "passive")
		)
		(pad "J57" smd circle
			(at 23 -4.5 90)
			(size 0.5 0.5)
			(layers "F.Cu" "F.Mask" "F.Paste")
			(net 421 "/Expansion connector/SPI1.SCK")
			(pinfunction "SPI1_CLK")
			(pintype "bidirectional")
		)
		(pad "J58" smd circle
			(at 23.9 -4.5 90)
			(size 0.5 0.5)
			(layers "F.Cu" "F.Mask" "F.Paste")
			(net 118 "/Expansion connector/UART5.TX")
			(pinfunction "UART5_TX")
			(pintype "output")
		)
		(pad "J59" smd circle
			(at 24.8 -4.5 90)
			(size 0.5 0.5)
			(layers "F.Cu" "F.Mask" "F.Paste")
			(net 551 "unconnected-(J1H-I2S3_DIN-PadJ59)")
			(pinfunction "I2S3_DIN")
			(pintype "input+no_connect")
		)
		(pad "J60" smd circle
			(at 25.7 -4.5 90)
			(size 0.5 0.5)
			(layers "F.Cu" "F.Mask" "F.Paste")
			(net 609 "/SoM_Power/~{MOD_SLEEP}")
			(pinfunction "MODULE_SLEEP_N")
			(pintype "output")
		)
		(pad "J61" smd circle
			(at 26.6 -4.5 90)
			(size 0.5 0.5)
			(layers "F.Cu" "F.Mask" "F.Paste")
			(net 139 "/SoM_IO/I2C2_SCL_1V8")
			(pinfunction "I2C2_CLK")
			(pintype "bidirectional")
		)
		(pad "J62" smd circle
			(at 27.5 -4.5 90)
			(size 0.5 0.5)
			(layers "F.Cu" "F.Mask" "F.Paste")
			(net 1 "GND")
			(pinfunction "GND")
			(pintype "passive")
		)
		(pad "J63" smd circle
			(at 28.4 -4.5 90)
			(size 0.5 0.5)
			(layers "F.Cu" "F.Mask" "F.Paste")
			(net 12 "SYS_VIN_HV")
			(pinfunction "SYS_VIN_HV")
			(pintype "passive")
		)
		(pad "J64" smd circle
			(at 29.3 -4.5 90)
			(size 0.5 0.5)
			(layers "F.Cu" "F.Mask" "F.Paste")
			(net 12 "SYS_VIN_HV")
			(pinfunction "SYS_VIN_HV")
			(pintype "passive")
		)
		(pad "J65" smd circle
			(at 30.2 -4.5 90)
			(size 0.5 0.5)
			(layers "F.Cu" "F.Mask" "F.Paste")
			(net 12 "SYS_VIN_HV")
			(pinfunction "SYS_VIN_HV")
			(pintype "passive")
		)
		(pad "K3" smd circle
			(at -28.2 -6 90)
			(size 0.5 0.5)
			(layers "F.Cu" "F.Mask" "F.Paste")
			(net 12 "SYS_VIN_HV")
			(pinfunction "SYS_VIN_HV")
			(pintype "passive")
		)
		(pad "K4" smd circle
			(at -27.3 -6 90)
			(size 0.5 0.5)
			(layers "F.Cu" "F.Mask" "F.Paste")
			(net 1 "GND")
			(pinfunction "GND")
			(pintype "passive")
		)
		(pad "K5" smd circle
			(at -26.4 -6 90)
			(size 0.5 0.5)
			(layers "F.Cu" "F.Mask" "F.Paste")
			(net 48 "/SoM_IO/I2C1_SCL_1V8")
			(pinfunction "I2C1_CLK")
			(pintype "bidirectional")
		)
		(pad "K6" smd circle
			(at -25.5 -6 90)
			(size 0.5 0.5)
			(layers "F.Cu" "F.Mask" "F.Paste")
			(net 368 "/Expansion connector/GPIO.21")
			(pinfunction "GPIO60")
			(pintype "passive")
		)
		(pad "K7" smd circle
			(at -24.6 -6 90)
			(size 0.5 0.5)
			(layers "F.Cu" "F.Mask" "F.Paste")
			(net 629 "unconnected-(J1G-FSI_GPIO27-PadK7)")
			(pinfunction "FSI_GPIO27")
			(pintype "passive+no_connect")
		)
		(pad "K8" smd circle
			(at -23.7 -6 90)
			(size 0.5 0.5)
			(layers "F.Cu" "F.Mask" "F.Paste")
			(net 1 "GND")
			(pinfunction "GND")
			(pintype "passive")
		)
		(pad "K9" smd circle
			(at -22.8 -6 90)
			(size 0.5 0.5)
			(layers "F.Cu" "F.Mask" "F.Paste")
			(net 632 "unconnected-(J1G-FSI_GPIO22-PadK9)")
			(pinfunction "FSI_GPIO22")
			(pintype "passive+no_connect")
		)
		(pad "K10" smd circle
			(at -21.9 -6 90)
			(size 0.5 0.5)
			(layers "F.Cu" "F.Mask" "F.Paste")
			(net 320 "unconnected-(J1D-FSI_GPIO28-PadK10)")
			(pinfunction "FSI_GPIO28")
			(pintype "passive+no_connect")
		)
		(pad "K11" smd circle
			(at -21 -6 90)
			(size 0.5 0.5)
			(layers "F.Cu" "F.Mask" "F.Paste")
			(net 1 "GND")
			(pinfunction "GND")
			(pintype "passive")
		)
		(pad "K12" smd circle
			(at -20.1 -6 90)
			(size 0.5 0.5)
			(layers "F.Cu" "F.Mask" "F.Paste")
			(net 517 "/Expansion connector/PCIe_{C3x2}.TX0-")
			(pinfunction "UPHY_TX6_N")
			(pintype "output")
		)
		(pad "K13" smd circle
			(at -19.2 -6 90)
			(size 0.5 0.5)
			(layers "F.Cu" "F.Mask" "F.Paste")
			(net 459 "/Expansion connector/PCIe_{C3x2}.TX0+")
			(pinfunction "UPHY_TX6_P")
			(pintype "output")
		)
		(pad "K14" smd circle
			(at -18.3 -6 90)
			(size 0.5 0.5)
			(layers "F.Cu" "F.Mask" "F.Paste")
			(net 1 "GND")
			(pinfunction "GND")
			(pintype "passive")
		)
		(pad "K15" smd circle
			(at -17 -6 90)
			(size 0.5 0.5)
			(layers "F.Cu" "F.Mask" "F.Paste")
			(net 1 "GND")
			(pinfunction "GND")
			(pintype "passive")
		)
		(pad "K16" smd circle
			(at -16.1 -6 90)
			(size 0.5 0.5)
			(layers "F.Cu" "F.Mask" "F.Paste")
			(net 586 "unconnected-(J1B-UPHY_TX16_N-PadK16)")
			(pinfunction "UPHY_TX16_N")
			(pintype "output+no_connect")
		)
		(pad "K17" smd circle
			(at -15.2 -6 90)
			(size 0.5 0.5)
			(layers "F.Cu" "F.Mask" "F.Paste")
			(net 754 "unconnected-(J1B-UPHY_TX16_P-PadK17)")
			(pinfunction "UPHY_TX16_P")
			(pintype "output+no_connect")
		)
		(pad "K18" smd circle
			(at -14.3 -6 90)
			(size 0.5 0.5)
			(layers "F.Cu" "F.Mask" "F.Paste")
			(net 1 "GND")
			(pinfunction "GND")
			(pintype "passive")
		)
		(pad "K19" smd circle
			(at -13 -6 90)
			(size 0.5 0.5)
			(layers "F.Cu" "F.Mask" "F.Paste")
			(net 1 "GND")
			(pinfunction "GND")
			(pintype "passive")
		)
		(pad "K20" smd circle
			(at -12.1 -6 90)
			(size 0.5 0.5)
			(layers "F.Cu" "F.Mask" "F.Paste")
			(net 516 "/Expansion connector/PCIe_{C2x1}.TX0-")
			(pinfunction "UPHY_TX4_N")
			(pintype "output")
		)
		(pad "K21" smd circle
			(at -11.2 -6 90)
			(size 0.5 0.5)
			(layers "F.Cu" "F.Mask" "F.Paste")
			(net 478 "/Expansion connector/PCIe_{C2x1}.TX0+")
			(pinfunction "UPHY_TX4_P")
			(pintype "output")
		)
		(pad "K22" smd circle
			(at -10.3 -6 90)
			(size 0.5 0.5)
			(layers "F.Cu" "F.Mask" "F.Paste")
			(net 1 "GND")
			(pinfunction "GND")
			(pintype "passive")
		)
		(pad "K23" smd circle
			(at -9 -6 90)
			(size 0.5 0.5)
			(layers "F.Cu" "F.Mask" "F.Paste")
			(net 1 "GND")
			(pinfunction "GND")
			(pintype "passive")
		)
		(pad "K24" smd circle
			(at -8.1 -6 90)
			(size 0.5 0.5)
			(layers "F.Cu" "F.Mask" "F.Paste")
			(net 418 "/M.2/PCIe_{C5x4}.TX1-")
			(pinfunction "UPHY_TX9_N")
			(pintype "output")
		)
		(pad "K25" smd circle
			(at -7.2 -6 90)
			(size 0.5 0.5)
			(layers "F.Cu" "F.Mask" "F.Paste")
			(net 392 "/M.2/PCIe_{C5x4}.TX1+")
			(pinfunction "UPHY_TX9_P")
			(pintype "output")
		)
		(pad "K26" smd circle
			(at -6.3 -6 90)
			(size 0.5 0.5)
			(layers "F.Cu" "F.Mask" "F.Paste")
			(net 1 "GND")
			(pinfunction "GND")
			(pintype "passive")
		)
		(pad "K27" smd circle
			(at -5 -6 90)
			(size 0.5 0.5)
			(layers "F.Cu" "F.Mask" "F.Paste")
			(net 1 "GND")
			(pinfunction "GND")
			(pintype "passive")
		)
		(pad "K28" smd circle
			(at -4.1 -6 90)
			(size 0.5 0.5)
			(layers "F.Cu" "F.Mask" "F.Paste")
			(net 696 "unconnected-(J1B-UPHY_TX13_N-PadK28)")
			(pinfunction "UPHY_TX13_N")
			(pintype "output+no_connect")
		)
		(pad "K29" smd circle
			(at -3.2 -6 90)
			(size 0.5 0.5)
			(layers "F.Cu" "F.Mask" "F.Paste")
			(net 602 "unconnected-(J1B-UPHY_TX13_P-PadK29)")
			(pinfunction "UPHY_TX13_P")
			(pintype "output+no_connect")
		)
		(pad "K30" smd circle
			(at -2.3 -6 90)
			(size 0.5 0.5)
			(layers "F.Cu" "F.Mask" "F.Paste")
			(net 1 "GND")
			(pinfunction "GND")
			(pintype "passive")
		)
		(pad "K31" smd circle
			(at -1 -6 90)
			(size 0.5 0.5)
			(layers "F.Cu" "F.Mask" "F.Paste")
			(net 1 "GND")
			(pinfunction "GND")
			(pintype "passive")
		)
		(pad "K32" smd circle
			(at -0.1 -6 90)
			(size 0.5 0.5)
			(layers "F.Cu" "F.Mask" "F.Paste")
			(net 618 "/Recovery USB/USBSS0.TX+")
			(pinfunction "UPHY_TX0_P")
			(pintype "output")
		)
		(pad "K33" smd circle
			(at 0.8 -6 90)
			(size 0.5 0.5)
			(layers "F.Cu" "F.Mask" "F.Paste")
			(net 630 "/Recovery USB/USBSS0.TX-")
			(pinfunction "UPHY_TX0_N")
			(pintype "output")
		)
		(pad "K34" smd circle
			(at 1.7 -6 90)
			(size 0.5 0.5)
			(layers "F.Cu" "F.Mask" "F.Paste")
			(net 1 "GND")
			(pinfunction "GND")
			(pintype "passive")
		)
		(pad "K35" smd circle
			(at 3 -6 90)
			(size 0.5 0.5)
			(layers "F.Cu" "F.Mask" "F.Paste")
			(net 1 "GND")
			(pinfunction "GND")
			(pintype "passive")
		)
		(pad "K36" smd circle
			(at 3.9 -6 90)
			(size 0.5 0.5)
			(layers "F.Cu" "F.Mask" "F.Paste")
			(net 769 "unconnected-(J1G-FSI_GPIO04-PadK36)")
			(pinfunction "FSI_GPIO04")
			(pintype "passive+no_connect")
		)
		(pad "K37" smd circle
			(at 4.8 -6 90)
			(size 0.5 0.5)
			(layers "F.Cu" "F.Mask" "F.Paste")
			(net 875 "Net-(J1A-FSI_GPIO03)")
			(pinfunction "FSI_GPIO03")
			(pintype "passive")
		)
		(pad "K38" smd circle
			(at 5.7 -6 90)
			(size 0.5 0.5)
			(layers "F.Cu" "F.Mask" "F.Paste")
			(net 1 "GND")
			(pinfunction "GND")
			(pintype "passive")
		)
		(pad "K39" smd circle
			(at 7 -6 90)
			(size 0.5 0.5)
			(layers "F.Cu" "F.Mask" "F.Paste")
			(net 1 "GND")
			(pinfunction "GND")
			(pintype "passive")
		)
		(pad "K40" smd circle
			(at 7.9 -6 90)
			(size 0.5 0.5)
			(layers "F.Cu" "F.Mask" "F.Paste")
			(net 119 "unconnected-(J1A-MID0-PadK40)")
			(pinfunction "MID0")
			(pintype "passive+no_connect")
		)
		(pad "K41" smd circle
			(at 8.8 -6 90)
			(size 0.5 0.5)
			(layers "F.Cu" "F.Mask" "F.Paste")
			(net 1 "GND")
			(pinfunction "GND")
			(pintype "passive")
		)
		(pad "K42" smd circle
			(at 9.7 -6 90)
			(size 0.5 0.5)
			(layers "F.Cu" "F.Mask" "F.Paste")
			(net 1 "GND")
			(pinfunction "GND")
			(pintype "passive")
		)
		(pad "K43" smd circle
			(at 10.6 -6 90)
			(size 0.5 0.5)
			(layers "F.Cu" "F.Mask" "F.Paste")
			(net 135 "/CSI/CAM3.CSI6_D0-")
			(pinfunction "CSI6_D0_N")
			(pintype "input")
		)
		(pad "K44" smd circle
			(at 11.5 -6 90)
			(size 0.5 0.5)
			(layers "F.Cu" "F.Mask" "F.Paste")
			(net 152 "/CSI/CAM3.CSI6_D0+")
			(pinfunction "CSI6_D0_P")
			(pintype "input")
		)
		(pad "K45" smd circle
			(at 12.4 -6 90)
			(size 0.5 0.5)
			(layers "F.Cu" "F.Mask" "F.Paste")
			(net 1 "GND")
			(pinfunction "GND")
			(pintype "passive")
		)
		(pad "K46" smd circle
			(at 13.3 -6 90)
			(size 0.5 0.5)
			(layers "F.Cu" "F.Mask" "F.Paste")
			(net 1247 "/SoM_IO2/DP1.TX3_C+")
			(pinfunction "DP1_D3_HDMI_CK_P")
			(pintype "output")
		)
		(pad "K47" smd circle
			(at 14.2 -6 90)
			(size 0.5 0.5)
			(layers "F.Cu" "F.Mask" "F.Paste")
			(net 1251 "/SoM_IO2/DP1.TX3_C-")
			(pinfunction "DP1_D3_HDMI_CK_N")
			(pintype "output")
		)
		(pad "K48" smd circle
			(at 15.1 -6 90)
			(size 0.5 0.5)
			(layers "F.Cu" "F.Mask" "F.Paste")
			(net 1 "GND")
			(pinfunction "GND")
			(pintype "passive")
		)
		(pad "K49" smd circle
			(at 16 -6 90)
			(size 0.5 0.5)
			(layers "F.Cu" "F.Mask" "F.Paste")
			(net 874 "unconnected-(J1C-GPIO25-PadK49)")
			(pinfunction "GPIO25")
			(pintype "passive+no_connect")
		)
		(pad "K50" smd circle
			(at 16.9 -6 90)
			(size 0.5 0.5)
			(layers "F.Cu" "F.Mask" "F.Paste")
			(net 788 "/SoM_IO2/DP0.HPD")
			(pinfunction "HPD0")
			(pintype "bidirectional")
		)
		(pad "K51" smd circle
			(at 17.8 -6 90)
			(size 0.5 0.5)
			(layers "F.Cu" "F.Mask" "F.Paste")
			(net 660 "unconnected-(J1I-GPIO69-PadK51)")
			(pinfunction "GPIO69")
			(pintype "passive+no_connect")
		)
		(pad "K52" smd circle
			(at 18.7 -6 90)
			(size 0.5 0.5)
			(layers "F.Cu" "F.Mask" "F.Paste")
			(net 876 "unconnected-(J1I-GPIO70-PadK52)")
			(pinfunction "GPIO70")
			(pintype "passive+no_connect")
		)
		(pad "K53" smd circle
			(at 19.6 -6 90)
			(size 0.5 0.5)
			(layers "F.Cu" "F.Mask" "F.Paste")
			(net 138 "/SoM_IO/UART1.TX")
			(pinfunction "UART1_TX")
			(pintype "output")
		)
		(pad "K54" smd circle
			(at 20.5 -6 90)
			(size 0.5 0.5)
			(layers "F.Cu" "F.Mask" "F.Paste")
			(net 108 "/SoM_IO/UART1.RX")
			(pinfunction "UART1_RX")
			(pintype "input")
		)
		(pad "K55" smd circle
			(at 21.4 -6 90)
			(size 0.5 0.5)
			(layers "F.Cu" "F.Mask" "F.Paste")
			(net 1 "GND")
			(pinfunction "GND")
			(pintype "passive")
		)
		(pad "K56" smd circle
			(at 22.3 -6 90)
			(size 0.5 0.5)
			(layers "F.Cu" "F.Mask" "F.Paste")
			(net 748 "unconnected-(J1I-GPIO19-PadK56)")
			(pinfunction "GPIO19")
			(pintype "output+no_connect")
		)
		(pad "K57" smd circle
			(at 23.2 -6 90)
			(size 0.5 0.5)
			(layers "F.Cu" "F.Mask" "F.Paste")
			(net 787 "unconnected-(J1I-PWM01-PadK57)")
			(pinfunction "PWM01")
			(pintype "passive+no_connect")
		)
		(pad "K58" smd circle
			(at 24.1 -6 90)
			(size 0.5 0.5)
			(layers "F.Cu" "F.Mask" "F.Paste")
			(net 56 "/Expansion connector/UART5.RTS")
			(pinfunction "UART5_RTS")
			(pintype "output")
		)
		(pad "K59" smd circle
			(at 25 -6 90)
			(size 0.5 0.5)
			(layers "F.Cu" "F.Mask" "F.Paste")
			(net 587 "unconnected-(J1H-I2S3_DOUT-PadK59)")
			(pinfunction "I2S3_DOUT")
			(pintype "output+no_connect")
		)
		(pad "K60" smd circle
			(at 25.9 -6 90)
			(size 0.5 0.5)
			(layers "F.Cu" "F.Mask" "F.Paste")
			(net 494 "/SoM_IO/UART3_DEBUG_RX_1V8")
			(pinfunction "UART3_RX_DEBUG")
			(pintype "input")
		)
		(pad "K61" smd circle
			(at 26.8 -6 90)
			(size 0.5 0.5)
			(layers "F.Cu" "F.Mask" "F.Paste")
			(net 167 "/SoM_IO/I2C2_SDA_1V8")
			(pinfunction "I2C2_DAT")
			(pintype "bidirectional")
		)
		(pad "K62" smd circle
			(at 27.7 -6 90)
			(size 0.5 0.5)
			(layers "F.Cu" "F.Mask" "F.Paste")
			(net 97 "/Peripherals/FAN_PWM")
			(pinfunction "FAN_PWM")
			(pintype "output")
		)
		(pad "K63" smd circle
			(at 28.6 -6 90)
			(size 0.5 0.5)
			(layers "F.Cu" "F.Mask" "F.Paste")
			(net 1 "GND")
			(pinfunction "GND")
			(pintype "passive")
		)
		(pad "L3" smd circle
			(at -28.4 -7.5 90)
			(size 0.5 0.5)
			(layers "F.Cu" "F.Mask" "F.Paste")
			(net 1 "GND")
			(pinfunction "GND")
			(pintype "passive")
		)
		(pad "L4" smd circle
			(at -27.5 -7.5 90)
			(size 0.5 0.5)
			(layers "F.Cu" "F.Mask" "F.Paste")
			(net 757 "unconnected-(J1I-UART4_RTS-PadL4)")
			(pinfunction "UART4_RTS")
			(pintype "output+no_connect")
		)
		(pad "L5" smd circle
			(at -26.6 -7.5 90)
			(size 0.5 0.5)
			(layers "F.Cu" "F.Mask" "F.Paste")
			(net 616 "unconnected-(J1I-UART4_TX-PadL5)")
			(pinfunction "UART4_TX")
			(pintype "output+no_connect")
		)
		(pad "L6" smd circle
			(at -25.7 -7.5 90)
			(size 0.5 0.5)
			(layers "F.Cu" "F.Mask" "F.Paste")
			(net 765 "unconnected-(J1I-UART4_CTS-PadL6)")
			(pinfunction "UART4_CTS")
			(pintype "input+no_connect")
		)
		(pad "L7" smd circle
			(at -24.8 -7.5 90)
			(size 0.5 0.5)
			(layers "F.Cu" "F.Mask" "F.Paste")
			(net 1 "GND")
			(pinfunction "GND")
			(pintype "passive")
		)
		(pad "L8" smd circle
			(at -23.9 -7.5 90)
			(size 0.5 0.5)
			(layers "F.Cu" "F.Mask" "F.Paste")
			(net 96 "/SoM_IO/I2C1_SDA_1V8")
			(pinfunction "I2C1_DAT")
			(pintype "bidirectional")
		)
		(pad "L9" smd circle
			(at -23 -7.5 90)
			(size 0.5 0.5)
			(layers "F.Cu" "F.Mask" "F.Paste")
			(net 649 "unconnected-(J1H-I2S7_DOUT-PadL9)")
			(pinfunction "I2S7_DOUT")
			(pintype "output+no_connect")
		)
		(pad "L10" smd circle
			(at -22.1 -7.5 90)
			(size 0.5 0.5)
			(layers "F.Cu" "F.Mask" "F.Paste")
			(net 495 "/SoM_Power/~{FORCE_RECOVERY}")
			(pinfunction "FORCE_RECOVERY_N")
			(pintype "input")
		)
		(pad "L11" smd circle
			(at -21.2 -7.5 90)
			(size 0.5 0.5)
			(layers "F.Cu" "F.Mask" "F.Paste")
			(net 793 "/SoM_Power/~{SLEEP_REQ}")
			(pinfunction "SLEEP_REQ_N")
			(pintype "input")
		)
		(pad "L12" smd circle
			(at -20.3 -7.5 90)
			(size 0.5 0.5)
			(layers "F.Cu" "F.Mask" "F.Paste")
			(net 1 "GND")
			(pinfunction "GND")
			(pintype "passive")
		)
		(pad "L13" smd circle
			(at -19 -7.5 90)
			(size 0.5 0.5)
			(layers "F.Cu" "F.Mask" "F.Paste")
			(net 1 "GND")
			(pinfunction "GND")
			(pintype "passive")
		)
		(pad "L14" smd circle
			(at -18.1 -7.5 90)
			(size 0.5 0.5)
			(layers "F.Cu" "F.Mask" "F.Paste")
			(net 107 "/SoM_IO/I2S_{M.2}.CLK")
			(pinfunction "I2S1_CLK")
			(pintype "bidirectional")
		)
		(pad "L15" smd circle
			(at -17.2 -7.5 90)
			(size 0.5 0.5)
			(layers "F.Cu" "F.Mask" "F.Paste")
			(net 580 "/SoM_IO/USBC1_FLG_1V8")
			(pinfunction "GPIO14")
			(pintype "passive")
		)
		(pad "L16" smd circle
			(at -16.3 -7.5 90)
			(size 0.5 0.5)
			(layers "F.Cu" "F.Mask" "F.Paste")
			(net 1 "GND")
			(pinfunction "GND")
			(pintype "passive")
		)
		(pad "L17" smd circle
			(at -15 -7.5 90)
			(size 0.5 0.5)
			(layers "F.Cu" "F.Mask" "F.Paste")
			(net 1 "GND")
			(pinfunction "GND")
			(pintype "passive")
		)
		(pad "L18" smd circle
			(at -14.1 -7.5 90)
			(size 0.5 0.5)
			(layers "F.Cu" "F.Mask" "F.Paste")
			(net 775 "/M.2/PCIe_{C5x4}.~{RST}")
			(pinfunction "PEX_C5_RST_N")
			(pintype "output")
		)
		(pad "L19" smd circle
			(at -13.2 -7.5 90)
			(size 0.5 0.5)
			(layers "F.Cu" "F.Mask" "F.Paste")
			(net 751 "/M.2/PCIe_{C5x4}.~{CLKREQ}")
			(pinfunction "PEX_C5_CLKREQ_N")
			(pintype "bidirectional")
		)
		(pad "L20" smd circle
			(at -12.3 -7.5 90)
			(size 0.5 0.5)
			(layers "F.Cu" "F.Mask" "F.Paste")
			(net 1 "GND")
			(pinfunction "GND")
			(pintype "passive")
		)
		(pad "L21" smd circle
			(at -11 -7.5 90)
			(size 0.5 0.5)
			(layers "F.Cu" "F.Mask" "F.Paste")
			(net 1 "GND")
			(pinfunction "GND")
			(pintype "passive")
		)
		(pad "L22" smd circle
			(at -10.1 -7.5 90)
			(size 0.5 0.5)
			(layers "F.Cu" "F.Mask" "F.Paste")
			(net 213 "+5V_SOM")
			(pinfunction "SYS_VIN_MV")
			(pintype "power_in")
		)
		(pad "L23" smd circle
			(at -9.2 -7.5 90)
			(size 0.5 0.5)
			(layers "F.Cu" "F.Mask" "F.Paste")
			(net 213 "+5V_SOM")
			(pinfunction "SYS_VIN_MV")
			(pintype "passive")
		)
		(pad "L24" smd circle
			(at -8.3 -7.5 90)
			(size 0.5 0.5)
			(layers "F.Cu" "F.Mask" "F.Paste")
			(net 1 "GND")
			(pinfunction "GND")
			(pintype "passive")
		)
		(pad "L25" smd circle
			(at -7 -7.5 90)
			(size 0.5 0.5)
			(layers "F.Cu" "F.Mask" "F.Paste")
			(net 1 "GND")
			(pinfunction "GND")
			(pintype "passive")
		)
		(pad "L26" smd circle
			(at -6.1 -7.5 90)
			(size 0.5 0.5)
			(layers "F.Cu" "F.Mask" "F.Paste")
			(net 213 "+5V_SOM")
			(pinfunction "SYS_VIN_MV")
			(pintype "passive")
		)
		(pad "L27" smd circle
			(at -5.2 -7.5 90)
			(size 0.5 0.5)
			(layers "F.Cu" "F.Mask" "F.Paste")
			(net 213 "+5V_SOM")
			(pinfunction "SYS_VIN_MV")
			(pintype "passive")
		)
		(pad "L28" smd circle
			(at -4.3 -7.5 90)
			(size 0.5 0.5)
			(layers "F.Cu" "F.Mask" "F.Paste")
			(net 1 "GND")
			(pinfunction "GND")
			(pintype "passive")
		)
		(pad "L29" smd circle
			(at -3 -7.5 90)
			(size 0.5 0.5)
			(layers "F.Cu" "F.Mask" "F.Paste")
			(net 1 "GND")
			(pinfunction "GND")
			(pintype "passive")
		)
		(pad "L30" smd circle
			(at -2.1 -7.5 90)
			(size 0.5 0.5)
			(layers "F.Cu" "F.Mask" "F.Paste")
			(net 213 "+5V_SOM")
			(pinfunction "SYS_VIN_MV")
			(pintype "passive")
		)
		(pad "L31" smd circle
			(at -1.2 -7.5 90)
			(size 0.5 0.5)
			(layers "F.Cu" "F.Mask" "F.Paste")
			(net 213 "+5V_SOM")
			(pinfunction "SYS_VIN_MV")
			(pintype "passive")
		)
		(pad "L32" smd circle
			(at -0.3 -7.5 90)
			(size 0.5 0.5)
			(layers "F.Cu" "F.Mask" "F.Paste")
			(net 1 "GND")
			(pinfunction "GND")
			(pintype "passive")
		)
		(pad "L33" smd circle
			(at 1 -7.5 90)
			(size 0.5 0.5)
			(layers "F.Cu" "F.Mask" "F.Paste")
			(net 1 "GND")
			(pinfunction "GND")
			(pintype "passive")
		)
		(pad "L34" smd circle
			(at 1.9 -7.5 90)
			(size 0.5 0.5)
			(layers "F.Cu" "F.Mask" "F.Paste")
			(net 213 "+5V_SOM")
			(pinfunction "SYS_VIN_MV")
			(pintype "passive")
		)
		(pad "L35" smd circle
			(at 2.8 -7.5 90)
			(size 0.5 0.5)
			(layers "F.Cu" "F.Mask" "F.Paste")
			(net 213 "+5V_SOM")
			(pinfunction "SYS_VIN_MV")
			(pintype "passive")
		)
		(pad "L36" smd circle
			(at 3.7 -7.5 90)
			(size 0.5 0.5)
			(layers "F.Cu" "F.Mask" "F.Paste")
			(net 1 "GND")
			(pinfunction "GND")
			(pintype "passive")
		)
		(pad "L37" smd circle
			(at 5 -7.5 90)
			(size 0.5 0.5)
			(layers "F.Cu" "F.Mask" "F.Paste")
			(net 1 "GND")
			(pinfunction "GND")
			(pintype "passive")
		)
		(pad "L38" smd circle
			(at 5.9 -7.5 90)
			(size 0.5 0.5)
			(layers "F.Cu" "F.Mask" "F.Paste")
			(net 213 "+5V_SOM")
			(pinfunction "SYS_VIN_MV")
			(pintype "passive")
		)
		(pad "L39" smd circle
			(at 6.8 -7.5 90)
			(size 0.5 0.5)
			(layers "F.Cu" "F.Mask" "F.Paste")
			(net 213 "+5V_SOM")
			(pinfunction "SYS_VIN_MV")
			(pintype "passive")
		)
		(pad "L40" smd circle
			(at 7.7 -7.5 90)
			(size 0.5 0.5)
			(layers "F.Cu" "F.Mask" "F.Paste")
			(net 1 "GND")
			(pinfunction "GND")
			(pintype "passive")
		)
		(pad "L41" smd circle
			(at 8.6 -7.5 90)
			(size 0.5 0.5)
			(layers "F.Cu" "F.Mask" "F.Paste")
			(net 566 "Net-(J1A-VM_SLEEP_N)")
			(pinfunction "VM_SLEEP_N")
			(pintype "output")
		)
		(pad "L42" smd circle
			(at 9.5 -7.5 90)
			(size 0.5 0.5)
			(layers "F.Cu" "F.Mask" "F.Paste")
			(net 700 "Net-(J1A-MV_LSW_MON)")
			(pinfunction "MV_LSW_MON")
			(pintype "input")
		)
		(pad "L43" smd circle
			(at 10.4 -7.5 90)
			(size 0.5 0.5)
			(layers "F.Cu" "F.Mask" "F.Paste")
			(net 1 "GND")
			(pinfunction "GND")
			(pintype "passive")
		)
		(pad "L44" smd circle
			(at 11.3 -7.5 90)
			(size 0.5 0.5)
			(layers "F.Cu" "F.Mask" "F.Paste")
			(net 664 "unconnected-(J1D-VM_I2C_SCK-PadL44)")
			(pinfunction "VM_I2C_SCK")
			(pintype "bidirectional+no_connect")
		)
		(pad "L45" smd circle
			(at 12.2 -7.5 90)
			(size 0.5 0.5)
			(layers "F.Cu" "F.Mask" "F.Paste")
			(net 734 "unconnected-(J1D-VM_I2C_DAT-PadL45)")
			(pinfunction "VM_I2C_DAT")
			(pintype "bidirectional+no_connect")
		)
		(pad "L46" smd circle
			(at 13.1 -7.5 90)
			(size 0.5 0.5)
			(layers "F.Cu" "F.Mask" "F.Paste")
			(net 1 "GND")
			(pinfunction "GND")
			(pintype "passive")
		)
		(pad "L47" smd circle
			(at 14 -7.5 90)
			(size 0.5 0.5)
			(layers "F.Cu" "F.Mask" "F.Paste")
			(net 601 "Net-(J1A-VM_INT_N)")
			(pinfunction "VM_INT_N")
			(pintype "input")
		)
		(pad "L48" smd circle
			(at 14.9 -7.5 90)
			(size 0.5 0.5)
			(layers "F.Cu" "F.Mask" "F.Paste")
			(net 654 "unconnected-(J1H-I2S7_DIN-PadL48)")
			(pinfunction "I2S7_DIN")
			(pintype "input+no_connect")
		)
		(pad "L49" smd circle
			(at 15.8 -7.5 90)
			(size 0.5 0.5)
			(layers "F.Cu" "F.Mask" "F.Paste")
			(net 712 "unconnected-(J1H-I2S7_LRCK-PadL49)")
			(pinfunction "I2S7_LRCK")
			(pintype "input+no_connect")
		)
		(pad "L50" smd circle
			(at 16.7 -7.5 90)
			(size 0.5 0.5)
			(layers "F.Cu" "F.Mask" "F.Paste")
			(net 705 "unconnected-(J1H-I2S7_SCLK-PadL50)")
			(pinfunction "I2S7_SCLK")
			(pintype "passive+no_connect")
		)
		(pad "L51" smd circle
			(at 17.6 -7.5 90)
			(size 0.5 0.5)
			(layers "F.Cu" "F.Mask" "F.Paste")
			(net 126 "/SoM_IO/UART1.RTS")
			(pinfunction "UART1_RTS")
			(pintype "output")
		)
		(pad "L52" smd circle
			(at 18.5 -7.5 90)
			(size 0.5 0.5)
			(layers "F.Cu" "F.Mask" "F.Paste")
			(net 605 "/SoM_Power/~{MODULE_SHDN}")
			(pinfunction "MODULE_SHDN_N")
			(pintype "output")
		)
		(pad "L53" smd circle
			(at 19.4 -7.5 90)
			(size 0.5 0.5)
			(layers "F.Cu" "F.Mask" "F.Paste")
			(net 4 "+3V3_AON")
			(pinfunction "SYS_VIN_SV")
			(pintype "power_in")
		)
		(pad "L54" smd circle
			(at 20.3 -7.5 90)
			(size 0.5 0.5)
			(layers "F.Cu" "F.Mask" "F.Paste")
			(net 1287 "/SoM_Power/MODULE_POWER_ON")
			(pinfunction "MODULE_POWER_ON")
			(pintype "input")
		)
		(pad "L55" smd circle
			(at 21.2 -7.5 90)
			(size 0.5 0.5)
			(layers "F.Cu" "F.Mask" "F.Paste")
			(net 246 "/SoM_Power/~{VDDIN_PWR_BAD}")
			(pinfunction "VDDIN_PWR_BAD_N")
			(pintype "bidirectional")
		)
		(pad "L56" smd circle
			(at 22.1 -7.5 90)
			(size 0.5 0.5)
			(layers "F.Cu" "F.Mask" "F.Paste")
			(net 621 "Net-(J1A-THERM_ALERT_N)")
			(pinfunction "THERM_ALERT_N")
			(pintype "output")
		)
		(pad "L57" smd circle
			(at 23 -7.5 90)
			(size 0.5 0.5)
			(layers "F.Cu" "F.Mask" "F.Paste")
			(net 763 "unconnected-(J1D-MCLK05-PadL57)")
			(pinfunction "MCLK05")
			(pintype "bidirectional+no_connect")
		)
		(pad "L58" smd circle
			(at 23.9 -7.5 90)
			(size 0.5 0.5)
			(layers "F.Cu" "F.Mask" "F.Paste")
			(net 741 "Net-(J1A-PERIPHERAL_RESET_N)")
			(pinfunction "PERIPHERAL_RESET_N")
			(pintype "input")
		)
		(pad "L59" smd circle
			(at 24.8 -7.5 90)
			(size 0.5 0.5)
			(layers "F.Cu" "F.Mask" "F.Paste")
			(net 760 "Net-(J1A-MODULE_POWER_GOOD)")
			(pinfunction "MODULE_POWER_GOOD")
			(pintype "output")
		)
		(pad "L60" smd circle
			(at 25.7 -7.5 90)
			(size 0.5 0.5)
			(layers "F.Cu" "F.Mask" "F.Paste")
			(net 702 "/SoM_Power/~{SYS_RESET}")
			(pinfunction "SYS_RESET_N")
			(pintype "bidirectional")
		)
		(pad "L61" smd circle
			(at 26.6 -7.5 90)
			(size 0.5 0.5)
			(layers "F.Cu" "F.Mask" "F.Paste")
			(net 85 "/SoM_Power/~{SOM_POWER_BTN}")
			(pinfunction "POWER_BTN_N")
			(pintype "bidirectional")
		)
		(pad "L62" smd circle
			(at 27.5 -7.5 90)
			(size 0.5 0.5)
			(layers "F.Cu" "F.Mask" "F.Paste")
			(net 1293 "/DCDC/CARRIER_PWR_ON")
			(pinfunction "CARRIER_POWER_ON")
			(pintype "output")
		)
		(pad "L63" smd circle
			(at 28.4 -7.5 90)
			(size 0.5 0.5)
			(layers "F.Cu" "F.Mask" "F.Paste")
			(net 1 "GND")
			(pinfunction "PRSNT1")
			(pintype "passive")
		)
	)
	(footprint "antmicro-footprints:R_0402_1005Metric"
		(layer "F.Cu")
		(at 214 130.8 180)
		(descr "Resistor SMD 0402")
		(tags "resistor SMD 0402")
		(property "Reference" "R92"
			(at -1.6 2.3 0)
			(layer "F.SilkS")
			(effects
				(font
					(size 0.7 0.7)
					(thickness 0.15)
				)
				(justify right top)
			)
		)
		(property "Value" "R_49k9_0402"
			(at -1.011843 1.772047 0)
			(layer "F.Fab")
			(effects
				(font
					(size 0.7 0.7)
					(thickness 0.15)
				)
				(justify right top)
			)
		)
		(property "Datasheet" "https://www.bourns.com/docs/product-datasheets/cr.pdf"
			(at 0 0 0)
			(layer "F.Fab")
			(hide yes)
			(effects
				(font
					(size 1.27 1.27)
					(thickness 0.15)
				)
			)
		)
		(property "Description" "SMD Chip Resistor, 49.9 kohm, ± 1%, 63 mW, 0402 [1005 Metric], Thick Film, General Purpose"
			(at 0 0 0)
			(layer "F.Fab")
			(hide yes)
			(effects
				(font
					(size 1.27 1.27)
					(thickness 0.15)
				)
			)
		)
		(property "MPN" "CR0402-FX-4992GLF"
			(at 0 0 180)
			(unlocked yes)
			(layer "F.Fab")
			(hide yes)
			(effects
				(font
					(size 1 1)
					(thickness 0.15)
				)
			)
		)
		(property "Manufacturer" "Bourns"
			(at 0 0 180)
			(unlocked yes)
			(layer "F.Fab")
			(hide yes)
			(effects
				(font
					(size 1 1)
					(thickness 0.15)
				)
			)
		)
		(property "License" "Apache-2.0"
			(at 0 0 180)
			(unlocked yes)
			(layer "F.Fab")
			(hide yes)
			(effects
				(font
					(size 1 1)
					(thickness 0.15)
				)
			)
		)
		(property "Author" "Antmicro"
			(at 0 0 180)
			(unlocked yes)
			(layer "F.Fab")
			(hide yes)
			(effects
				(font
					(size 1 1)
					(thickness 0.15)
				)
			)
		)
		(property "Val" "49k9"
			(at 0 0 180)
			(unlocked yes)
			(layer "F.Fab")
			(hide yes)
			(effects
				(font
					(size 1 1)
					(thickness 0.15)
				)
			)
		)
		(property "Tolerance" "1%"
			(at 0 0 180)
			(unlocked yes)
			(layer "F.Fab")
			(hide yes)
			(effects
				(font
					(size 1 1)
					(thickness 0.15)
				)
			)
		)
		(sheetname "/USB Hub/")
		(sheetfile "usb_hub.kicad_sch")
		(attr smd)
		(fp_rect
			(start -0.925 -0.47)
			(end 0.925 0.47)
			(stroke
				(width 0.05)
				(type default)
			)
			(fill no)
			(layer "F.CrtYd")
		)
		(fp_rect
			(start -0.5 -0.25)
			(end 0.5 0.25)
			(stroke
				(width 0.15)
				(type solid)
			)
			(fill no)
			(layer "F.Fab")
		)
		(fp_text user "${REFERENCE}"
			(at -0.95 3.168 0)
			(layer "F.Fab")
			(effects
				(font
					(size 0.7 0.7)
					(thickness 0.15)
				)
				(justify right top)
			)
		)
		(fp_text user "Author: Antmicro"
			(at -0.95 4.169 0)
			(layer "F.Fab")
			(effects
				(font
					(size 0.7 0.7)
					(thickness 0.15)
				)
				(justify right top)
			)
		)
		(fp_text user "License: Apache-2.0"
			(at -0.95 5.169 0)
			(layer "F.Fab")
			(effects
				(font
					(size 0.7 0.7)
					(thickness 0.15)
				)
				(justify right top)
			)
		)
		(pad "1" smd roundrect
			(at -0.48 0 180)
			(size 0.59 0.64)
			(layers "F.Cu" "F.Mask" "F.Paste")
			(roundrect_rratio 0.25)
			(net 1 "GND")
			(pintype "passive")
		)
		(pad "2" smd roundrect
			(at 0.48 0 180)
			(size 0.59 0.64)
			(layers "F.Cu" "F.Mask" "F.Paste")
			(roundrect_rratio 0.25)
			(net 932 "/USB Hub/USBC4_VBUS_MON")
			(pintype "passive")
		)
	)
	(footprint "antmicro-footprints:LED_0603_1608Metric_G"
		(layer "F.Cu")
		(at 197.55 88.22 90)
		(descr "LED SMD 0603 Green")
		(tags "LED SMD 0603 Green")
		(property "Reference" "D19"
			(at -3.42 0.35 90)
			(layer "F.SilkS")
			(effects
				(font
					(size 0.7 0.7)
					(thickness 0.15)
				)
				(justify left bottom)
			)
		)
		(property "Value" "LED_G_0603_LTST-C190GKT"
			(at -0.001 1.599 90)
			(layer "F.Fab")
			(effects
				(font
					(size 0.7 0.7)
					(thickness 0.15)
				)
				(justify left bottom)
			)
		)
		(property "Datasheet" "https://media.digikey.com/pdf/Data%20Sheets/Lite-On%20PDFs/LTST-C190GKT.pdf"
			(at 0 0 90)
			(layer "F.Fab")
			(hide yes)
			(effects
				(font
					(size 1.27 1.27)
					(thickness 0.15)
				)
			)
		)
		(property "Description" "LED, Green, SMD, 0603, 20 mA, 2.1 V, 569 nm"
			(at 0 0 90)
			(layer "F.Fab")
			(hide yes)
			(effects
				(font
					(size 1.27 1.27)
					(thickness 0.15)
				)
			)
		)
		(property "MPN" "LTST-C190GKT"
			(at 0 0 90)
			(unlocked yes)
			(layer "F.Fab")
			(hide yes)
			(effects
				(font
					(size 1 1)
					(thickness 0.15)
				)
			)
		)
		(property "Manufacturer" "Lite-On"
			(at 0 0 90)
			(unlocked yes)
			(layer "F.Fab")
			(hide yes)
			(effects
				(font
					(size 1 1)
					(thickness 0.15)
				)
			)
		)
		(property "Author" "Antmicro"
			(at 0 0 90)
			(unlocked yes)
			(layer "F.Fab")
			(hide yes)
			(effects
				(font
					(size 1 1)
					(thickness 0.15)
				)
			)
		)
		(property "License" "Apache-2.0"
			(at 0 0 90)
			(unlocked yes)
			(layer "F.Fab")
			(hide yes)
			(effects
				(font
					(size 1 1)
					(thickness 0.15)
				)
			)
		)
		(property "Color" "Green"
			(at 0 0 90)
			(unlocked yes)
			(layer "F.Fab")
			(hide yes)
			(effects
				(font
					(size 1 1)
					(thickness 0.15)
				)
			)
		)
		(sheetname "/USB Debug, PD/")
		(sheetfile "usb_debug_pd.kicad_sch")
		(attr smd)
		(fp_line
			(start 0.22 -0.35)
			(end -0.22 -0.35)
			(stroke
				(width 0.15)
				(type solid)
			)
			(layer "F.SilkS")
		)
		(fp_line
			(start -1.18 -0.319)
			(end -1.18 0.321)
			(stroke
				(width 0.15)
				(type solid)
			)
			(layer "F.SilkS")
		)
		(fp_line
			(start 0.105328 0.001008)
			(end 0.24 0.001)
			(stroke
				(width 0.1)
				(type solid)
			)
			(layer "F.SilkS")
		)
		(fp_line
			(start -0.094672 0.001008)
			(end 0.105328 -0.198992)
			(stroke
				(width 0.1)
				(type solid)
			)
			(layer "F.SilkS")
		)
		(fp_line
			(start -0.094672 0.001008)
			(end -0.24 0.001008)
			(stroke
				(width 0.1)
				(type solid)
			)
			(layer "F.SilkS")
		)
		(fp_line
			(start 0.105328 0.201008)
			(end 0.105328 -0.198992)
			(stroke
				(width 0.1)
				(type solid)
			)
			(layer "F.SilkS")
		)
		(fp_line
			(start 0.105328 0.201008)
			(end -0.094672 0.001008)
			(stroke
				(width 0.1)
				(type solid)
			)
			(layer "F.SilkS")
		)
		(fp_line
			(start -0.094672 0.201008)
			(end -0.094672 -0.198992)
			(stroke
				(width 0.1)
				(type solid)
			)
			(layer "F.SilkS")
		)
		(fp_line
			(start 0.22 0.35)
			(end -0.22 0.35)
			(stroke
				(width 0.15)
				(type solid)
			)
			(layer "F.SilkS")
		)
		(fp_rect
			(start 1.25 0.65)
			(end -1.25 -0.65)
			(stroke
				(width 0.05)
				(type solid)
			)
			(fill no)
			(layer "F.CrtYd")
		)
		(fp_line
			(start 0.201 -0.202)
			(end -0.101 0)
			(stroke
				(width 0.15)
				(type solid)
			)
			(layer "F.Fab")
		)
		(fp_line
			(start -0.199 -0.202)
			(end -0.199 0.1)
			(stroke
				(width 0.15)
				(type solid)
			)
			(layer "F.Fab")
		)
		(fp_line
			(start 0.599 0)
			(end 0.201 0)
			(stroke
				(width 0.15)
				(type solid)
			)
			(layer "F.Fab")
		)
		(fp_line
			(start 0.201 0)
			(end 0.201 -0.202)
			(stroke
				(width 0.15)
				(type solid)
			)
			(layer "F.Fab")
		)
		(fp_line
			(start -0.101 0)
			(end 0.201 0.2)
			(stroke
				(width 0.15)
				(type solid)
			)
			(layer "F.Fab")
		)
		(fp_line
			(start -0.199 0)
			(end -0.597 0)
			(stroke
				(width 0.15)
				(type solid)
			)
			(layer "F.Fab")
		)
		(fp_line
			(start 0.201 0.2)
			(end 0.201 0)
			(stroke
				(width 0.15)
				(type solid)
			)
			(layer "F.Fab")
		)
		(fp_line
			(start -0.199 0.2)
			(end -0.199 0.1)
			(stroke
				(width 0.15)
				(type solid)
			)
			(layer "F.Fab")
		)
		(fp_rect
			(start 0.848 0.4)
			(end -0.85 -0.402)
			(stroke
				(width 0.15)
				(type solid)
			)
			(fill no)
			(layer "F.Fab")
		)
		(fp_text user "License: Apache-2.0"
			(at -1.4224 3.599 90)
			(layer "F.Fab")
			(effects
				(font
					(size 0.7 0.7)
					(thickness 0.15)
				)
				(justify left bottom)
			)
		)
		(fp_text user "${REFERENCE}"
			(at -1.4224 5.999 90)
			(layer "F.Fab")
			(effects
				(font
					(size 0.7 0.7)
					(thickness 0.15)
				)
				(justify left bottom)
			)
		)
		(fp_text user "Author: Antmicro"
			(at -1.4224 4.799 90)
			(layer "F.Fab")
			(effects
				(font
					(size 0.7 0.7)
					(thickness 0.15)
				)
				(justify left bottom)
			)
		)
		(pad "1" smd roundrect
			(at -0.7 0 270)
			(size 0.8 1)
			(layers "F.Cu" "F.Mask" "F.Paste")
			(roundrect_rratio 0.2)
			(net 1 "GND")
			(pinfunction "C")
			(pintype "passive")
		)
		(pad "2" smd roundrect
			(at 0.7 0 270)
			(size 0.8 1)
			(layers "F.Cu" "F.Mask" "F.Paste")
			(roundrect_rratio 0.2)
			(net 534 "Net-(D19-A)")
			(pinfunction "A")
			(pintype "passive")
		)
	)
	(footprint "antmicro-footprints:R_0402_1005Metric"
		(layer "F.Cu")
		(at 67.500532 55.769 90)
		(descr "Resistor SMD 0402")
		(tags "resistor SMD 0402")
		(property "Reference" "R306"
			(at -1.281 -1.700532 90)
			(layer "F.SilkS")
			(effects
				(font
					(size 0.7 0.7)
					(thickness 0.15)
				)
				(justify left bottom)
			)
		)
		(property "Value" "R_470R_0402"
			(at -1.011843 1.772046 90)
			(layer "F.Fab")
			(effects
				(font
					(size 0.7 0.7)
					(thickness 0.15)
				)
				(justify left bottom)
			)
		)
		(property "Datasheet" "https://www.bourns.com/docs/product-datasheets/cr.pdf"
			(at 0 0 90)
			(layer "F.Fab")
			(hide yes)
			(effects
				(font
					(size 1.27 1.27)
					(thickness 0.15)
				)
			)
		)
		(property "Description" "SMD Chip Resistor, 470 ohm, ± 1%, 62.5 mW, 0402 [1005 Metric], Thick Film, General Purpose"
			(at 0 0 90)
			(layer "F.Fab")
			(hide yes)
			(effects
				(font
					(size 1.27 1.27)
					(thickness 0.15)
				)
			)
		)
		(property "MPN" "CR0402-FX-4700GLF"
			(at 0 0 90)
			(unlocked yes)
			(layer "F.Fab")
			(hide yes)
			(effects
				(font
					(size 1 1)
					(thickness 0.15)
				)
			)
		)
		(property "Manufacturer" "Bourns"
			(at 0 0 90)
			(unlocked yes)
			(layer "F.Fab")
			(hide yes)
			(effects
				(font
					(size 1 1)
					(thickness 0.15)
				)
			)
		)
		(property "License" "Apache-2.0"
			(at 0 0 90)
			(unlocked yes)
			(layer "F.Fab")
			(hide yes)
			(effects
				(font
					(size 1 1)
					(thickness 0.15)
				)
			)
		)
		(property "Author" "Antmicro"
			(at 0 0 90)
			(unlocked yes)
			(layer "F.Fab")
			(hide yes)
			(effects
				(font
					(size 1 1)
					(thickness 0.15)
				)
			)
		)
		(property "Val" "470R"
			(at 0 0 90)
			(unlocked yes)
			(layer "F.Fab")
			(hide yes)
			(effects
				(font
					(size 1 1)
					(thickness 0.15)
				)
			)
		)
		(property "Tolerance" "1%"
			(at 0 0 90)
			(unlocked yes)
			(layer "F.Fab")
			(hide yes)
			(effects
				(font
					(size 1 1)
					(thickness 0.15)
				)
			)
		)
		(sheetname "/SoM_Power/")
		(sheetfile "som_power.kicad_sch")
		(attr smd)
		(fp_poly
			(pts
				(xy -0.925 -0.47) (xy -0.925 0.47) (xy 0.925 0.47) (xy 0.925 -0.47)
			)
			(stroke
				(width 0.05)
				(type default)
			)
			(fill no)
			(layer "F.CrtYd")
		)
		(fp_poly
			(pts
				(xy -0.5 -0.25) (xy -0.5 0.25) (xy 0.5 0.25) (xy 0.5 -0.25)
			)
			(stroke
				(width 0.15)
				(type solid)
			)
			(fill no)
			(layer "F.Fab")
		)
		(fp_text user "License: Apache-2.0"
			(at -0.949999 5.169 90)
			(layer "F.Fab")
			(effects
				(font
					(size 0.7 0.7)
					(thickness 0.15)
				)
				(justify left bottom)
			)
		)
		(fp_text user "Author: Antmicro"
			(at -0.95 4.169 90)
			(layer "F.Fab")
			(effects
				(font
					(size 0.7 0.7)
					(thickness 0.15)
				)
				(justify left bottom)
			)
		)
		(fp_text user "${REFERENCE}"
			(at -0.95 3.168 90)
			(layer "F.Fab")
			(effects
				(font
					(size 0.7 0.7)
					(thickness 0.15)
				)
				(justify left bottom)
			)
		)
		(pad "1" smd roundrect
			(at -0.48 0 90)
			(size 0.59 0.64)
			(layers "F.Cu" "F.Mask" "F.Paste")
			(roundrect_rratio 0.25)
			(net 549 "Net-(D52-A)")
			(pintype "passive")
		)
		(pad "2" smd roundrect
			(at 0.48 0 90)
			(size 0.59 0.64)
			(layers "F.Cu" "F.Mask" "F.Paste")
			(roundrect_rratio 0.25)
			(net 491 "+5V_AON")
			(pintype "passive")
		)
	)
	(footprint "antmicro-footprints:C_0805_2012Metric"
		(layer "F.Cu")
		(at 173.17 93.32 -90)
		(descr "Capacitor SMD 0805")
		(tags "capacitor SMD 0805")
		(property "Reference" "C298"
			(at 1.745 0.425 90)
			(layer "F.SilkS")
			(effects
				(font
					(size 0.7 0.7)
					(thickness 0.15)
				)
				(justify right top)
			)
		)
		(property "Value" "C_22u_25V_0805"
			(at -2.055717 1.963152 90)
			(layer "F.Fab")
			(effects
				(font
					(size 0.7 0.7)
					(thickness 0.15)
				)
				(justify right top)
			)
		)
		(property "Datasheet" "https://product.samsungsem.com/mlcc/CL21A226MAYNNN.do"
			(at 0 0 90)
			(layer "F.Fab")
			(hide yes)
			(effects
				(font
					(size 1.27 1.27)
					(thickness 0.15)
				)
			)
		)
		(property "Description" "SMT Multilayer Ceramic Capacitor, 22uF, +/-20%, 25V, X5R, 0805 [2012 Metric]"
			(at 0 0 90)
			(layer "F.Fab")
			(hide yes)
			(effects
				(font
					(size 1.27 1.27)
					(thickness 0.15)
				)
			)
		)
		(property "MPN" "CL21A226MAYNNNE"
			(at 0 0 270)
			(unlocked yes)
			(layer "F.Fab")
			(hide yes)
			(effects
				(font
					(size 1 1)
					(thickness 0.15)
				)
			)
		)
		(property "Manufacturer" "Samsung Electro-Mechanics"
			(at 0 0 270)
			(unlocked yes)
			(layer "F.Fab")
			(hide yes)
			(effects
				(font
					(size 1 1)
					(thickness 0.15)
				)
			)
		)
		(property "License" "Apache-2.0"
			(at 0 0 270)
			(unlocked yes)
			(layer "F.Fab")
			(hide yes)
			(effects
				(font
					(size 1 1)
					(thickness 0.15)
				)
			)
		)
		(property "Author" "Antmicro"
			(at 0 0 270)
			(unlocked yes)
			(layer "F.Fab")
			(hide yes)
			(effects
				(font
					(size 1 1)
					(thickness 0.15)
				)
			)
		)
		(property "Val" "22u"
			(at 0 0 270)
			(unlocked yes)
			(layer "F.Fab")
			(hide yes)
			(effects
				(font
					(size 1 1)
					(thickness 0.15)
				)
			)
		)
		(property "Voltage" "25V"
			(at 0 0 270)
			(unlocked yes)
			(layer "F.Fab")
			(hide yes)
			(effects
				(font
					(size 1 1)
					(thickness 0.15)
				)
			)
		)
		(property "Dielectric" "X5R"
			(at 0 0 270)
			(unlocked yes)
			(layer "F.Fab")
			(hide yes)
			(effects
				(font
					(size 1 1)
					(thickness 0.15)
				)
			)
		)
		(property "Public" "False"
			(at 0 0 270)
			(unlocked yes)
			(layer "F.Fab")
			(hide yes)
			(effects
				(font
					(size 1 1)
					(thickness 0.15)
				)
			)
		)
		(component_classes
			(class "DCDC_SOM")
		)
		(sheetname "/DCDC/")
		(sheetfile "dcdc.kicad_sch")
		(attr smd)
		(fp_line
			(start -0.3 0.7)
			(end 0.3 0.7)
			(stroke
				(width 0.15)
				(type solid)
			)
			(layer "F.SilkS")
		)
		(fp_line
			(start -0.3 -0.7)
			(end 0.3 -0.7)
			(stroke
				(width 0.15)
				(type solid)
			)
			(layer "F.SilkS")
		)
		(fp_rect
			(start 1.95 -0.9)
			(end -1.95 0.9)
			(stroke
				(width 0.05)
				(type default)
			)
			(fill no)
			(layer "F.CrtYd")
		)
		(fp_rect
			(start -0.95 -0.675)
			(end 0.95 0.675)
			(stroke
				(width 0.15)
				(type solid)
			)
			(fill no)
			(layer "F.Fab")
		)
		(fp_text user "License: Apache-2.0"
			(at -1.9 4.947 90)
			(layer "F.Fab")
			(effects
				(font
					(size 0.7 0.7)
					(thickness 0.15)
				)
				(justify right top)
			)
		)
		(fp_text user "${REFERENCE}"
			(at -1.9 3.947 90)
			(layer "F.Fab")
			(effects
				(font
					(size 0.7 0.7)
					(thickness 0.15)
				)
				(justify right top)
			)
		)
		(fp_text user "Author: Antmicro"
			(at -1.9 5.947 90)
			(layer "F.Fab")
			(effects
				(font
					(size 0.7 0.7)
					(thickness 0.15)
				)
				(justify right top)
			)
		)
		(pad "1" smd roundrect
			(at -1.1 0 270)
			(size 1.2 1.3)
			(layers "F.Cu" "F.Mask" "F.Paste")
			(roundrect_rratio 0.25)
			(net 1 "GND")
			(pintype "passive")
		)
		(pad "2" smd roundrect
			(at 1.1 0 270)
			(size 1.2 1.3)
			(layers "F.Cu" "F.Mask" "F.Paste")
			(roundrect_rratio 0.25)
			(net 903 "/DCDC/16V_OUT")
			(pintype "passive")
		)
	)
	(footprint "antmicro-footprints:C_0402_1005Metric"
		(layer "F.Cu")
		(at 109.8 128.5)
		(descr "Capacitor SMD 0402")
		(tags "capacitor SMD 0402")
		(property "Reference" "C196"
			(at -0.9 -0.4 180)
			(layer "F.SilkS")
			(effects
				(font
					(size 0.7 0.7)
					(thickness 0.15)
				)
				(justify right top)
			)
		)
		(property "Value" "C_220n_0402"
			(at -1.022927 2.155213 180)
			(layer "F.Fab")
			(effects
				(font
					(size 0.7 0.7)
					(thickness 0.15)
				)
				(justify right top)
			)
		)
		(property "Datasheet" "https://www.yageo.com/en/Chart/Download/pdf/CC0402KRX5R6BB224"
			(at 0 0 180)
			(layer "F.Fab")
			(hide yes)
			(effects
				(font
					(size 1.27 1.27)
					(thickness 0.15)
				)
			)
		)
		(property "Description" "SMD Multilayer Ceramic Capacitor, 0.22 µF, 10 V, 0402 [1005 Metric], ± 10%, X5R, CC Series"
			(at 0 0 180)
			(layer "F.Fab")
			(hide yes)
			(effects
				(font
					(size 1.27 1.27)
					(thickness 0.15)
				)
			)
		)
		(property "MPN" "CC0402KRX5R6BB224"
			(at 0 0 180)
			(unlocked yes)
			(layer "F.Fab")
			(hide yes)
			(effects
				(font
					(size 1 1)
					(thickness 0.15)
				)
			)
		)
		(property "Val" "220n"
			(at 0 0 180)
			(unlocked yes)
			(layer "F.Fab")
			(hide yes)
			(effects
				(font
					(size 1 1)
					(thickness 0.15)
				)
			)
		)
		(property "Voltage" "25V"
			(at 0 0 180)
			(unlocked yes)
			(layer "F.Fab")
			(hide yes)
			(effects
				(font
					(size 1 1)
					(thickness 0.15)
				)
			)
		)
		(property "Dielectric" "X7R"
			(at 0 0 180)
			(unlocked yes)
			(layer "F.Fab")
			(hide yes)
			(effects
				(font
					(size 1 1)
					(thickness 0.15)
				)
			)
		)
		(property "Manufacturer" "YAGEO"
			(at 0 0 180)
			(unlocked yes)
			(layer "F.Fab")
			(hide yes)
			(effects
				(font
					(size 1 1)
					(thickness 0.15)
				)
			)
		)
		(property "License" "Apache-2.0"
			(at 0 0 180)
			(unlocked yes)
			(layer "F.Fab")
			(hide yes)
			(effects
				(font
					(size 1 1)
					(thickness 0.15)
				)
			)
		)
		(property "Author" "Antmicro"
			(at 0 0 180)
			(unlocked yes)
			(layer "F.Fab")
			(hide yes)
			(effects
				(font
					(size 1 1)
					(thickness 0.15)
				)
			)
		)
		(property "Public" "False"
			(at 0 0 180)
			(unlocked yes)
			(layer "F.Fab")
			(hide yes)
			(effects
				(font
					(size 1 1)
					(thickness 0.15)
				)
			)
		)
		(sheetname "/M.2/")
		(sheetfile "m2.kicad_sch")
		(attr smd)
		(fp_poly
			(pts
				(xy -0.925 -0.47) (xy -0.925 0.47) (xy 0.925 0.47) (xy 0.925 -0.47)
			)
			(stroke
				(width 0.05)
				(type default)
			)
			(fill no)
			(layer "F.CrtYd")
		)
		(fp_line
			(start -0.494 -0.25)
			(end 0.504 -0.25)
			(stroke
				(width 0.15)
				(type solid)
			)
			(layer "F.Fab")
		)
		(fp_line
			(start -0.494 0.248)
			(end -0.494 -0.25)
			(stroke
				(width 0.15)
				(type solid)
			)
			(layer "F.Fab")
		)
		(fp_line
			(start 0.504 -0.25)
			(end 0.504 0.248)
			(stroke
				(width 0.15)
				(type solid)
			)
			(layer "F.Fab")
		)
		(fp_line
			(start 0.504 0.248)
			(end -0.494 0.248)
			(stroke
				(width 0.15)
				(type solid)
			)
			(layer "F.Fab")
		)
		(fp_text user "${REFERENCE}"
			(at -0.939 4.599 180)
			(layer "F.Fab")
			(effects
				(font
					(size 0.7 0.7)
					(thickness 0.15)
				)
				(justify right top)
			)
		)
		(fp_text user "License: Apache-2.0"
			(at -0.939 5.799 180)
			(layer "F.Fab")
			(effects
				(font
					(size 0.7 0.7)
					(thickness 0.15)
				)
				(justify right top)
			)
		)
		(fp_text user "Author: Antmicro"
			(at -0.939 3.399 180)
			(layer "F.Fab")
			(effects
				(font
					(size 0.7 0.7)
					(thickness 0.15)
				)
				(justify right top)
			)
		)
		(pad "1" smd roundrect
			(at -0.48 0)
			(size 0.59 0.64)
			(layers "F.Cu" "F.Mask" "F.Paste")
			(roundrect_rratio 0.25)
			(net 16 "/M.2/PCIe_{C1x1}.TX0-")
			(pintype "passive")
		)
		(pad "2" smd roundrect
			(at 0.48 0)
			(size 0.59 0.64)
			(layers "F.Cu" "F.Mask" "F.Paste")
			(roundrect_rratio 0.25)
			(net 444 "/M.2/M2_E_PET0_N")
			(pintype "passive")
		)
	)
	(footprint "antmicro-footprints:R_0402_1005Metric"
		(layer "F.Cu")
		(at 195.1 131.3)
		(descr "Resistor SMD 0402")
		(tags "resistor SMD 0402")
		(property "Reference" "R71"
			(at -1.1 5.3 0)
			(layer "F.SilkS")
			(effects
				(font
					(size 0.7 0.7)
					(thickness 0.15)
				)
				(justify left bottom)
			)
		)
		(property "Value" "R_0R_0402"
			(at -1.011843 1.772046 0)
			(layer "F.Fab")
			(effects
				(font
					(size 0.7 0.7)
					(thickness 0.15)
				)
				(justify left bottom)
			)
		)
		(property "Datasheet" "https://industrial.panasonic.com/cdbs/www-data/pdf/RDA0000/AOA0000C301.pdf"
			(at 0 0 0)
			(layer "F.Fab")
			(hide yes)
			(effects
				(font
					(size 1.27 1.27)
					(thickness 0.15)
				)
			)
		)
		(property "Description" "SMD Chip Resistor, Jumper, 0 ohm, 100 mW, 0402 [1005 Metric], Thick Film, General Purpose"
			(at 0 0 0)
			(layer "F.Fab")
			(hide yes)
			(effects
				(font
					(size 1.27 1.27)
					(thickness 0.15)
				)
			)
		)
		(property "MPN" "ERJ2GE0R00X"
			(at 0 0 0)
			(unlocked yes)
			(layer "F.Fab")
			(hide yes)
			(effects
				(font
					(size 1 1)
					(thickness 0.15)
				)
			)
		)
		(property "Manufacturer" "Panasonic"
			(at 0 0 0)
			(unlocked yes)
			(layer "F.Fab")
			(hide yes)
			(effects
				(font
					(size 1 1)
					(thickness 0.15)
				)
			)
		)
		(property "License" "Apache-2.0"
			(at 0 0 0)
			(unlocked yes)
			(layer "F.Fab")
			(hide yes)
			(effects
				(font
					(size 1 1)
					(thickness 0.15)
				)
			)
		)
		(property "Author" "Antmicro"
			(at 0 0 0)
			(unlocked yes)
			(layer "F.Fab")
			(hide yes)
			(effects
				(font
					(size 1 1)
					(thickness 0.15)
				)
			)
		)
		(property "Val" "0R"
			(at 0 0 0)
			(unlocked yes)
			(layer "F.Fab")
			(hide yes)
			(effects
				(font
					(size 1 1)
					(thickness 0.15)
				)
			)
		)
		(property "Tolerance" "~"
			(at 0 0 0)
			(unlocked yes)
			(layer "F.Fab")
			(hide yes)
			(effects
				(font
					(size 1 1)
					(thickness 0.15)
				)
			)
		)
		(property "Current" "1A"
			(at 0 0 180)
			(unlocked yes)
			(layer "F.Fab")
			(hide yes)
			(effects
				(font
					(size 1 1)
					(thickness 0.15)
				)
			)
		)
		(sheetname "/USB Hub/")
		(sheetfile "usb_hub.kicad_sch")
		(attr smd exclude_from_pos_files exclude_from_bom dnp)
		(fp_poly
			(pts
				(xy -0.925 -0.47) (xy -0.925 0.47) (xy 0.925 0.47) (xy 0.925 -0.47)
			)
			(stroke
				(width 0.05)
				(type default)
			)
			(fill no)
			(layer "F.CrtYd")
		)
		(fp_poly
			(pts
				(xy -0.5 -0.25) (xy -0.5 0.25) (xy 0.5 0.25) (xy 0.5 -0.25)
			)
			(stroke
				(width 0.15)
				(type solid)
			)
			(fill no)
			(layer "F.Fab")
		)
		(fp_text user "${REFERENCE}"
			(at -0.95 3.168 0)
			(layer "F.Fab")
			(effects
				(font
					(size 0.7 0.7)
					(thickness 0.15)
				)
				(justify left bottom)
			)
		)
		(fp_text user "Author: Antmicro"
			(at -0.95 4.169 0)
			(layer "F.Fab")
			(effects
				(font
					(size 0.7 0.7)
					(thickness 0.15)
				)
				(justify left bottom)
			)
		)
		(fp_text user "License: Apache-2.0"
			(at -0.949999 5.169 0)
			(layer "F.Fab")
			(effects
				(font
					(size 0.7 0.7)
					(thickness 0.15)
				)
				(justify left bottom)
			)
		)
		(pad "1" smd roundrect
			(at -0.48 0)
			(size 0.59 0.64)
			(layers "F.Cu" "F.Mask" "F.Paste")
			(roundrect_rratio 0.25)
			(net 853 "/I2C_{SYS}.SCL")
			(pintype "passive")
		)
		(pad "2" smd roundrect
			(at 0.48 0)
			(size 0.59 0.64)
			(layers "F.Cu" "F.Mask" "F.Paste")
			(roundrect_rratio 0.25)
			(net 1234 "Net-(U21-PF26)")
			(pintype "passive")
		)
	)
	(footprint "antmicro-footprints:TP_SMD_0.75mm"
		(layer "F.Cu")
		(at 205.8 76.8)
		(property "Reference" "TP77"
			(at 0.5 -0.6 90)
			(layer "F.SilkS")
			(effects
				(font
					(size 0.7 0.7)
					(thickness 0.15)
				)
				(justify left bottom)
			)
		)
		(property "Value" "TP_0.75mm_SMD"
			(at 0 1.2 0)
			(layer "F.Fab")
			(effects
				(font
					(size 0.7 0.7)
					(thickness 0.15)
				)
				(justify left bottom)
			)
		)
		(property "Description" "SMT test point"
			(at 0 0 0)
			(layer "F.Fab")
			(hide yes)
			(effects
				(font
					(size 1.27 1.27)
					(thickness 0.15)
				)
			)
		)
		(property "MPN" ""
			(at 0 0 0)
			(unlocked yes)
			(layer "F.Fab")
			(hide yes)
			(effects
				(font
					(size 1 1)
					(thickness 0.15)
				)
			)
		)
		(property "Manufacturer" ""
			(at 0 0 0)
			(unlocked yes)
			(layer "F.Fab")
			(hide yes)
			(effects
				(font
					(size 1 1)
					(thickness 0.15)
				)
			)
		)
		(property "Author" "Antmicro"
			(at 0 0 0)
			(unlocked yes)
			(layer "F.Fab")
			(hide yes)
			(effects
				(font
					(size 1 1)
					(thickness 0.15)
				)
			)
		)
		(property "License" "Apache-2.0"
			(at 0 0 0)
			(unlocked yes)
			(layer "F.Fab")
			(hide yes)
			(effects
				(font
					(size 1 1)
					(thickness 0.15)
				)
			)
		)
		(sheetname "/Power/")
		(sheetfile "power.kicad_sch")
		(attr exclude_from_pos_files exclude_from_bom)
		(fp_circle
			(center 0 0)
			(end 0.475 0)
			(stroke
				(width 0.05)
				(type default)
			)
			(fill no)
			(layer "F.CrtYd")
		)
		(fp_text user "Author: Antmicro"
			(at -0.4 3.901 0)
			(layer "F.Fab")
			(effects
				(font
					(size 0.7 0.7)
					(thickness 0.15)
				)
				(justify left bottom)
			)
		)
		(fp_text user "License: Apache-2.0"
			(at -0.4 5.101 0)
			(layer "F.Fab")
			(effects
				(font
					(size 0.7 0.7)
					(thickness 0.15)
				)
				(justify left bottom)
			)
		)
		(fp_text user "${REFERENCE}"
			(at -0.4 2.7 0)
			(layer "F.Fab")
			(effects
				(font
					(size 0.7 0.7)
					(thickness 0.15)
				)
				(justify left bottom)
			)
		)
		(pad "1" smd circle
			(at 0 0)
			(size 0.75 0.75)
			(layers "F.Cu" "F.Mask")
			(net 525 "/Power/USBPD2_HV")
			(pinfunction "1")
			(pintype "passive")
		)
	)
	(footprint "antmicro-footprints:R_0402_1005Metric"
		(layer "F.Cu")
		(at 88 62.5 180)
		(descr "Resistor SMD 0402")
		(tags "resistor SMD 0402")
		(property "Reference" "R19"
			(at 17 -8.75 0)
			(layer "F.SilkS")
			(effects
				(font
					(size 0.7 0.7)
					(thickness 0.15)
				)
				(justify right top)
			)
		)
		(property "Value" "R_499k_0402"
			(at -1.011843 1.772047 0)
			(layer "F.Fab")
			(effects
				(font
					(size 0.7 0.7)
					(thickness 0.15)
				)
				(justify right top)
			)
		)
		(property "Datasheet" "https://www.mouser.com/datasheet/2/54/cr-1858361.pdf"
			(at 0 0 0)
			(layer "F.Fab")
			(hide yes)
			(effects
				(font
					(size 1.27 1.27)
					(thickness 0.15)
				)
			)
		)
		(property "Description" "SMD Chip Resistor, 499 kohm, ± 1%, 63 mW, 0402 [1005 Metric], Thick Film, General Purpose"
			(at 0 0 0)
			(layer "F.Fab")
			(hide yes)
			(effects
				(font
					(size 1.27 1.27)
					(thickness 0.15)
				)
			)
		)
		(property "MPN" "CR0402-FX-4993GLF"
			(at 0 0 180)
			(unlocked yes)
			(layer "F.Fab")
			(hide yes)
			(effects
				(font
					(size 1 1)
					(thickness 0.15)
				)
			)
		)
		(property "Manufacturer" "Bourns"
			(at 0 0 180)
			(unlocked yes)
			(layer "F.Fab")
			(hide yes)
			(effects
				(font
					(size 1 1)
					(thickness 0.15)
				)
			)
		)
		(property "License" "Apache-2.0"
			(at 0 0 180)
			(unlocked yes)
			(layer "F.Fab")
			(hide yes)
			(effects
				(font
					(size 1 1)
					(thickness 0.15)
				)
			)
		)
		(property "Author" "Antmicro"
			(at 0 0 180)
			(unlocked yes)
			(layer "F.Fab")
			(hide yes)
			(effects
				(font
					(size 1 1)
					(thickness 0.15)
				)
			)
		)
		(property "Val" "499k"
			(at 0 0 180)
			(unlocked yes)
			(layer "F.Fab")
			(hide yes)
			(effects
				(font
					(size 1 1)
					(thickness 0.15)
				)
			)
		)
		(property "Tolerance" "1%"
			(at 0 0 180)
			(unlocked yes)
			(layer "F.Fab")
			(hide yes)
			(effects
				(font
					(size 1 1)
					(thickness 0.15)
				)
			)
		)
		(sheetname "/SoM_Power/")
		(sheetfile "som_power.kicad_sch")
		(attr smd)
		(fp_rect
			(start -0.925 -0.47)
			(end 0.925 0.47)
			(stroke
				(width 0.05)
				(type default)
			)
			(fill no)
			(layer "F.CrtYd")
		)
		(fp_rect
			(start -0.5 -0.25)
			(end 0.5 0.25)
			(stroke
				(width 0.15)
				(type solid)
			)
			(fill no)
			(layer "F.Fab")
		)
		(fp_text user "${REFERENCE}"
			(at -0.95 3.168 0)
			(layer "F.Fab")
			(effects
				(font
					(size 0.7 0.7)
					(thickness 0.15)
				)
				(justify right top)
			)
		)
		(fp_text user "Author: Antmicro"
			(at -0.95 4.169 0)
			(layer "F.Fab")
			(effects
				(font
					(size 0.7 0.7)
					(thickness 0.15)
				)
				(justify right top)
			)
		)
		(fp_text user "License: Apache-2.0"
			(at -0.95 5.169 0)
			(layer "F.Fab")
			(effects
				(font
					(size 0.7 0.7)
					(thickness 0.15)
				)
				(justify right top)
			)
		)
		(pad "1" smd roundrect
			(at -0.48 0 180)
			(size 0.59 0.64)
			(layers "F.Cu" "F.Mask" "F.Paste")
			(roundrect_rratio 0.25)
			(net 246 "/SoM_Power/~{VDDIN_PWR_BAD}")
			(pintype "passive")
		)
		(pad "2" smd roundrect
			(at 0.48 0 180)
			(size 0.59 0.64)
			(layers "F.Cu" "F.Mask" "F.Paste")
			(roundrect_rratio 0.25)
			(net 213 "+5V_SOM")
			(pintype "passive")
		)
	)
	(footprint "antmicro-footprints:C_0402_1005Metric"
		(layer "F.Cu")
		(at 211.8 103.325 180)
		(descr "Capacitor SMD 0402")
		(tags "capacitor SMD 0402")
		(property "Reference" "C117"
			(at 0.94 0.415 0)
			(layer "F.SilkS")
			(effects
				(font
					(size 0.7 0.7)
					(thickness 0.15)
				)
				(justify right top)
			)
		)
		(property "Value" "C_100n_0402"
			(at -1.022927 2.155213 0)
			(layer "F.Fab")
			(effects
				(font
					(size 0.7 0.7)
					(thickness 0.15)
				)
				(justify right top)
			)
		)
		(property "Datasheet" "https://www.murata.com/products/productdetail?partno=GRM155R61H104KE14%23"
			(at 0 0 0)
			(layer "F.Fab")
			(hide yes)
			(effects
				(font
					(size 1.27 1.27)
					(thickness 0.15)
				)
			)
		)
		(property "Description" "SMD Multilayer Ceramic Capacitor, 0.1 µF, 50 V, 0402 [1005 Metric], ± 10%, X5R, GRM Series"
			(at 0 0 0)
			(layer "F.Fab")
			(hide yes)
			(effects
				(font
					(size 1.27 1.27)
					(thickness 0.15)
				)
			)
		)
		(property "Manufacturer" "Murata"
			(at 0 0 180)
			(unlocked yes)
			(layer "F.Fab")
			(hide yes)
			(effects
				(font
					(size 1 1)
					(thickness 0.15)
				)
			)
		)
		(property "MPN" "GRM155R61H104KE14D"
			(at 0 0 180)
			(unlocked yes)
			(layer "F.Fab")
			(hide yes)
			(effects
				(font
					(size 1 1)
					(thickness 0.15)
				)
			)
		)
		(property "Val" "100n"
			(at 0 0 180)
			(unlocked yes)
			(layer "F.Fab")
			(hide yes)
			(effects
				(font
					(size 1 1)
					(thickness 0.15)
				)
			)
		)
		(property "License" "Apache-2.0"
			(at 0 0 180)
			(unlocked yes)
			(layer "F.Fab")
			(hide yes)
			(effects
				(font
					(size 1 1)
					(thickness 0.15)
				)
			)
		)
		(property "Author" "Antmicro"
			(at 0 0 180)
			(unlocked yes)
			(layer "F.Fab")
			(hide yes)
			(effects
				(font
					(size 1 1)
					(thickness 0.15)
				)
			)
		)
		(property "Voltage" "50V"
			(at 0 0 180)
			(unlocked yes)
			(layer "F.Fab")
			(hide yes)
			(effects
				(font
					(size 1 1)
					(thickness 0.15)
				)
			)
		)
		(property "Dielectric" "X5R"
			(at 0 0 180)
			(unlocked yes)
			(layer "F.Fab")
			(hide yes)
			(effects
				(font
					(size 1 1)
					(thickness 0.15)
				)
			)
		)
		(sheetname "/Recovery USB/")
		(sheetfile "recovery_usb.kicad_sch")
		(attr smd)
		(fp_rect
			(start -0.925 -0.47)
			(end 0.925 0.47)
			(stroke
				(width 0.05)
				(type default)
			)
			(fill no)
			(layer "F.CrtYd")
		)
		(fp_line
			(start 0.504 0.248)
			(end -0.494 0.248)
			(stroke
				(width 0.15)
				(type solid)
			)
			(layer "F.Fab")
		)
		(fp_line
			(start 0.504 -0.25)
			(end 0.504 0.248)
			(stroke
				(width 0.15)
				(type solid)
			)
			(layer "F.Fab")
		)
		(fp_line
			(start -0.494 0.248)
			(end -0.494 -0.25)
			(stroke
				(width 0.15)
				(type solid)
			)
			(layer "F.Fab")
		)
		(fp_line
			(start -0.494 -0.25)
			(end 0.504 -0.25)
			(stroke
				(width 0.15)
				(type solid)
			)
			(layer "F.Fab")
		)
		(fp_text user "${REFERENCE}"
			(at -0.939 4.599 0)
			(layer "F.Fab")
			(effects
				(font
					(size 0.7 0.7)
					(thickness 0.15)
				)
				(justify right top)
			)
		)
		(fp_text user "Author: Antmicro"
			(at -0.939 3.399 0)
			(layer "F.Fab")
			(effects
				(font
					(size 0.7 0.7)
					(thickness 0.15)
				)
				(justify right top)
			)
		)
		(fp_text user "License: Apache-2.0"
			(at -0.939 5.799 0)
			(layer "F.Fab")
			(effects
				(font
					(size 0.7 0.7)
					(thickness 0.15)
				)
				(justify right top)
			)
		)
		(pad "1" smd roundrect
			(at -0.48 0 180)
			(size 0.59 0.64)
			(layers "F.Cu" "F.Mask" "F.Paste")
			(roundrect_rratio 0.25)
			(net 2 "+3V3")
			(pintype "passive")
		)
		(pad "2" smd roundrect
			(at 0.48 0 180)
			(size 0.59 0.64)
			(layers "F.Cu" "F.Mask" "F.Paste")
			(roundrect_rratio 0.25)
			(net 1 "GND")
			(pintype "passive")
		)
	)
	(footprint "antmicro-footprints:Fiducial_1mm_Mask3mm"
		(layer "F.Cu")
		(at 61.67 70.35)
		(descr "Circular Fiducial, 1.5mm bare copper, 3mm soldermask opening")
		(tags "fiducial")
		(property "Reference" "FD1"
			(at -1.03 2.5 0)
			(layer "F.SilkS")
			(effects
				(font
					(size 0.7 0.7)
					(thickness 0.15)
				)
				(justify left bottom)
			)
		)
		(property "Value" "Fiducial_1mm_Mask3mm"
			(at 0 2.603 0)
			(layer "F.Fab")
			(effects
				(font
					(size 0.7 0.7)
					(thickness 0.15)
				)
				(justify left bottom)
			)
		)
		(property "Description" "Fiducial mask"
			(at 0 0 0)
			(layer "F.Fab")
			(hide yes)
			(effects
				(font
					(size 1.27 1.27)
					(thickness 0.15)
				)
			)
		)
		(property "Author" "Antmicro"
			(at 0 0 0)
			(unlocked yes)
			(layer "F.Fab")
			(hide yes)
			(effects
				(font
					(size 1 1)
					(thickness 0.15)
				)
			)
		)
		(property "License" "Apache-2.0"
			(at 0 0 0)
			(unlocked yes)
			(layer "F.Fab")
			(hide yes)
			(effects
				(font
					(size 1 1)
					(thickness 0.15)
				)
			)
		)
		(sheetname "/")
		(sheetfile "jetson-agx-thor-baseboard.kicad_sch")
		(attr exclude_from_pos_files exclude_from_bom)
		(fp_circle
			(center 0 0)
			(end 1.5 0)
			(stroke
				(width 0.05)
				(type solid)
			)
			(fill no)
			(layer "F.CrtYd")
		)
		(fp_circle
			(center 0 0)
			(end 1.5 0)
			(stroke
				(width 0.15)
				(type solid)
			)
			(fill no)
			(layer "F.Fab")
		)
		(fp_text user "${REFERENCE}"
			(at -1.25 4.603 0)
			(layer "F.Fab")
			(effects
				(font
					(size 0.7 0.7)
					(thickness 0.15)
				)
				(justify left bottom)
			)
		)
		(fp_text user "License: Apache-2.0"
			(at -1.25 7.003 0)
			(layer "F.Fab")
			(effects
				(font
					(size 0.7 0.7)
					(thickness 0.15)
				)
				(justify left bottom)
			)
		)
		(fp_text user "Author: Antmicro"
			(at -1.25 5.803 0)
			(layer "F.Fab")
			(effects
				(font
					(size 0.7 0.7)
					(thickness 0.15)
				)
				(justify left bottom)
			)
		)
		(pad "" smd circle
			(at 0 0)
			(size 1 1)
			(layers "F.Cu" "F.Mask")
			(solder_mask_margin 1)
			(clearance 1)
		)
	)
	(footprint "antmicro-footprints:DHVQFN-14-1EP_2.5x3mm"
		(layer "F.Cu")
		(at 152.48 118.75 180)
		(property "Reference" "U1"
			(at 1.18 2.95 0)
			(layer "F.SilkS")
			(effects
				(font
					(size 0.7 0.7)
					(thickness 0.15)
				)
				(justify right top)
			)
		)
		(property "Value" "NTS0104_DHVQFN"
			(at 0 2.897999 0)
			(layer "F.Fab")
			(effects
				(font
					(size 0.7 0.7)
					(thickness 0.15)
				)
				(justify right top)
			)
		)
		(property "Datasheet" "https://www.nxp.com/docs/en/data-sheet/NTS0104.pdf"
			(at 0 0 0)
			(layer "F.Fab")
			(hide yes)
			(effects
				(font
					(size 1.27 1.27)
					(thickness 0.15)
				)
			)
		)
		(property "Description" "Voltage Level Translator Bidirectional 1 Circuit 4 Channel 50Mbps 14-DHVQFN (2.5x3)"
			(at 0 0 0)
			(layer "F.Fab")
			(hide yes)
			(effects
				(font
					(size 1.27 1.27)
					(thickness 0.15)
				)
			)
		)
		(property "MPN" "NTS0104BQ"
			(at 0 0 180)
			(unlocked yes)
			(layer "F.Fab")
			(hide yes)
			(effects
				(font
					(size 1 1)
					(thickness 0.15)
				)
			)
		)
		(property "Manufacturer" "NXP"
			(at 0 0 180)
			(unlocked yes)
			(layer "F.Fab")
			(hide yes)
			(effects
				(font
					(size 1 1)
					(thickness 0.15)
				)
			)
		)
		(property "Author" "Antmicro"
			(at 0 0 180)
			(unlocked yes)
			(layer "F.Fab")
			(hide yes)
			(effects
				(font
					(size 1 1)
					(thickness 0.15)
				)
			)
		)
		(property "License" "Apache-2.0"
			(at 0 0 180)
			(unlocked yes)
			(layer "F.Fab")
			(hide yes)
			(effects
				(font
					(size 1 1)
					(thickness 0.15)
				)
			)
		)
		(sheetname "/SoM_IO/")
		(sheetfile "som_io.kicad_sch")
		(attr smd)
		(fp_line
			(start 1.35 1.6)
			(end 1.35 1.249)
			(stroke
				(width 0.15)
				(type solid)
			)
			(layer "F.SilkS")
		)
		(fp_line
			(start 1.35 -1.601)
			(end 1.35 -1.25)
			(stroke
				(width 0.15)
				(type solid)
			)
			(layer "F.SilkS")
		)
		(fp_line
			(start 1.35 -1.601)
			(end 0.494 -1.601)
			(stroke
				(width 0.15)
				(type solid)
			)
			(layer "F.SilkS")
		)
		(fp_line
			(start 0.494 1.6)
			(end 1.35 1.6)
			(stroke
				(width 0.15)
				(type solid)
			)
			(layer "F.SilkS")
		)
		(fp_line
			(start -1.35 -1.601)
			(end -1.35 -1.25)
			(stroke
				(width 0.15)
				(type solid)
			)
			(layer "F.SilkS")
		)
		(fp_line
			(start -1.351 1.6)
			(end -0.5 1.6)
			(stroke
				(width 0.15)
				(type solid)
			)
			(layer "F.SilkS")
		)
		(fp_line
			(start -1.351 1.6)
			(end -1.351 1.249)
			(stroke
				(width 0.15)
				(type solid)
			)
			(layer "F.SilkS")
		)
		(fp_line
			(start -1.351 -1.601)
			(end -0.499999 -1.601)
			(stroke
				(width 0.15)
				(type solid)
			)
			(layer "F.SilkS")
		)
		(fp_circle
			(center -0.7 -1.85)
			(end -0.653 -1.85)
			(stroke
				(width 0.15)
				(type solid)
			)
			(fill yes)
			(layer "F.SilkS")
		)
		(fp_poly
			(pts
				(xy -1.85 -2) (xy 1.8 -2) (xy 1.8 1.95) (xy -1.85 1.95)
			)
			(stroke
				(width 0.05)
				(type solid)
			)
			(fill no)
			(layer "F.CrtYd")
		)
		(fp_line
			(start 1.249 -1.5)
			(end 1.248999 1.499)
			(stroke
				(width 0.15)
				(type solid)
			)
			(layer "F.Fab")
		)
		(fp_line
			(start 1.248999 1.499)
			(end -1.25 1.499001)
			(stroke
				(width 0.15)
				(type solid)
			)
			(layer "F.Fab")
		)
		(fp_line
			(start -1 -1.5)
			(end 1.249 -1.5)
			(stroke
				(width 0.15)
				(type solid)
			)
			(layer "F.Fab")
		)
		(fp_line
			(start -1.25 1.499001)
			(end -1.25 -1.25)
			(stroke
				(width 0.15)
				(type solid)
			)
			(layer "F.Fab")
		)
		(fp_line
			(start -1.25 -1.25)
			(end -1 -1.5)
			(stroke
				(width 0.15)
				(type solid)
			)
			(layer "F.Fab")
		)
		(fp_text user "${REFERENCE}"
			(at -1.841 4.896999 0)
			(layer "F.Fab")
			(effects
				(font
					(size 0.7 0.7)
					(thickness 0.15)
				)
				(justify right top)
			)
		)
		(fp_text user "License: Apache-2.0"
			(at -1.841001 6.097 0)
			(layer "F.Fab")
			(effects
				(font
					(size 0.7 0.7)
					(thickness 0.15)
				)
				(justify right top)
			)
		)
		(fp_text user "Author: Antmicro"
			(at -1.841001 7.296 0)
			(layer "F.Fab")
			(effects
				(font
					(size 0.7 0.7)
					(thickness 0.15)
				)
				(justify right top)
			)
		)
		(pad "1" smd oval
			(at -0.25 -1.5 180)
			(size 0.3 0.8)
			(layers "F.Cu" "F.Mask" "F.Paste")
			(net 11 "+1V8")
			(pinfunction "VCC_A")
			(pintype "power_in")
		)
		(pad "2" smd oval
			(at -1.25 -1 270)
			(size 0.3 0.8)
			(layers "F.Cu" "F.Mask" "F.Paste")
			(net 331 "/SoM_IO/I2C0_SDA_1V8")
			(pinfunction "A1")
			(pintype "passive")
		)
		(pad "3" smd oval
			(at -1.25 -0.5 270)
			(size 0.3 0.8)
			(layers "F.Cu" "F.Mask" "F.Paste")
			(net 317 "/SoM_IO/I2C0_SCL_1V8")
			(pinfunction "A2")
			(pintype "passive")
		)
		(pad "4" smd oval
			(at -1.249999 0 270)
			(size 0.3 0.8)
			(layers "F.Cu" "F.Mask" "F.Paste")
			(net 145 "/SoM_IO/I2C3_SDA_1V8")
			(pinfunction "A3")
			(pintype "passive")
		)
		(pad "5" smd oval
			(at -1.25 0.494 270)
			(size 0.3 0.8)
			(layers "F.Cu" "F.Mask" "F.Paste")
			(net 60 "/SoM_IO/I2C3_SCL_1V8")
			(pinfunction "A4")
			(pintype "passive")
		)
		(pad "6" smd oval
			(at -1.25 0.994001 270)
			(size 0.3 0.8)
			(layers "F.Cu" "F.Mask" "F.Paste")
			(net 1321 "unconnected-(U1-NC-Pad6)")
			(pinfunction "NC")
			(pintype "no_connect")
		)
		(pad "7" smd oval
			(at -0.25 1.499 180)
			(size 0.3 0.8)
			(layers "F.Cu" "F.Mask" "F.Paste")
			(net 1 "GND")
			(pinfunction "GND")
			(pintype "power_in")
		)
		(pad "8" smd oval
			(at 0.244 1.499 180)
			(size 0.3 0.8)
			(layers "F.Cu" "F.Mask" "F.Paste")
			(net 11 "+1V8")
			(pinfunction "OE")
			(pintype "passive")
		)
		(pad "9" smd oval
			(at 1.249 0.994001 270)
			(size 0.3 0.8)
			(layers "F.Cu" "F.Mask" "F.Paste")
			(net 1320 "unconnected-(U1-NC-Pad9)")
			(pinfunction "NC")
			(pintype "no_connect")
		)
		(pad "10" smd oval
			(at 1.249 0.494 270)
			(size 0.3 0.8)
			(layers "F.Cu" "F.Mask" "F.Paste")
			(net 1000 "/SFP/I2C_{SFP}.SCL")
			(pinfunction "B4")
			(pintype "passive")
		)
		(pad "11" smd oval
			(at 1.248999 0 270)
			(size 0.3 0.8)
			(layers "F.Cu" "F.Mask" "F.Paste")
			(net 999 "/SFP/I2C_{SFP}.SDA")
			(pinfunction "B3")
			(pintype "passive")
		)
		(pad "12" smd oval
			(at 1.249 -0.5 270)
			(size 0.3 0.8)
			(layers "F.Cu" "F.Mask" "F.Paste")
			(net 561 "/Expansion connector/I2C0.SDA")
			(pinfunction "B2")
			(pintype "passive")
		)
		(pad "13" smd oval
			(at 1.249 -1 270)
			(size 0.3 0.8)
			(layers "F.Cu" "F.Mask" "F.Paste")
			(net 407 "/Expansion connector/I2C0.SCL")
			(pinfunction "B1")
			(pintype "passive")
		)
		(pad "14" smd oval
			(at 0.244 -1.5 180)
			(size 0.3 0.8)
			(layers "F.Cu" "F.Mask" "F.Paste")
			(net 2 "+3V3")
			(pinfunction "VCC_B")
			(pintype "power_in")
		)
		(pad "15" smd rect
			(at 0 0 180)
			(size 1 1.5)
			(layers "F.Cu" "F.Mask" "F.Paste")
			(net 1 "GND")
			(pinfunction "GNDPAD")
			(pintype "power_in")
		)
	)
	(footprint "antmicro-footprints:LED_0603_1608Metric_G"
		(layer "F.Cu")
		(at 173 55.31 -90)
		(descr "LED SMD 0603 Green")
		(tags "LED SMD 0603 Green")
		(property "Reference" "D42"
			(at -0.88 1.5 90)
			(layer "F.SilkS")
			(effects
				(font
					(size 0.7 0.7)
					(thickness 0.15)
				)
				(justify right top)
			)
		)
		(property "Value" "LED_G_0603_LTST-C190GKT"
			(at -0.001 1.599 90)
			(layer "F.Fab")
			(effects
				(font
					(size 0.7 0.7)
					(thickness 0.15)
				)
				(justify right top)
			)
		)
		(property "Datasheet" "https://media.digikey.com/pdf/Data%20Sheets/Lite-On%20PDFs/LTST-C190GKT.pdf"
			(at 0 0 90)
			(layer "F.Fab")
			(hide yes)
			(effects
				(font
					(size 1.27 1.27)
					(thickness 0.15)
				)
			)
		)
		(property "Description" "LED, Green, SMD, 0603, 20 mA, 2.1 V, 569 nm"
			(at 0 0 90)
			(layer "F.Fab")
			(hide yes)
			(effects
				(font
					(size 1.27 1.27)
					(thickness 0.15)
				)
			)
		)
		(property "MPN" "LTST-C190GKT"
			(at 0 0 270)
			(unlocked yes)
			(layer "F.Fab")
			(hide yes)
			(effects
				(font
					(size 1 1)
					(thickness 0.15)
				)
			)
		)
		(property "Manufacturer" "Lite-On"
			(at 0 0 270)
			(unlocked yes)
			(layer "F.Fab")
			(hide yes)
			(effects
				(font
					(size 1 1)
					(thickness 0.15)
				)
			)
		)
		(property "Author" "Antmicro"
			(at 0 0 270)
			(unlocked yes)
			(layer "F.Fab")
			(hide yes)
			(effects
				(font
					(size 1 1)
					(thickness 0.15)
				)
			)
		)
		(property "License" "Apache-2.0"
			(at 0 0 270)
			(unlocked yes)
			(layer "F.Fab")
			(hide yes)
			(effects
				(font
					(size 1 1)
					(thickness 0.15)
				)
			)
		)
		(property "Color" "Green"
			(at 0 0 270)
			(unlocked yes)
			(layer "F.Fab")
			(hide yes)
			(effects
				(font
					(size 1 1)
					(thickness 0.15)
				)
			)
		)
		(sheetname "/Power/")
		(sheetfile "power.kicad_sch")
		(attr smd)
		(fp_line
			(start 0.22 0.35)
			(end -0.22 0.35)
			(stroke
				(width 0.15)
				(type solid)
			)
			(layer "F.SilkS")
		)
		(fp_line
			(start -0.094672 0.201008)
			(end -0.094672 -0.198992)
			(stroke
				(width 0.1)
				(type solid)
			)
			(layer "F.SilkS")
		)
		(fp_line
			(start 0.105328 0.201008)
			(end -0.094672 0.001008)
			(stroke
				(width 0.1)
				(type solid)
			)
			(layer "F.SilkS")
		)
		(fp_line
			(start 0.105328 0.201008)
			(end 0.105328 -0.198992)
			(stroke
				(width 0.1)
				(type solid)
			)
			(layer "F.SilkS")
		)
		(fp_line
			(start -0.094672 0.001008)
			(end -0.24 0.001008)
			(stroke
				(width 0.1)
				(type solid)
			)
			(layer "F.SilkS")
		)
		(fp_line
			(start -0.094672 0.001008)
			(end 0.105328 -0.198992)
			(stroke
				(width 0.1)
				(type solid)
			)
			(layer "F.SilkS")
		)
		(fp_line
			(start 0.105328 0.001008)
			(end 0.24 0.001)
			(stroke
				(width 0.1)
				(type solid)
			)
			(layer "F.SilkS")
		)
		(fp_line
			(start -1.18 -0.319)
			(end -1.18 0.321)
			(stroke
				(width 0.15)
				(type solid)
			)
			(layer "F.SilkS")
		)
		(fp_line
			(start 0.22 -0.35)
			(end -0.22 -0.35)
			(stroke
				(width 0.15)
				(type solid)
			)
			(layer "F.SilkS")
		)
		(fp_rect
			(start 1.25 0.65)
			(end -1.25 -0.65)
			(stroke
				(width 0.05)
				(type solid)
			)
			(fill no)
			(layer "F.CrtYd")
		)
		(fp_line
			(start -0.199 0.2)
			(end -0.199 0.1)
			(stroke
				(width 0.15)
				(type solid)
			)
			(layer "F.Fab")
		)
		(fp_line
			(start 0.201 0.2)
			(end 0.201 0)
			(stroke
				(width 0.15)
				(type solid)
			)
			(layer "F.Fab")
		)
		(fp_line
			(start -0.199 0)
			(end -0.597 0)
			(stroke
				(width 0.15)
				(type solid)
			)
			(layer "F.Fab")
		)
		(fp_line
			(start -0.101 0)
			(end 0.201 0.2)
			(stroke
				(width 0.15)
				(type solid)
			)
			(layer "F.Fab")
		)
		(fp_line
			(start 0.201 0)
			(end 0.201 -0.202)
			(stroke
				(width 0.15)
				(type solid)
			)
			(layer "F.Fab")
		)
		(fp_line
			(start 0.599 0)
			(end 0.201 0)
			(stroke
				(width 0.15)
				(type solid)
			)
			(layer "F.Fab")
		)
		(fp_line
			(start -0.199 -0.202)
			(end -0.199 0.1)
			(stroke
				(width 0.15)
				(type solid)
			)
			(layer "F.Fab")
		)
		(fp_line
			(start 0.201 -0.202)
			(end -0.101 0)
			(stroke
				(width 0.15)
				(type solid)
			)
			(layer "F.Fab")
		)
		(fp_rect
			(start 0.848 0.4)
			(end -0.85 -0.402)
			(stroke
				(width 0.15)
				(type solid)
			)
			(fill no)
			(layer "F.Fab")
		)
		(fp_text user "Author: Antmicro"
			(at -1.4224 4.799 90)
			(layer "F.Fab")
			(effects
				(font
					(size 0.7 0.7)
					(thickness 0.15)
				)
				(justify right top)
			)
		)
		(fp_text user "${REFERENCE}"
			(at -1.4224 5.999 90)
			(layer "F.Fab")
			(effects
				(font
					(size 0.7 0.7)
					(thickness 0.15)
				)
				(justify right top)
			)
		)
		(fp_text user "License: Apache-2.0"
			(at -1.4224 3.599 90)
			(layer "F.Fab")
			(effects
				(font
					(size 0.7 0.7)
					(thickness 0.15)
				)
				(justify right top)
			)
		)
		(pad "1" smd roundrect
			(at -0.7 0 90)
			(size 0.8 1)
			(layers "F.Cu" "F.Mask" "F.Paste")
			(roundrect_rratio 0.2)
			(net 1 "GND")
			(pinfunction "C")
			(pintype "passive")
		)
		(pad "2" smd roundrect
			(at 0.7 0 90)
			(size 0.8 1)
			(layers "F.Cu" "F.Mask" "F.Paste")
			(roundrect_rratio 0.2)
			(net 1127 "Net-(D42-A)")
			(pinfunction "A")
			(pintype "passive")
		)
	)
	(footprint "antmicro-footprints:UQFN-24_2x4mm_P0.4mm_Texas_RJW0024A"
		(layer "F.Cu")
		(at 152.525 104.41 180)
		(property "Reference" "U78"
			(at 3.625 2 0)
			(unlocked yes)
			(layer "F.SilkS")
			(effects
				(font
					(size 0.7 0.7)
					(thickness 0.15)
				)
				(justify left bottom)
			)
		)
		(property "Value" "SN74AXC8T245_UQFN"
			(at 0 3.4 180)
			(unlocked yes)
			(layer "F.Fab")
			(effects
				(font
					(size 0.7 0.7)
					(thickness 0.15)
				)
				(justify left bottom)
			)
		)
		(property "Datasheet" "https://www.ti.com/lit/ds/symlink/sn74axc8t245.pdf?ts=1702327536011"
			(at 0 0 0)
			(layer "F.Fab")
			(hide yes)
			(effects
				(font
					(size 1.27 1.27)
					(thickness 0.15)
				)
			)
		)
		(property "Description" "8-bit dual-supply bus transceiver"
			(at 0 0 0)
			(layer "F.Fab")
			(hide yes)
			(effects
				(font
					(size 1.27 1.27)
					(thickness 0.15)
				)
			)
		)
		(property "MPN" "SN74AXC8T245RJWR"
			(at 0 0 180)
			(unlocked yes)
			(layer "F.Fab")
			(hide yes)
			(effects
				(font
					(size 1 1)
					(thickness 0.15)
				)
			)
		)
		(property "Manufacturer" "Texas Instruments"
			(at 0 0 180)
			(unlocked yes)
			(layer "F.Fab")
			(hide yes)
			(effects
				(font
					(size 1 1)
					(thickness 0.15)
				)
			)
		)
		(property "Author" "Antmicro"
			(at 0 0 180)
			(unlocked yes)
			(layer "F.Fab")
			(hide yes)
			(effects
				(font
					(size 1 1)
					(thickness 0.15)
				)
			)
		)
		(property "License" "Apache-2.0"
			(at 0 0 180)
			(unlocked yes)
			(layer "F.Fab")
			(hide yes)
			(effects
				(font
					(size 1 1)
					(thickness 0.15)
				)
			)
		)
		(sheetname "/SoM_IO/")
		(sheetfile "som_io.kicad_sch")
		(attr smd)
		(fp_line
			(start 1.200001 2)
			(end 1.2 2.2)
			(stroke
				(width 0.15)
				(type solid)
			)
			(layer "F.SilkS")
		)
		(fp_line
			(start 1.2 -2.2)
			(end 1.200001 -2)
			(stroke
				(width 0.15)
				(type solid)
			)
			(layer "F.SilkS")
		)
		(fp_line
			(start 0.499999 2.2)
			(end 1.2 2.2)
			(stroke
				(width 0.15)
				(type solid)
			)
			(layer "F.SilkS")
		)
		(fp_line
			(start 0.499999 -2.2)
			(end 1.2 -2.2)
			(stroke
				(width 0.15)
				(type solid)
			)
			(layer "F.SilkS")
		)
		(fp_line
			(start -1 -2.2)
			(end -0.499999 -2.2)
			(stroke
				(width 0.15)
				(type solid)
			)
			(layer "F.SilkS")
		)
		(fp_line
			(start -1.2 2.2)
			(end -0.499999 2.2)
			(stroke
				(width 0.15)
				(type solid)
			)
			(layer "F.SilkS")
		)
		(fp_line
			(start -1.200001 2)
			(end -1.2 2.2)
			(stroke
				(width 0.15)
				(type solid)
			)
			(layer "F.SilkS")
		)
		(fp_circle
			(center -1.2 -2.05)
			(end -1.15 -2.05)
			(stroke
				(width 0.15)
				(type solid)
			)
			(fill yes)
			(layer "F.SilkS")
		)
		(fp_poly
			(pts
				(xy 1.200001 0.95) (xy 1.2 1.05) (xy 1.199 1.06) (xy 1.196 1.069) (xy 1.192 1.078) (xy 1.185 1.084999)
				(xy 1.178 1.092) (xy 1.169 1.096) (xy 1.16 1.099) (xy 1.15 1.1) (xy 0.3 1.099999) (xy 0.29 1.099)
				(xy 0.281 1.096) (xy 0.272 1.092001) (xy 0.265 1.085) (xy 0.258 1.078001) (xy 0.254 1.069) (xy 0.251 1.06)
				(xy 0.25 1.05) (xy 0.25 0.95) (xy 0.251 0.94) (xy 0.254001 0.931) (xy 0.258 0.922) (xy 0.265 0.915)
				(xy 0.272 0.908) (xy 0.281 0.904001) (xy 0.29 0.901) (xy 0.3 0.9) (xy 1.15 0.9) (xy 1.16 0.901)
				(xy 1.169 0.904) (xy 1.178 0.908) (xy 1.185 0.915) (xy 1.192 0.922) (xy 1.196 0.931) (xy 1.199 0.939999)
			)
			(stroke
				(width 0)
				(type solid)
			)
			(fill yes)
			(layer "F.Paste")
		)
		(fp_poly
			(pts
				(xy 1.200001 -0.65) (xy 1.2 -0.55) (xy 1.199 -0.54) (xy 1.196 -0.531) (xy 1.192 -0.522) (xy 1.185001 -0.515)
				(xy 1.178 -0.508) (xy 1.169 -0.504) (xy 1.159999 -0.501) (xy 1.15 -0.5) (xy 0.3 -0.499999) (xy 0.289999 -0.501)
				(xy 0.281 -0.504) (xy 0.272 -0.508) (xy 0.265 -0.515) (xy 0.258 -0.522) (xy 0.254 -0.531) (xy 0.251 -0.54)
				(xy 0.25 -0.55) (xy 0.25 -0.65) (xy 0.251 -0.66) (xy 0.254001 -0.669) (xy 0.258 -0.678) (xy 0.265 -0.685)
				(xy 0.272 -0.692) (xy 0.281 -0.696) (xy 0.29 -0.699001) (xy 0.3 -0.7) (xy 1.15 -0.7) (xy 1.16 -0.699001)
				(xy 1.169 -0.696) (xy 1.178 -0.692) (xy 1.185 -0.685001) (xy 1.192 -0.678) (xy 1.196 -0.669) (xy 1.199001 -0.66)
			)
			(stroke
				(width 0)
				(type solid)
			)
			(fill yes)
			(layer "F.Paste")
		)
		(fp_poly
			(pts
				(xy 1.200001 -1.85) (xy 1.2 -1.75) (xy 1.199 -1.74) (xy 1.196 -1.731) (xy 1.192 -1.722) (xy 1.185 -1.715001)
				(xy 1.178 -1.708) (xy 1.169 -1.704) (xy 1.16 -1.701001) (xy 1.15 -1.7) (xy 0.600001 -1.7) (xy 0.59 -1.701001)
				(xy 0.581 -1.704) (xy 0.572 -1.707999) (xy 0.565 -1.715) (xy 0.558 -1.721999) (xy 0.554 -1.731)
				(xy 0.551 -1.74) (xy 0.55 -1.75) (xy 0.55 -1.85) (xy 0.551 -1.86) (xy 0.554 -1.869) (xy 0.558 -1.878)
				(xy 0.565 -1.885) (xy 0.572 -1.892) (xy 0.581 -1.895999) (xy 0.59 -1.899) (xy 0.6 -1.9) (xy 1.15 -1.9)
				(xy 1.16 -1.899) (xy 1.169 -1.896) (xy 1.178 -1.892) (xy 1.185 -1.885) (xy 1.192 -1.878) (xy 1.196 -1.869)
				(xy 1.199 -1.860001)
			)
			(stroke
				(width 0)
				(type solid)
			)
			(fill yes)
			(layer "F.Paste")
		)
		(fp_poly
			(pts
				(xy 1.2 1.75) (xy 1.200001 1.85) (xy 1.199 1.860001) (xy 1.196 1.869) (xy 1.192 1.878) (xy 1.185 1.885)
				(xy 1.178 1.892) (xy 1.169 1.896) (xy 1.16 1.899) (xy 1.15 1.9) (xy 0.6 1.9) (xy 0.59 1.899) (xy 0.581 1.895999)
				(xy 0.572 1.892) (xy 0.565 1.885) (xy 0.558 1.878) (xy 0.554 1.869) (xy 0.551 1.86) (xy 0.55 1.85)
				(xy 0.55 1.75) (xy 0.551 1.74) (xy 0.554 1.731) (xy 0.558 1.721999) (xy 0.565 1.715) (xy 0.572 1.707999)
				(xy 0.581 1.704) (xy 0.59 1.701001) (xy 0.600001 1.7) (xy 1.15 1.7) (xy 1.16 1.701001) (xy 1.169 1.704)
				(xy 1.178 1.708) (xy 1.185 1.715001) (xy 1.192 1.722) (xy 1.196 1.731) (xy 1.199 1.74)
			)
			(stroke
				(width 0)
				(type solid)
			)
			(fill yes)
			(layer "F.Paste")
		)
		(fp_poly
			(pts
				(xy 1.2 1.35) (xy 1.2 1.45) (xy 1.199 1.46) (xy 1.196 1.469) (xy 1.192 1.478) (xy 1.185 1.485) (xy 1.178 1.492)
				(xy 1.169 1.496) (xy 1.16 1.499) (xy 1.15 1.5) (xy 0.6 1.5) (xy 0.59 1.499) (xy 0.581 1.496) (xy 0.572 1.492)
				(xy 0.565 1.485) (xy 0.558 1.478) (xy 0.554 1.469) (xy 0.551 1.46) (xy 0.55 1.45) (xy 0.55 1.35)
				(xy 0.551 1.34) (xy 0.554 1.331) (xy 0.558 1.322) (xy 0.565 1.315) (xy 0.572 1.308) (xy 0.581 1.304)
				(xy 0.59 1.301) (xy 0.6 1.3) (xy 1.15 1.3) (xy 1.16 1.301) (xy 1.169 1.304) (xy 1.178 1.308) (xy 1.185 1.315)
				(xy 1.192 1.322) (xy 1.196 1.331) (xy 1.199 1.34)
			)
			(stroke
				(width 0)
				(type solid)
			)
			(fill yes)
			(layer "F.Paste")
		)
		(fp_poly
			(pts
				(xy 1.2 0.55) (xy 1.200001 0.65) (xy 1.199001 0.66) (xy 1.196 0.669) (xy 1.192 0.678) (xy 1.185 0.685001)
				(xy 1.178 0.692) (xy 1.169 0.696) (xy 1.16 0.699001) (xy 1.15 0.7) (xy 0.3 0.7) (xy 0.29 0.699001)
				(xy 0.281 0.696) (xy 0.272 0.692) (xy 0.265 0.685) (xy 0.258 0.678) (xy 0.254001 0.669) (xy 0.251 0.66)
				(xy 0.25 0.65) (xy 0.25 0.55) (xy 0.251 0.54) (xy 0.254 0.531) (xy 0.258 0.522) (xy 0.265 0.515)
				(xy 0.272 0.508) (xy 0.281 0.504) (xy 0.289999 0.501) (xy 0.3 0.499999) (xy 1.15 0.5) (xy 1.159999 0.501)
				(xy 1.169 0.504) (xy 1.178 0.508) (xy 1.185001 0.515) (xy 1.192 0.522) (xy 1.196 0.531) (xy 1.199 0.54)
			)
			(stroke
				(width 0)
				(type solid)
			)
			(fill yes)
			(layer "F.Paste")
		)
		(fp_poly
			(pts
				(xy 1.2 0.15) (xy 1.2 0.25) (xy 1.199 0.26) (xy 1.196 0.269) (xy 1.192 0.278) (xy 1.185 0.285) (xy 1.178 0.292)
				(xy 1.169 0.296) (xy 1.16 0.299) (xy 1.15 0.3) (xy 0.3 0.3) (xy 0.29 0.299) (xy 0.281 0.296001)
				(xy 0.272 0.292) (xy 0.265 0.285) (xy 0.258 0.278) (xy 0.254 0.269) (xy 0.251 0.26) (xy 0.25 0.25)
				(xy 0.25 0.15) (xy 0.251 0.14) (xy 0.254 0.131) (xy 0.258001 0.122) (xy 0.265 0.115) (xy 0.272001 0.108)
				(xy 0.281 0.104) (xy 0.29 0.101) (xy 0.3 0.1) (xy 1.15 0.1) (xy 1.16 0.101) (xy 1.169 0.104) (xy 1.178 0.108)
				(xy 1.185 0.115) (xy 1.192 0.122) (xy 1.196 0.131) (xy 1.199 0.14)
			)
			(stroke
				(width 0)
				(type solid)
			)
			(fill yes)
			(layer "F.Paste")
		)
		(fp_poly
			(pts
				(xy 1.2 -0.25) (xy 1.2 -0.15) (xy 1.199 -0.14) (xy 1.196 -0.131) (xy 1.192 -0.122) (xy 1.185 -0.115)
				(xy 1.178 -0.108) (xy 1.169 -0.104) (xy 1.16 -0.101) (xy 1.15 -0.1) (xy 0.3 -0.1) (xy 0.29 -0.101)
				(xy 0.281 -0.104) (xy 0.272001 -0.108) (xy 0.265 -0.115) (xy 0.258001 -0.122) (xy 0.254 -0.131)
				(xy 0.251 -0.14) (xy 0.25 -0.15) (xy 0.25 -0.25) (xy 0.251 -0.26) (xy 0.254 -0.269) (xy 0.258 -0.278)
				(xy 0.265 -0.285) (xy 0.272 -0.292) (xy 0.281 -0.296001) (xy 0.29 -0.299) (xy 0.3 -0.3) (xy 1.15 -0.3)
				(xy 1.16 -0.299) (xy 1.169 -0.296) (xy 1.178 -0.292) (xy 1.185 -0.285) (xy 1.192 -0.278) (xy 1.196 -0.269)
				(xy 1.199 -0.26)
			)
			(stroke
				(width 0)
				(type solid)
			)
			(fill yes)
			(layer "F.Paste")
		)
		(fp_poly
			(pts
				(xy 1.2 -1.05) (xy 1.200001 -0.95) (xy 1.199 -0.939999) (xy 1.196 -0.931) (xy 1.192 -0.922) (xy 1.185 -0.915)
				(xy 1.178 -0.908) (xy 1.169 -0.904) (xy 1.16 -0.901) (xy 1.15 -0.9) (xy 0.3 -0.9) (xy 0.29 -0.901)
				(xy 0.281 -0.904001) (xy 0.272 -0.908) (xy 0.265 -0.915) (xy 0.258 -0.922) (xy 0.254001 -0.931)
				(xy 0.251 -0.94) (xy 0.25 -0.95) (xy 0.25 -1.05) (xy 0.251 -1.06) (xy 0.254 -1.069) (xy 0.258 -1.078001)
				(xy 0.265 -1.085) (xy 0.272 -1.092001) (xy 0.281 -1.096) (xy 0.29 -1.099) (xy 0.3 -1.099999) (xy 1.15 -1.1)
				(xy 1.16 -1.099) (xy 1.169 -1.096) (xy 1.178 -1.092) (xy 1.185 -1.084999) (xy 1.192 -1.078) (xy 1.196 -1.069)
				(xy 1.199 -1.06)
			)
			(stroke
				(width 0)
				(type solid)
			)
			(fill yes)
			(layer "F.Paste")
		)
		(fp_poly
			(pts
				(xy 1.2 -1.45) (xy 1.2 -1.35) (xy 1.199 -1.34) (xy 1.196 -1.331) (xy 1.192 -1.322) (xy 1.185 -1.315)
				(xy 1.178 -1.308) (xy 1.169 -1.304) (xy 1.16 -1.301) (xy 1.15 -1.3) (xy 0.6 -1.3) (xy 0.59 -1.301)
				(xy 0.581 -1.304) (xy 0.572 -1.308) (xy 0.565 -1.315) (xy 0.558 -1.322) (xy 0.554 -1.331) (xy 0.551 -1.34)
				(xy 0.55 -1.35) (xy 0.55 -1.45) (xy 0.551 -1.46) (xy 0.554 -1.469) (xy 0.558 -1.478) (xy 0.565 -1.485)
				(xy 0.572 -1.492) (xy 0.581 -1.496) (xy 0.59 -1.499) (xy 0.6 -1.5) (xy 1.15 -1.5) (xy 1.16 -1.499)
				(xy 1.169 -1.496) (xy 1.178 -1.492) (xy 1.185 -1.485) (xy 1.192 -1.478) (xy 1.196 -1.469) (xy 1.199 -1.46)
			)
			(stroke
				(width 0)
				(type solid)
			)
			(fill yes)
			(layer "F.Paste")
		)
		(fp_poly
			(pts
				(xy 0.25 -1.5) (xy 0.15 -1.5) (xy 0.14 -1.501) (xy 0.131 -1.504001) (xy 0.122 -1.508) (xy 0.115 -1.515)
				(xy 0.108 -1.522) (xy 0.104001 -1.531) (xy 0.101 -1.54) (xy 0.1 -1.55) (xy 0.1 -2.15) (xy 0.101 -2.16)
				(xy 0.104 -2.169001) (xy 0.108 -2.178) (xy 0.115 -2.185) (xy 0.122 -2.192) (xy 0.130999 -2.196)
				(xy 0.14 -2.199) (xy 0.15 -2.2) (xy 0.25 -2.2) (xy 0.26 -2.199) (xy 0.269 -2.196) (xy 0.278 -2.192)
				(xy 0.285 -2.185) (xy 0.292 -2.178) (xy 0.296 -2.169) (xy 0.299 -2.16) (xy 0.3 -2.150001) (xy 0.300001 -1.55)
				(xy 0.298999 -1.54) (xy 0.296 -1.531) (xy 0.292 -1.522) (xy 0.285 -1.515) (xy 0.278 -1.508) (xy 0.269 -1.504)
				(xy 0.26 -1.501)
			)
			(stroke
				(width 0)
				(type solid)
			)
			(fill yes)
			(layer "F.Paste")
		)
		(fp_poly
			(pts
				(xy 0.15 1.5) (xy 0.25 1.5) (xy 0.26 1.501) (xy 0.269 1.504) (xy 0.278 1.508) (xy 0.285 1.515) (xy 0.292 1.522)
				(xy 0.296 1.531) (xy 0.298999 1.54) (xy 0.300001 1.55) (xy 0.3 2.150001) (xy 0.299 2.16) (xy 0.296 2.169)
				(xy 0.292 2.178) (xy 0.285 2.185) (xy 0.278 2.192) (xy 0.269 2.196) (xy 0.26 2.199) (xy 0.25 2.2)
				(xy 0.15 2.2) (xy 0.14 2.199) (xy 0.130999 2.196) (xy 0.122 2.192) (xy 0.115 2.185) (xy 0.108 2.178)
				(xy 0.104 2.169001) (xy 0.101 2.16) (xy 0.1 2.15) (xy 0.1 1.55) (xy 0.101 1.54) (xy 0.104001 1.531)
				(xy 0.108 1.522) (xy 0.115 1.515) (xy 0.122 1.508) (xy 0.131 1.504001) (xy 0.14 1.501)
			)
			(stroke
				(width 0)
				(type solid)
			)
			(fill yes)
			(layer "F.Paste")
		)
		(fp_poly
			(pts
				(xy -0.15 -1.5) (xy -0.25 -1.5) (xy -0.26 -1.501) (xy -0.269 -1.504) (xy -0.278 -1.508) (xy -0.285 -1.515)
				(xy -0.292 -1.522) (xy -0.296 -1.531) (xy -0.298999 -1.54) (xy -0.300001 -1.55) (xy -0.3 -2.150001)
				(xy -0.299 -2.16) (xy -0.296 -2.169) (xy -0.292 -2.178) (xy -0.285 -2.185) (xy -0.278 -2.192) (xy -0.269 -2.196)
				(xy -0.26 -2.199) (xy -0.25 -2.2) (xy -0.15 -2.2) (xy -0.14 -2.199) (xy -0.130999 -2.196) (xy -0.122 -2.192)
				(xy -0.115 -2.185) (xy -0.108 -2.178) (xy -0.104 -2.169001) (xy -0.101 -2.16) (xy -0.1 -2.15) (xy -0.1 -1.55)
				(xy -0.101 -1.54) (xy -0.104001 -1.531) (xy -0.108 -1.522) (xy -0.115 -1.515) (xy -0.122 -1.508)
				(xy -0.131 -1.504001) (xy -0.14 -1.501)
			)
			(stroke
				(width 0)
				(type solid)
			)
			(fill yes)
			(layer "F.Paste")
		)
		(fp_poly
			(pts
				(xy -0.25 1.5) (xy -0.15 1.5) (xy -0.14 1.501) (xy -0.131 1.504001) (xy -0.122 1.508) (xy -0.115 1.515)
				(xy -0.108 1.522) (xy -0.104001 1.531) (xy -0.101 1.54) (xy -0.1 1.55) (xy -0.1 2.15) (xy -0.101 2.16)
				(xy -0.104 2.169001) (xy -0.108 2.178) (xy -0.115 2.185) (xy -0.122 2.192) (xy -0.130999 2.196)
				(xy -0.14 2.199) (xy -0.15 2.2) (xy -0.25 2.2) (xy -0.26 2.199) (xy -0.269 2.196) (xy -0.278 2.192)
				(xy -0.285 2.185) (xy -0.292 2.178) (xy -0.296 2.169) (xy -0.299 2.16) (xy -0.3 2.150001) (xy -0.300001 1.55)
				(xy -0.298999 1.54) (xy -0.296 1.531) (xy -0.292 1.522) (xy -0.285 1.515) (xy -0.278 1.508) (xy -0.269 1.504)
				(xy -0.26 1.501)
			)
			(stroke
				(width 0)
				(type solid)
			)
			(fill yes)
			(layer "F.Paste")
		)
		(fp_poly
			(pts
				(xy -1.2 1.45) (xy -1.2 1.35) (xy -1.199 1.34) (xy -1.196 1.331) (xy -1.192 1.322) (xy -1.185 1.315)
				(xy -1.178 1.308) (xy -1.169 1.304) (xy -1.16 1.301) (xy -1.15 1.3) (xy -0.6 1.3) (xy -0.59 1.301)
				(xy -0.581 1.304) (xy -0.572 1.308) (xy -0.565 1.315) (xy -0.558 1.322) (xy -0.554 1.331) (xy -0.551 1.34)
				(xy -0.55 1.35) (xy -0.55 1.45) (xy -0.551 1.46) (xy -0.554 1.469) (xy -0.558 1.478) (xy -0.565 1.485)
				(xy -0.572 1.492) (xy -0.581 1.496) (xy -0.59 1.499) (xy -0.6 1.5) (xy -1.15 1.5) (xy -1.16 1.499)
				(xy -1.169 1.496) (xy -1.178 1.492) (xy -1.185 1.485) (xy -1.192 1.478) (xy -1.196 1.469) (xy -1.199 1.46)
			)
			(stroke
				(width 0)
				(type solid)
			)
			(fill yes)
			(layer "F.Paste")
		)
		(fp_poly
			(pts
				(xy -1.2 1.05) (xy -1.200001 0.95) (xy -1.199 0.939999) (xy -1.196 0.931) (xy -1.192 0.922) (xy -1.185 0.915)
				(xy -1.178 0.908) (xy -1.169 0.904) (xy -1.16 0.901) (xy -1.15 0.9) (xy -0.3 0.9) (xy -0.29 0.901)
				(xy -0.281 0.904001) (xy -0.272 0.908) (xy -0.265 0.915) (xy -0.258 0.922) (xy -0.254001 0.931)
				(xy -0.251 0.94) (xy -0.25 0.95) (xy -0.25 1.05) (xy -0.251 1.06) (xy -0.254 1.069) (xy -0.258 1.078001)
				(xy -0.265 1.085) (xy -0.272 1.092001) (xy -0.281 1.096) (xy -0.29 1.099) (xy -0.3 1.099999) (xy -1.15 1.1)
				(xy -1.16 1.099) (xy -1.169 1.096) (xy -1.178 1.092) (xy -1.185 1.084999) (xy -1.192 1.078) (xy -1.196 1.069)
				(xy -1.199 1.06)
			)
			(stroke
				(width 0)
				(type solid)
			)
			(fill yes)
			(layer "F.Paste")
		)
		(fp_poly
			(pts
				(xy -1.2 0.25) (xy -1.2 0.15) (xy -1.199 0.14) (xy -1.196 0.131) (xy -1.192 0.122) (xy -1.185 0.115)
				(xy -1.178 0.108) (xy -1.169 0.104) (xy -1.16 0.101) (xy -1.15 0.1) (xy -0.3 0.1) (xy -0.29 0.101)
				(xy -0.281 0.104) (xy -0.272001 0.108) (xy -0.265 0.115) (xy -0.258001 0.122) (xy -0.254 0.131)
				(xy -0.251 0.14) (xy -0.25 0.15) (xy -0.25 0.25) (xy -0.251 0.26) (xy -0.254 0.269) (xy -0.258 0.278)
				(xy -0.265 0.285) (xy -0.272 0.292) (xy -0.281 0.296001) (xy -0.29 0.299) (xy -0.3 0.3) (xy -1.15 0.3)
				(xy -1.16 0.299) (xy -1.169 0.296) (xy -1.178 0.292) (xy -1.185 0.285) (xy -1.192 0.278) (xy -1.196 0.269)
				(xy -1.199 0.26)
			)
			(stroke
				(width 0)
				(type solid)
			)
			(fill yes)
			(layer "F.Paste")
		)
		(fp_poly
			(pts
				(xy -1.2 -0.15) (xy -1.2 -0.25) (xy -1.199 -0.26) (xy -1.196 -0.269) (xy -1.192 -0.278) (xy -1.185 -0.285)
				(xy -1.178 -0.292) (xy -1.169 -0.296) (xy -1.16 -0.299) (xy -1.15 -0.3) (xy -0.3 -0.3) (xy -0.29 -0.299)
				(xy -0.281 -0.296001) (xy -0.272 -0.292) (xy -0.265 -0.285) (xy -0.258 -0.278) (xy -0.254 -0.269)
				(xy -0.251 -0.26) (xy -0.25 -0.25) (xy -0.25 -0.15) (xy -0.251 -0.14) (xy -0.254 -0.131) (xy -0.258001 -0.122)
				(xy -0.265 -0.115) (xy -0.272001 -0.108) (xy -0.281 -0.104) (xy -0.29 -0.101) (xy -0.3 -0.1) (xy -1.15 -0.1)
				(xy -1.16 -0.101) (xy -1.169 -0.104) (xy -1.178 -0.108) (xy -1.185 -0.115) (xy -1.192 -0.122) (xy -1.196 -0.131)
				(xy -1.199 -0.14)
			)
			(stroke
				(width 0)
				(type solid)
			)
			(fill yes)
			(layer "F.Paste")
		)
		(fp_poly
			(pts
				(xy -1.2 -0.55) (xy -1.200001 -0.65) (xy -1.199001 -0.66) (xy -1.196 -0.669) (xy -1.192 -0.678)
				(xy -1.185 -0.685001) (xy -1.178 -0.692) (xy -1.169 -0.696) (xy -1.16 -0.699001) (xy -1.15 -0.7)
				(xy -0.3 -0.7) (xy -0.29 -0.699001) (xy -0.281 -0.696) (xy -0.272 -0.692) (xy -0.265 -0.685) (xy -0.258 -0.678)
				(xy -0.254001 -0.669) (xy -0.251 -0.66) (xy -0.25 -0.65) (xy -0.25 -0.55) (xy -0.251 -0.54) (xy -0.254 -0.531)
				(xy -0.258 -0.522) (xy -0.265 -0.515) (xy -0.272 -0.508) (xy -0.281 -0.504) (xy -0.289999 -0.501)
				(xy -0.3 -0.499999) (xy -1.15 -0.5) (xy -1.159999 -0.501) (xy -1.169 -0.504) (xy -1.178 -0.508)
				(xy -1.185001 -0.515) (xy -1.192 -0.522) (xy -1.196 -0.531) (xy -1.199 -0.54)
			)
			(stroke
				(width 0)
				(type solid)
			)
			(fill yes)
			(layer "F.Paste")
		)
		(fp_poly
			(pts
				(xy -1.2 -1.35) (xy -1.2 -1.45) (xy -1.199 -1.46) (xy -1.196 -1.469) (xy -1.192 -1.478) (xy -1.185 -1.485)
				(xy -1.178 -1.492) (xy -1.169 -1.496) (xy -1.16 -1.499) (xy -1.15 -1.5) (xy -0.6 -1.5) (xy -0.59 -1.499)
				(xy -0.581 -1.496) (xy -0.572 -1.492) (xy -0.565 -1.485) (xy -0.558 -1.478) (xy -0.554 -1.469) (xy -0.551 -1.46)
				(xy -0.55 -1.45) (xy -0.55 -1.35) (xy -0.551 -1.34) (xy -0.554 -1.331) (xy -0.558 -1.322) (xy -0.565 -1.315)
				(xy -0.572 -1.308) (xy -0.581 -1.304) (xy -0.59 -1.301) (xy -0.6 -1.3) (xy -1.15 -1.3) (xy -1.16 -1.301)
				(xy -1.169 -1.304) (xy -1.178 -1.308) (xy -1.185 -1.315) (xy -1.192 -1.322) (xy -1.196 -1.331) (xy -1.199 -1.34)
			)
			(stroke
				(width 0)
				(type solid)
			)
			(fill yes)
			(layer "F.Paste")
		)
		(fp_poly
			(pts
				(xy -1.2 -1.75) (xy -1.200001 -1.85) (xy -1.199 -1.860001) (xy -1.196 -1.869) (xy -1.192 -1.878)
				(xy -1.185 -1.885) (xy -1.178 -1.892) (xy -1.169 -1.896) (xy -1.16 -1.899) (xy -1.15 -1.9) (xy -0.6 -1.9)
				(xy -0.59 -1.899) (xy -0.581 -1.895999) (xy -0.572 -1.892) (xy -0.565 -1.885) (xy -0.558 -1.878)
				(xy -0.554 -1.869) (xy -0.551 -1.86) (xy -0.55 -1.85) (xy -0.55 -1.75) (xy -0.551 -1.74) (xy -0.554 -1.731)
				(xy -0.558 -1.721999) (xy -0.565 -1.715) (xy -0.572 -1.707999) (xy -0.581 -1.704) (xy -0.59 -1.701001)
				(xy -0.600001 -1.7) (xy -1.15 -1.7) (xy -1.16 -1.701001) (xy -1.169 -1.704) (xy -1.178 -1.708) (xy -1.185 -1.715001)
				(xy -1.192 -1.722) (xy -1.196 -1.731) (xy -1.199 -1.74)
			)
			(stroke
				(width 0)
				(type solid)
			)
			(fill yes)
			(layer "F.Paste")
		)
		(fp_poly
			(pts
				(xy -1.200001 1.85) (xy -1.2 1.75) (xy -1.199 1.74) (xy -1.196 1.731) (xy -1.192 1.722) (xy -1.185 1.715001)
				(xy -1.178 1.708) (xy -1.169 1.704) (xy -1.16 1.701001) (xy -1.15 1.7) (xy -0.600001 1.7) (xy -0.59 1.701001)
				(xy -0.581 1.704) (xy -0.572 1.707999) (xy -0.565 1.715) (xy -0.558 1.721999) (xy -0.554 1.731)
				(xy -0.551 1.74) (xy -0.55 1.75) (xy -0.55 1.85) (xy -0.551 1.86) (xy -0.554 1.869) (xy -0.558 1.878)
				(xy -0.565 1.885) (xy -0.572 1.892) (xy -0.581 1.895999) (xy -0.59 1.899) (xy -0.6 1.9) (xy -1.15 1.9)
				(xy -1.16 1.899) (xy -1.169 1.896) (xy -1.178 1.892) (xy -1.185 1.885) (xy -1.192 1.878) (xy -1.196 1.869)
				(xy -1.199 1.860001)
			)
			(stroke
				(width 0)
				(type solid)
			)
			(fill yes)
			(layer "F.Paste")
		)
		(fp_poly
			(pts
				(xy -1.200001 0.65) (xy -1.2 0.55) (xy -1.199 0.54) (xy -1.196 0.531) (xy -1.192 0.522) (xy -1.185001 0.515)
				(xy -1.178 0.508) (xy -1.169 0.504) (xy -1.159999 0.501) (xy -1.15 0.5) (xy -0.3 0.499999) (xy -0.289999 0.501)
				(xy -0.281 0.504) (xy -0.272 0.508) (xy -0.265 0.515) (xy -0.258 0.522) (xy -0.254 0.531) (xy -0.251 0.54)
				(xy -0.25 0.55) (xy -0.25 0.65) (xy -0.251 0.66) (xy -0.254001 0.669) (xy -0.258 0.678) (xy -0.265 0.685)
				(xy -0.272 0.692) (xy -0.281 0.696) (xy -0.29 0.699001) (xy -0.3 0.7) (xy -1.15 0.7) (xy -1.16 0.699001)
				(xy -1.169 0.696) (xy -1.178 0.692) (xy -1.185 0.685001) (xy -1.192 0.678) (xy -1.196 0.669) (xy -1.199001 0.66)
			)
			(stroke
				(width 0)
				(type solid)
			)
			(fill yes)
			(layer "F.Paste")
		)
		(fp_poly
			(pts
				(xy -1.200001 -0.95) (xy -1.2 -1.05) (xy -1.199 -1.06) (xy -1.196 -1.069) (xy -1.192 -1.078) (xy -1.185 -1.084999)
				(xy -1.178 -1.092) (xy -1.169 -1.096) (xy -1.16 -1.099) (xy -1.15 -1.1) (xy -0.3 -1.099999) (xy -0.29 -1.099)
				(xy -0.281 -1.096) (xy -0.272 -1.092001) (xy -0.265 -1.085) (xy -0.258 -1.078001) (xy -0.254 -1.069)
				(xy -0.251 -1.06) (xy -0.25 -1.05) (xy -0.25 -0.95) (xy -0.251 -0.94) (xy -0.254001 -0.931) (xy -0.258 -0.922)
				(xy -0.265 -0.915) (xy -0.272 -0.908) (xy -0.281 -0.904001) (xy -0.29 -0.901) (xy -0.3 -0.9) (xy -1.15 -0.9)
				(xy -1.16 -0.901) (xy -1.169 -0.904) (xy -1.178 -0.908) (xy -1.185 -0.915) (xy -1.192 -0.922) (xy -1.196 -0.931)
				(xy -1.199 -0.939999)
			)
			(stroke
				(width 0)
				(type solid)
			)
			(fill yes)
			(layer "F.Paste")
		)
		(fp_poly
			(pts
				(xy -1.3 -2.3) (xy 1.3 -2.3) (xy 1.3 2.3) (xy -1.3 2.3)
			)
			(stroke
				(width 0.05)
				(type solid)
			)
			(fill no)
			(layer "F.CrtYd")
		)
		(fp_line
			(start 1.05 2.05)
			(end 1.05 -2.05)
			(stroke
				(width 0.15)
				(type solid)
			)
			(layer "F.Fab")
		)
		(fp_line
			(start -1.05 2.05)
			(end 1.05 2.05)
			(stroke
				(width 0.15)
				(type solid)
			)
			(layer "F.Fab")
		)
		(fp_line
			(start -1.05 2.05)
			(end -1.05 -2.05)
			(stroke
				(width 0.15)
				(type solid)
			)
			(layer "F.Fab")
		)
		(fp_line
			(start -1.05 -2.05)
			(end 1.05 -2.05)
			(stroke
				(width 0.15)
				(type solid)
			)
			(layer "F.Fab")
		)
		(fp_circle
			(center -0.5 -1.5)
			(end -0.2 -1.5)
			(stroke
				(width 0.15)
				(type solid)
			)
			(fill no)
			(layer "F.Fab")
		)
		(fp_text user "Author: Antmicro"
			(at -1.65 5.9 0)
			(layer "F.Fab")
			(effects
				(font
					(size 0.7 0.7)
					(thickness 0.15)
				)
				(justify right top)
			)
		)
		(fp_text user "License: Apache-2.0"
			(at -1.65 7.1 0)
			(layer "F.Fab")
			(effects
				(font
					(size 0.7 0.7)
					(thickness 0.15)
				)
				(justify right top)
			)
		)
		(fp_text user "${REFERENCE}"
			(at -1.65 4.7 180)
			(unlocked yes)
			(layer "F.Fab")
			(effects
				(font
					(size 0.7 0.7)
					(thickness 0.15)
				)
				(justify left bottom)
			)
		)
		(pad "1" smd rect
			(at -0.85 -1.8 180)
			(size 0.700001 0.2)
			(layers "F.Cu" "F.Mask")
			(net 11 "+1V8")
			(pinfunction "DIR1")
			(pintype "input")
		)
		(pad "2" smd rect
			(at -0.85 -1.4 180)
			(size 0.700001 0.2)
			(layers "F.Cu" "F.Mask")
			(net 625 "/SoM_IO/SFP_LEDY_1V8")
			(pinfunction "A1")
			(pintype "bidirectional")
		)
		(pad "3" smd rect
			(at -0.7 -1 180)
			(size 1 0.2)
			(layers "F.Cu" "F.Mask")
			(net 643 "/SoM_IO/SFP_LEDG_1V8")
			(pinfunction "A2")
			(pintype "bidirectional")
		)
		(pad "4" smd rect
			(at -0.7 -0.6 180)
			(size 1 0.2)
			(layers "F.Cu" "F.Mask")
			(net 1 "GND")
			(pinfunction "A3")
			(pintype "bidirectional")
		)
		(pad "5" smd rect
			(at -0.7 -0.2 180)
			(size 1 0.2)
			(layers "F.Cu" "F.Mask")
			(net 689 "/SoM_IO/USBC2_PEN_1V8")
			(pinfunction "A4")
			(pintype "bidirectional")
		)
		(pad "6" smd rect
			(at -0.7 0.2 180)
			(size 1 0.2)
			(layers "F.Cu" "F.Mask")
			(net 1242 "/SoM_IO/USBC2_ID_1V8")
			(pinfunction "A5")
			(pintype "bidirectional")
		)
		(pad "7" smd rect
			(at -0.7 0.6 180)
			(size 1 0.2)
			(layers "F.Cu" "F.Mask")
			(net 692 "/SoM_IO/~{USBC2_INT}_1V8")
			(pinfunction "A6")
			(pintype "bidirectional")
		)
		(pad "8" smd rect
			(at -0.7 1 180)
			(size 1 0.2)
			(layers "F.Cu" "F.Mask")
			(net 1244 "/SoM_IO/USBC2_VBUS_DET_1V8")
			(pinfunction "A7")
			(pintype "bidirectional")
		)
		(pad "9" smd rect
			(at -0.85 1.4 180)
			(size 0.700001 0.2)
			(layers "F.Cu" "F.Mask")
			(net 780 "/SoM_IO/~{PDC_I2C1_IRQ}_1V8")
			(pinfunction "A8")
			(pintype "bidirectional")
		)
		(pad "10" smd rect
			(at -0.85 1.8 180)
			(size 0.700001 0.2)
			(layers "F.Cu" "F.Mask")
			(net 11 "+1V8")
			(pinfunction "DIR2")
			(pintype "input")
		)
		(pad "11" smd rect
			(at -0.199999 1.825 270)
			(size 0.750001 0.2)
			(layers "F.Cu" "F.Mask")
			(net 1 "GND")
			(pinfunction "GND")
			(pintype "power_in")
		)
		(pad "12" smd rect
			(at 0.199999 1.825 270)
			(size 0.750001 0.2)
			(layers "F.Cu" "F.Mask")
			(net 1 "GND")
			(pinfunction "GND")
			(pintype "passive")
		)
		(pad "13" smd rect
			(at 0.85 1.8 180)
			(size 0.700001 0.2)
			(layers "F.Cu" "F.Mask")
			(net 954 "/SoM_IO/~{PDC_I2C1_IRQ}")
			(pinfunction "B8")
			(pintype "bidirectional")
		)
		(pad "14" smd rect
			(at 0.85 1.4 180)
			(size 0.700001 0.2)
			(layers "F.Cu" "F.Mask")
			(net 1018 "/Recovery USB/USBC2_VBUS_DET")
			(pinfunction "B7")
			(pintype "bidirectional")
		)
		(pad "15" smd rect
			(at 0.7 1 180)
			(size 1 0.2)
			(layers "F.Cu" "F.Mask")
			(net 1026 "/Recovery USB/~{USBC2_INT}")
			(pinfunction "B6")
			(pintype "bidirectional")
		)
		(pad "16" smd rect
			(at 0.7 0.6 180)
			(size 1 0.2)
			(layers "F.Cu" "F.Mask")
			(net 889 "/Recovery USB/USBC2_ID")
			(pinfunction "B5")
			(pintype "bidirectional")
		)
		(pad "17" smd rect
			(at 0.7 0.2 180)
			(size 1 0.2)
			(layers "F.Cu" "F.Mask")
			(net 1017 "/Recovery USB/USBC2_PEN")
			(pinfunction "B4")
			(pintype "bidirectional")
		)
		(pad "18" smd rect
			(at 0.7 -0.2 180)
			(size 1 0.2)
			(layers "F.Cu" "F.Mask")
			(net 1340 "unconnected-(U78-B3-Pad18)")
			(pinfunction "B3")
			(pintype "bidirectional+no_connect")
		)
		(pad "19" smd rect
			(at 0.7 -0.6 180)
			(size 1 0.2)
			(layers "F.Cu" "F.Mask")
			(net 1004 "/SFP/SFP_LEDG")
			(pinfunction "B2")
			(pintype "bidirectional")
		)
		(pad "20" smd rect
			(at 0.7 -1 180)
			(size 1 0.2)
			(layers "F.Cu" "F.Mask")
			(net 1003 "/SFP/SFP_LEDY")
			(pinfunction "B1")
			(pintype "bidirectional")
		)
		(pad "21" smd rect
			(at 0.85 -1.4 180)
			(size 0.700001 0.2)
			(layers "F.Cu" "F.Mask")
			(net 1 "GND")
			(pinfunction "OE_N")
			(pintype "input")
		)
		(pad "22" smd rect
			(at 0.85 -1.8 180)
			(size 0.700001 0.2)
			(layers "F.Cu" "F.Mask")
			(net 2 "+3V3")
			(pinfunction "VCCB")
			(pintype "power_in")
		)
		(pad "23" smd rect
			(at 0.199999 -1.825 270)
			(size 0.750001 0.2)
			(layers "F.Cu" "F.Mask")
			(net 2 "+3V3")
			(pinfunction "VCCB")
			(pintype "passive")
		)
		(pad "24" smd rect
			(at -0.199999 -1.825 270)
			(size 0.750001 0.2)
			(layers "F.Cu" "F.Mask")
			(net 11 "+1V8")
			(pinfunction "VCCA")
			(pintype "power_in")
		)
	)
	(footprint "antmicro-footprints:C_0805_2012Metric"
		(layer "F.Cu")
		(at 164.09 79.81 90)
		(descr "Capacitor SMD 0805")
		(tags "capacitor SMD 0805")
		(property "Reference" "C287"
			(at -4.68 0.51 90)
			(layer "F.SilkS")
			(effects
				(font
					(size 0.7 0.7)
					(thickness 0.15)
				)
				(justify left bottom)
			)
		)
		(property "Value" "C_22u_25V_0805"
			(at -2.055717 1.963152 90)
			(layer "F.Fab")
			(effects
				(font
					(size 0.7 0.7)
					(thickness 0.15)
				)
				(justify left bottom)
			)
		)
		(property "Datasheet" "https://product.samsungsem.com/mlcc/CL21A226MAYNNN.do"
			(at 0 0 90)
			(layer "F.Fab")
			(hide yes)
			(effects
				(font
					(size 1.27 1.27)
					(thickness 0.15)
				)
			)
		)
		(property "Description" "SMT Multilayer Ceramic Capacitor, 22uF, +/-20%, 25V, X5R, 0805 [2012 Metric]"
			(at 0 0 90)
			(layer "F.Fab")
			(hide yes)
			(effects
				(font
					(size 1.27 1.27)
					(thickness 0.15)
				)
			)
		)
		(property "MPN" "CL21A226MAYNNNE"
			(at 0 0 90)
			(unlocked yes)
			(layer "F.Fab")
			(hide yes)
			(effects
				(font
					(size 1 1)
					(thickness 0.15)
				)
			)
		)
		(property "Manufacturer" "Samsung Electro-Mechanics"
			(at 0 0 90)
			(unlocked yes)
			(layer "F.Fab")
			(hide yes)
			(effects
				(font
					(size 1 1)
					(thickness 0.15)
				)
			)
		)
		(property "License" "Apache-2.0"
			(at 0 0 90)
			(unlocked yes)
			(layer "F.Fab")
			(hide yes)
			(effects
				(font
					(size 1 1)
					(thickness 0.15)
				)
			)
		)
		(property "Author" "Antmicro"
			(at 0 0 90)
			(unlocked yes)
			(layer "F.Fab")
			(hide yes)
			(effects
				(font
					(size 1 1)
					(thickness 0.15)
				)
			)
		)
		(property "Val" "22u"
			(at 0 0 90)
			(unlocked yes)
			(layer "F.Fab")
			(hide yes)
			(effects
				(font
					(size 1 1)
					(thickness 0.15)
				)
			)
		)
		(property "Voltage" "25V"
			(at 0 0 90)
			(unlocked yes)
			(layer "F.Fab")
			(hide yes)
			(effects
				(font
					(size 1 1)
					(thickness 0.15)
				)
			)
		)
		(property "Dielectric" "X5R"
			(at 0 0 90)
			(unlocked yes)
			(layer "F.Fab")
			(hide yes)
			(effects
				(font
					(size 1 1)
					(thickness 0.15)
				)
			)
		)
		(property "Public" "False"
			(at 0 0 90)
			(unlocked yes)
			(layer "F.Fab")
			(hide yes)
			(effects
				(font
					(size 1 1)
					(thickness 0.15)
				)
			)
		)
		(component_classes
			(class "DCDC_20V")
		)
		(sheetname "/DCDC/")
		(sheetfile "dcdc.kicad_sch")
		(attr smd)
		(fp_line
			(start -0.3 -0.7)
			(end 0.3 -0.7)
			(stroke
				(width 0.15)
				(type solid)
			)
			(layer "F.SilkS")
		)
		(fp_line
			(start -0.3 0.7)
			(end 0.3 0.7)
			(stroke
				(width 0.15)
				(type solid)
			)
			(layer "F.SilkS")
		)
		(fp_rect
			(start 1.95 -0.9)
			(end -1.95 0.9)
			(stroke
				(width 0.05)
				(type default)
			)
			(fill no)
			(layer "F.CrtYd")
		)
		(fp_rect
			(start -0.95 -0.675)
			(end 0.95 0.675)
			(stroke
				(width 0.15)
				(type solid)
			)
			(fill no)
			(layer "F.Fab")
		)
		(fp_text user "Author: Antmicro"
			(at -1.9 5.947 90)
			(layer "F.Fab")
			(effects
				(font
					(size 0.7 0.7)
					(thickness 0.15)
				)
				(justify left bottom)
			)
		)
		(fp_text user "${REFERENCE}"
			(at -1.9 3.947 90)
			(layer "F.Fab")
			(effects
				(font
					(size 0.7 0.7)
					(thickness 0.15)
				)
				(justify left bottom)
			)
		)
		(fp_text user "License: Apache-2.0"
			(at -1.9 4.947 90)
			(layer "F.Fab")
			(effects
				(font
					(size 0.7 0.7)
					(thickness 0.15)
				)
				(justify left bottom)
			)
		)
		(pad "1" smd roundrect
			(at -1.1 0 90)
			(size 1.2 1.3)
			(layers "F.Cu" "F.Mask" "F.Paste")
			(roundrect_rratio 0.25)
			(net 1 "GND")
			(pintype "passive")
		)
		(pad "2" smd roundrect
			(at 1.1 0 90)
			(size 1.2 1.3)
			(layers "F.Cu" "F.Mask" "F.Paste")
			(roundrect_rratio 0.25)
			(net 1105 "/DCDC/20V_OUT")
			(pintype "passive")
		)
	)
	(footprint "antmicro-footprints:TP_SMD_0.75mm"
		(layer "F.Cu")
		(at 184.25 57.14 90)
		(property "Reference" "TP4"
			(at -1.51 -0.69 90)
			(layer "F.SilkS")
			(hide yes)
			(effects
				(font
					(size 0.7 0.7)
					(thickness 0.15)
				)
				(justify left bottom)
			)
		)
		(property "Value" "TP_0.75mm_SMD"
			(at 0 1.2 90)
			(layer "F.Fab")
			(effects
				(font
					(size 0.7 0.7)
					(thickness 0.15)
				)
				(justify left bottom)
			)
		)
		(property "Description" "SMT test point"
			(at 0 0 90)
			(layer "F.Fab")
			(hide yes)
			(effects
				(font
					(size 1.27 1.27)
					(thickness 0.15)
				)
			)
		)
		(property "MPN" ""
			(at 0 0 90)
			(unlocked yes)
			(layer "F.Fab")
			(hide yes)
			(effects
				(font
					(size 1 1)
					(thickness 0.15)
				)
			)
		)
		(property "Manufacturer" ""
			(at 0 0 90)
			(unlocked yes)
			(layer "F.Fab")
			(hide yes)
			(effects
				(font
					(size 1 1)
					(thickness 0.15)
				)
			)
		)
		(property "Author" "Antmicro"
			(at 0 0 90)
			(unlocked yes)
			(layer "F.Fab")
			(hide yes)
			(effects
				(font
					(size 1 1)
					(thickness 0.15)
				)
			)
		)
		(property "License" "Apache-2.0"
			(at 0 0 90)
			(unlocked yes)
			(layer "F.Fab")
			(hide yes)
			(effects
				(font
					(size 1 1)
					(thickness 0.15)
				)
			)
		)
		(sheetname "/Power/")
		(sheetfile "power.kicad_sch")
		(attr exclude_from_pos_files exclude_from_bom)
		(fp_circle
			(center 0 0)
			(end 0.475 0)
			(stroke
				(width 0.05)
				(type default)
			)
			(fill no)
			(layer "F.CrtYd")
		)
		(fp_text user "Author: Antmicro"
			(at -0.4 3.901 90)
			(layer "F.Fab")
			(effects
				(font
					(size 0.7 0.7)
					(thickness 0.15)
				)
				(justify left bottom)
			)
		)
		(fp_text user "License: Apache-2.0"
			(at -0.4 5.101 90)
			(layer "F.Fab")
			(effects
				(font
					(size 0.7 0.7)
					(thickness 0.15)
				)
				(justify left bottom)
			)
		)
		(fp_text user "${REFERENCE}"
			(at -0.4 2.7 90)
			(layer "F.Fab")
			(effects
				(font
					(size 0.7 0.7)
					(thickness 0.15)
				)
				(justify left bottom)
			)
		)
		(pad "1" smd circle
			(at 0 0 90)
			(size 0.75 0.75)
			(layers "F.Cu" "F.Mask")
			(net 13 "VCC")
			(pinfunction "1")
			(pintype "passive")
		)
	)
	(footprint "antmicro-footprints:C_0402_1005Metric"
		(layer "F.Cu")
		(at 65.68 85.87 90)
		(descr "Capacitor SMD 0402")
		(tags "capacitor SMD 0402")
		(property "Reference" "C156"
			(at 0.87 0.32 90)
			(layer "F.SilkS")
			(effects
				(font
					(size 0.7 0.7)
					(thickness 0.15)
				)
				(justify left bottom)
			)
		)
		(property "Value" "C_100n_0402"
			(at -1.022927 2.155213 90)
			(layer "F.Fab")
			(effects
				(font
					(size 0.7 0.7)
					(thickness 0.15)
				)
				(justify left bottom)
			)
		)
		(property "Datasheet" "https://www.murata.com/products/productdetail?partno=GRM155R61H104KE14%23"
			(at 0 0 90)
			(layer "F.Fab")
			(hide yes)
			(effects
				(font
					(size 1.27 1.27)
					(thickness 0.15)
				)
			)
		)
		(property "Description" "SMD Multilayer Ceramic Capacitor, 0.1 µF, 50 V, 0402 [1005 Metric], ± 10%, X5R, GRM Series"
			(at 0 0 90)
			(layer "F.Fab")
			(hide yes)
			(effects
				(font
					(size 1.27 1.27)
					(thickness 0.15)
				)
			)
		)
		(property "Manufacturer" "Murata"
			(at 0 0 90)
			(unlocked yes)
			(layer "F.Fab")
			(hide yes)
			(effects
				(font
					(size 1 1)
					(thickness 0.15)
				)
			)
		)
		(property "MPN" "GRM155R61H104KE14D"
			(at 0 0 90)
			(unlocked yes)
			(layer "F.Fab")
			(hide yes)
			(effects
				(font
					(size 1 1)
					(thickness 0.15)
				)
			)
		)
		(property "Val" "100n"
			(at 0 0 90)
			(unlocked yes)
			(layer "F.Fab")
			(hide yes)
			(effects
				(font
					(size 1 1)
					(thickness 0.15)
				)
			)
		)
		(property "License" "Apache-2.0"
			(at 0 0 90)
			(unlocked yes)
			(layer "F.Fab")
			(hide yes)
			(effects
				(font
					(size 1 1)
					(thickness 0.15)
				)
			)
		)
		(property "Author" "Antmicro"
			(at 0 0 90)
			(unlocked yes)
			(layer "F.Fab")
			(hide yes)
			(effects
				(font
					(size 1 1)
					(thickness 0.15)
				)
			)
		)
		(property "Voltage" "50V"
			(at 0 0 90)
			(unlocked yes)
			(layer "F.Fab")
			(hide yes)
			(effects
				(font
					(size 1 1)
					(thickness 0.15)
				)
			)
		)
		(property "Dielectric" "X5R"
			(at 0 0 90)
			(unlocked yes)
			(layer "F.Fab")
			(hide yes)
			(effects
				(font
					(size 1 1)
					(thickness 0.15)
				)
			)
		)
		(sheetname "/CSI/")
		(sheetfile "csi.kicad_sch")
		(attr smd)
		(fp_rect
			(start -0.925 -0.47)
			(end 0.925 0.47)
			(stroke
				(width 0.05)
				(type default)
			)
			(fill no)
			(layer "F.CrtYd")
		)
		(fp_line
			(start 0.504 -0.25)
			(end 0.504 0.248)
			(stroke
				(width 0.15)
				(type solid)
			)
			(layer "F.Fab")
		)
		(fp_line
			(start -0.494 -0.25)
			(end 0.504 -0.25)
			(stroke
				(width 0.15)
				(type solid)
			)
			(layer "F.Fab")
		)
		(fp_line
			(start 0.504 0.248)
			(end -0.494 0.248)
			(stroke
				(width 0.15)
				(type solid)
			)
			(layer "F.Fab")
		)
		(fp_line
			(start -0.494 0.248)
			(end -0.494 -0.25)
			(stroke
				(width 0.15)
				(type solid)
			)
			(layer "F.Fab")
		)
		(fp_text user "Author: Antmicro"
			(at -0.939 3.399 90)
			(layer "F.Fab")
			(effects
				(font
					(size 0.7 0.7)
					(thickness 0.15)
				)
				(justify left bottom)
			)
		)
		(fp_text user "License: Apache-2.0"
			(at -0.939 5.799 90)
			(layer "F.Fab")
			(effects
				(font
					(size 0.7 0.7)
					(thickness 0.15)
				)
				(justify left bottom)
			)
		)
		(fp_text user "${REFERENCE}"
			(at -0.939 4.599 90)
			(layer "F.Fab")
			(effects
				(font
					(size 0.7 0.7)
					(thickness 0.15)
				)
				(justify left bottom)
			)
		)
		(pad "1" smd roundrect
			(at -0.48 0 90)
			(size 0.59 0.64)
			(layers "F.Cu" "F.Mask" "F.Paste")
			(roundrect_rratio 0.25)
			(net 5 "+5V")
			(pintype "passive")
		)
		(pad "2" smd roundrect
			(at 0.48 0 90)
			(size 0.59 0.64)
			(layers "F.Cu" "F.Mask" "F.Paste")
			(roundrect_rratio 0.25)
			(net 1 "GND")
			(pintype "passive")
		)
	)
	(footprint "antmicro-footprints:R_0402_1005Metric"
		(layer "F.Cu")
		(at 136 109.1 180)
		(descr "Resistor SMD 0402")
		(tags "resistor SMD 0402")
		(property "Reference" "R346"
			(at 1 0.3 0)
			(layer "F.SilkS")
			(effects
				(font
					(size 0.7 0.7)
					(thickness 0.15)
				)
				(justify right top)
			)
		)
		(property "Value" "R_0R_0402"
			(at -1.011843 1.772047 0)
			(layer "F.Fab")
			(effects
				(font
					(size 0.7 0.7)
					(thickness 0.15)
				)
				(justify right top)
			)
		)
		(property "Datasheet" "https://industrial.panasonic.com/cdbs/www-data/pdf/RDA0000/AOA0000C301.pdf"
			(at 0 0 0)
			(layer "F.Fab")
			(hide yes)
			(effects
				(font
					(size 1.27 1.27)
					(thickness 0.15)
				)
			)
		)
		(property "Description" "SMD Chip Resistor, Jumper, 0 ohm, 100 mW, 0402 [1005 Metric], Thick Film, General Purpose"
			(at 0 0 0)
			(layer "F.Fab")
			(hide yes)
			(effects
				(font
					(size 1.27 1.27)
					(thickness 0.15)
				)
			)
		)
		(property "MPN" "ERJ2GE0R00X"
			(at 0 0 180)
			(unlocked yes)
			(layer "F.Fab")
			(hide yes)
			(effects
				(font
					(size 1 1)
					(thickness 0.15)
				)
			)
		)
		(property "Manufacturer" "Panasonic"
			(at 0 0 180)
			(unlocked yes)
			(layer "F.Fab")
			(hide yes)
			(effects
				(font
					(size 1 1)
					(thickness 0.15)
				)
			)
		)
		(property "License" "Apache-2.0"
			(at 0 0 180)
			(unlocked yes)
			(layer "F.Fab")
			(hide yes)
			(effects
				(font
					(size 1 1)
					(thickness 0.15)
				)
			)
		)
		(property "Author" "Antmicro"
			(at 0 0 180)
			(unlocked yes)
			(layer "F.Fab")
			(hide yes)
			(effects
				(font
					(size 1 1)
					(thickness 0.15)
				)
			)
		)
		(property "Val" "0R"
			(at 0 0 180)
			(unlocked yes)
			(layer "F.Fab")
			(hide yes)
			(effects
				(font
					(size 1 1)
					(thickness 0.15)
				)
			)
		)
		(property "Tolerance" "~"
			(at 0 0 180)
			(unlocked yes)
			(layer "F.Fab")
			(hide yes)
			(effects
				(font
					(size 1 1)
					(thickness 0.15)
				)
			)
		)
		(property "Current" "1A"
			(at 0 0 180)
			(unlocked yes)
			(layer "F.Fab")
			(hide yes)
			(effects
				(font
					(size 1 1)
					(thickness 0.15)
				)
			)
		)
		(sheetname "/Peripherals/")
		(sheetfile "peripherals.kicad_sch")
		(attr smd)
		(fp_rect
			(start -0.925 -0.47)
			(end 0.925 0.47)
			(stroke
				(width 0.05)
				(type default)
			)
			(fill no)
			(layer "F.CrtYd")
		)
		(fp_rect
			(start -0.5 -0.25)
			(end 0.5 0.25)
			(stroke
				(width 0.15)
				(type solid)
			)
			(fill no)
			(layer "F.Fab")
		)
		(fp_text user "License: Apache-2.0"
			(at -0.95 5.169 0)
			(layer "F.Fab")
			(effects
				(font
					(size 0.7 0.7)
					(thickness 0.15)
				)
				(justify right top)
			)
		)
		(fp_text user "Author: Antmicro"
			(at -0.95 4.169 0)
			(layer "F.Fab")
			(effects
				(font
					(size 0.7 0.7)
					(thickness 0.15)
				)
				(justify right top)
			)
		)
		(fp_text user "${REFERENCE}"
			(at -0.95 3.168 0)
			(layer "F.Fab")
			(effects
				(font
					(size 0.7 0.7)
					(thickness 0.15)
				)
				(justify right top)
			)
		)
		(pad "1" smd roundrect
			(at -0.48 0 180)
			(size 0.59 0.64)
			(layers "F.Cu" "F.Mask" "F.Paste")
			(roundrect_rratio 0.25)
			(net 1314 "/Peripherals/GPIOEX_P0_1")
			(pintype "passive")
		)
		(pad "2" smd roundrect
			(at 0.48 0 180)
			(size 0.59 0.64)
			(layers "F.Cu" "F.Mask" "F.Paste")
			(roundrect_rratio 0.25)
			(net 123 "/CSI/CAM_CTRL.CSIB_PEN")
			(pintype "passive")
		)
	)
	(footprint "antmicro-footprints:R_0402_1005Metric"
		(layer "F.Cu")
		(at 92.98 148.205736)
		(descr "Resistor SMD 0402")
		(tags "resistor SMD 0402")
		(property "Reference" "R195"
			(at 1.02 0.394264 0)
			(layer "F.SilkS")
			(effects
				(font
					(size 0.7 0.7)
					(thickness 0.15)
				)
				(justify left bottom)
			)
		)
		(property "Value" "R_0R_0402"
			(at -1.011843 1.772046 0)
			(layer "F.Fab")
			(effects
				(font
					(size 0.7 0.7)
					(thickness 0.15)
				)
				(justify left bottom)
			)
		)
		(property "Datasheet" "https://industrial.panasonic.com/cdbs/www-data/pdf/RDA0000/AOA0000C301.pdf"
			(at 0 0 0)
			(layer "F.Fab")
			(hide yes)
			(effects
				(font
					(size 1.27 1.27)
					(thickness 0.15)
				)
			)
		)
		(property "Description" "SMD Chip Resistor, Jumper, 0 ohm, 100 mW, 0402 [1005 Metric], Thick Film, General Purpose"
			(at 0 0 0)
			(layer "F.Fab")
			(hide yes)
			(effects
				(font
					(size 1.27 1.27)
					(thickness 0.15)
				)
			)
		)
		(property "MPN" "ERJ2GE0R00X"
			(at 0 0 0)
			(unlocked yes)
			(layer "F.Fab")
			(hide yes)
			(effects
				(font
					(size 1 1)
					(thickness 0.15)
				)
			)
		)
		(property "Manufacturer" "Panasonic"
			(at 0 0 0)
			(unlocked yes)
			(layer "F.Fab")
			(hide yes)
			(effects
				(font
					(size 1 1)
					(thickness 0.15)
				)
			)
		)
		(property "License" "Apache-2.0"
			(at 0 0 0)
			(unlocked yes)
			(layer "F.Fab")
			(hide yes)
			(effects
				(font
					(size 1 1)
					(thickness 0.15)
				)
			)
		)
		(property "Author" "Antmicro"
			(at 0 0 0)
			(unlocked yes)
			(layer "F.Fab")
			(hide yes)
			(effects
				(font
					(size 1 1)
					(thickness 0.15)
				)
			)
		)
		(property "Val" "0R"
			(at 0 0 0)
			(unlocked yes)
			(layer "F.Fab")
			(hide yes)
			(effects
				(font
					(size 1 1)
					(thickness 0.15)
				)
			)
		)
		(property "Tolerance" "~"
			(at 0 0 0)
			(unlocked yes)
			(layer "F.Fab")
			(hide yes)
			(effects
				(font
					(size 1 1)
					(thickness 0.15)
				)
			)
		)
		(property "Current" "1A"
			(at 0 0 0)
			(unlocked yes)
			(layer "F.Fab")
			(hide yes)
			(effects
				(font
					(size 1 1)
					(thickness 0.15)
				)
			)
		)
		(sheetname "/SoM_IO2/")
		(sheetfile "som_io2.kicad_sch")
		(attr smd exclude_from_pos_files exclude_from_bom dnp)
		(fp_poly
			(pts
				(xy -0.925 -0.47) (xy -0.925 0.47) (xy 0.925 0.47) (xy 0.925 -0.47)
			)
			(stroke
				(width 0.05)
				(type default)
			)
			(fill no)
			(layer "F.CrtYd")
		)
		(fp_poly
			(pts
				(xy -0.5 -0.25) (xy -0.5 0.25) (xy 0.5 0.25) (xy 0.5 -0.25)
			)
			(stroke
				(width 0.15)
				(type solid)
			)
			(fill no)
			(layer "F.Fab")
		)
		(fp_text user "${REFERENCE}"
			(at -0.95 3.168 0)
			(layer "F.Fab")
			(effects
				(font
					(size 0.7 0.7)
					(thickness 0.15)
				)
				(justify left bottom)
			)
		)
		(fp_text user "Author: Antmicro"
			(at -0.95 4.169 0)
			(layer "F.Fab")
			(effects
				(font
					(size 0.7 0.7)
					(thickness 0.15)
				)
				(justify left bottom)
			)
		)
		(fp_text user "License: Apache-2.0"
			(at -0.949999 5.169 0)
			(layer "F.Fab")
			(effects
				(font
					(size 0.7 0.7)
					(thickness 0.15)
				)
				(justify left bottom)
			)
		)
		(pad "1" smd roundrect
			(at -0.48 0)
			(size 0.59 0.64)
			(layers "F.Cu" "F.Mask" "F.Paste")
			(roundrect_rratio 0.25)
			(net 1002 "/SoM_IO2/C2_REFCLK-")
			(pintype "passive")
		)
		(pad "2" smd roundrect
			(at 0.48 0)
			(size 0.59 0.64)
			(layers "F.Cu" "F.Mask" "F.Paste")
			(roundrect_rratio 0.25)
			(net 668 "/SoM_IO2/PCIe_{C2x1}R_CLK-")
			(pintype "passive")
		)
	)
	(footprint "antmicro-footprints:C_0402_1005Metric"
		(layer "F.Cu")
		(at 91.1 95.5)
		(descr "Capacitor SMD 0402")
		(tags "capacitor SMD 0402")
		(property "Reference" "C350"
			(at 1.1 0.500001 0)
			(layer "F.SilkS")
			(effects
				(font
					(size 0.7 0.7)
					(thickness 0.15)
				)
				(justify left bottom)
			)
		)
		(property "Value" "C_100n_0402"
			(at -1.022927 2.155213 0)
			(layer "F.Fab")
			(effects
				(font
					(size 0.7 0.7)
					(thickness 0.15)
				)
				(justify left bottom)
			)
		)
		(property "Datasheet" "https://www.murata.com/products/productdetail?partno=GRM155R61H104KE14%23"
			(at 0 0 0)
			(layer "F.Fab")
			(hide yes)
			(effects
				(font
					(size 1.27 1.27)
					(thickness 0.15)
				)
			)
		)
		(property "Description" "SMD Multilayer Ceramic Capacitor, 0.1 µF, 50 V, 0402 [1005 Metric], ± 10%, X5R, GRM Series"
			(at 0 0 0)
			(layer "F.Fab")
			(hide yes)
			(effects
				(font
					(size 1.27 1.27)
					(thickness 0.15)
				)
			)
		)
		(property "Manufacturer" "Murata"
			(at 0 0 0)
			(unlocked yes)
			(layer "F.Fab")
			(hide yes)
			(effects
				(font
					(size 1 1)
					(thickness 0.15)
				)
			)
		)
		(property "MPN" "GRM155R61H104KE14D"
			(at 0 0 0)
			(unlocked yes)
			(layer "F.Fab")
			(hide yes)
			(effects
				(font
					(size 1 1)
					(thickness 0.15)
				)
			)
		)
		(property "Val" "100n"
			(at 0 0 0)
			(unlocked yes)
			(layer "F.Fab")
			(hide yes)
			(effects
				(font
					(size 1 1)
					(thickness 0.15)
				)
			)
		)
		(property "License" "Apache-2.0"
			(at 0 0 0)
			(unlocked yes)
			(layer "F.Fab")
			(hide yes)
			(effects
				(font
					(size 1 1)
					(thickness 0.15)
				)
			)
		)
		(property "Author" "Antmicro"
			(at 0 0 0)
			(unlocked yes)
			(layer "F.Fab")
			(hide yes)
			(effects
				(font
					(size 1 1)
					(thickness 0.15)
				)
			)
		)
		(property "Voltage" "50V"
			(at 0 0 0)
			(unlocked yes)
			(layer "F.Fab")
			(hide yes)
			(effects
				(font
					(size 1 1)
					(thickness 0.15)
				)
			)
		)
		(property "Dielectric" "X5R"
			(at 0 0 0)
			(unlocked yes)
			(layer "F.Fab")
			(hide yes)
			(effects
				(font
					(size 1 1)
					(thickness 0.15)
				)
			)
		)
		(sheetname "/SoM_IO2/")
		(sheetfile "som_io2.kicad_sch")
		(attr smd)
		(fp_rect
			(start -0.925 -0.47)
			(end 0.925 0.47)
			(stroke
				(width 0.05)
				(type default)
			)
			(fill no)
			(layer "F.CrtYd")
		)
		(fp_line
			(start -0.494 -0.25)
			(end 0.504 -0.25)
			(stroke
				(width 0.15)
				(type solid)
			)
			(layer "F.Fab")
		)
		(fp_line
			(start -0.494 0.248)
			(end -0.494 -0.25)
			(stroke
				(width 0.15)
				(type solid)
			)
			(layer "F.Fab")
		)
		(fp_line
			(start 0.504 -0.25)
			(end 0.504 0.248)
			(stroke
				(width 0.15)
				(type solid)
			)
			(layer "F.Fab")
		)
		(fp_line
			(start 0.504 0.248)
			(end -0.494 0.248)
			(stroke
				(width 0.15)
				(type solid)
			)
			(layer "F.Fab")
		)
		(fp_text user "Author: Antmicro"
			(at -0.939 3.399 0)
			(layer "F.Fab")
			(effects
				(font
					(size 0.7 0.7)
					(thickness 0.15)
				)
				(justify left bottom)
			)
		)
		(fp_text user "${REFERENCE}"
			(at -0.939 4.599 0)
			(layer "F.Fab")
			(effects
				(font
					(size 0.7 0.7)
					(thickness 0.15)
				)
				(justify left bottom)
			)
		)
		(fp_text user "License: Apache-2.0"
			(at -0.939 5.799 0)
			(layer "F.Fab")
			(effects
				(font
					(size 0.7 0.7)
					(thickness 0.15)
				)
				(justify left bottom)
			)
		)
		(pad "1" smd roundrect
			(at -0.48 0)
			(size 0.59 0.64)
			(layers "F.Cu" "F.Mask" "F.Paste")
			(roundrect_rratio 0.25)
			(net 680 "/Expansion connector/DP3.TX2-")
			(pintype "passive")
		)
		(pad "2" smd roundrect
			(at 0.48 0)
			(size 0.59 0.64)
			(layers "F.Cu" "F.Mask" "F.Paste")
			(roundrect_rratio 0.25)
			(net 1270 "/SoM_IO2/DP3.TX2_C-")
			(pintype "passive")
		)
	)
	(footprint "antmicro-footprints:LED_0603_1608Metric_G"
		(layer "F.Cu")
		(at 166.25 55.3 -90)
		(descr "LED SMD 0603 Green")
		(tags "LED SMD 0603 Green")
		(property "Reference" "D31"
			(at -0.9 1.57 90)
			(layer "F.SilkS")
			(effects
				(font
					(size 0.7 0.7)
					(thickness 0.15)
				)
				(justify right top)
			)
		)
		(property "Value" "LED_G_0603_LTST-C190GKT"
			(at -0.001 1.599 90)
			(layer "F.Fab")
			(effects
				(font
					(size 0.7 0.7)
					(thickness 0.15)
				)
				(justify right top)
			)
		)
		(property "Datasheet" "https://media.digikey.com/pdf/Data%20Sheets/Lite-On%20PDFs/LTST-C190GKT.pdf"
			(at 0 0 90)
			(layer "F.Fab")
			(hide yes)
			(effects
				(font
					(size 1.27 1.27)
					(thickness 0.15)
				)
			)
		)
		(property "Description" "LED, Green, SMD, 0603, 20 mA, 2.1 V, 569 nm"
			(at 0 0 90)
			(layer "F.Fab")
			(hide yes)
			(effects
				(font
					(size 1.27 1.27)
					(thickness 0.15)
				)
			)
		)
		(property "MPN" "LTST-C190GKT"
			(at 0 0 270)
			(unlocked yes)
			(layer "F.Fab")
			(hide yes)
			(effects
				(font
					(size 1 1)
					(thickness 0.15)
				)
			)
		)
		(property "Manufacturer" "Lite-On"
			(at 0 0 270)
			(unlocked yes)
			(layer "F.Fab")
			(hide yes)
			(effects
				(font
					(size 1 1)
					(thickness 0.15)
				)
			)
		)
		(property "Author" "Antmicro"
			(at 0 0 270)
			(unlocked yes)
			(layer "F.Fab")
			(hide yes)
			(effects
				(font
					(size 1 1)
					(thickness 0.15)
				)
			)
		)
		(property "License" "Apache-2.0"
			(at 0 0 270)
			(unlocked yes)
			(layer "F.Fab")
			(hide yes)
			(effects
				(font
					(size 1 1)
					(thickness 0.15)
				)
			)
		)
		(property "Color" "Green"
			(at 0 0 270)
			(unlocked yes)
			(layer "F.Fab")
			(hide yes)
			(effects
				(font
					(size 1 1)
					(thickness 0.15)
				)
			)
		)
		(sheetname "/Power/")
		(sheetfile "power.kicad_sch")
		(attr smd)
		(fp_line
			(start 0.22 0.35)
			(end -0.22 0.35)
			(stroke
				(width 0.15)
				(type solid)
			)
			(layer "F.SilkS")
		)
		(fp_line
			(start -0.094672 0.201008)
			(end -0.094672 -0.198992)
			(stroke
				(width 0.1)
				(type solid)
			)
			(layer "F.SilkS")
		)
		(fp_line
			(start 0.105328 0.201008)
			(end -0.094672 0.001008)
			(stroke
				(width 0.1)
				(type solid)
			)
			(layer "F.SilkS")
		)
		(fp_line
			(start 0.105328 0.201008)
			(end 0.105328 -0.198992)
			(stroke
				(width 0.1)
				(type solid)
			)
			(layer "F.SilkS")
		)
		(fp_line
			(start -0.094672 0.001008)
			(end -0.24 0.001008)
			(stroke
				(width 0.1)
				(type solid)
			)
			(layer "F.SilkS")
		)
		(fp_line
			(start -0.094672 0.001008)
			(end 0.105328 -0.198992)
			(stroke
				(width 0.1)
				(type solid)
			)
			(layer "F.SilkS")
		)
		(fp_line
			(start 0.105328 0.001008)
			(end 0.24 0.001)
			(stroke
				(width 0.1)
				(type solid)
			)
			(layer "F.SilkS")
		)
		(fp_line
			(start -1.18 -0.319)
			(end -1.18 0.321)
			(stroke
				(width 0.15)
				(type solid)
			)
			(layer "F.SilkS")
		)
		(fp_line
			(start 0.22 -0.35)
			(end -0.22 -0.35)
			(stroke
				(width 0.15)
				(type solid)
			)
			(layer "F.SilkS")
		)
		(fp_rect
			(start 1.25 0.65)
			(end -1.25 -0.65)
			(stroke
				(width 0.05)
				(type solid)
			)
			(fill no)
			(layer "F.CrtYd")
		)
		(fp_line
			(start -0.199 0.2)
			(end -0.199 0.1)
			(stroke
				(width 0.15)
				(type solid)
			)
			(layer "F.Fab")
		)
		(fp_line
			(start 0.201 0.2)
			(end 0.201 0)
			(stroke
				(width 0.15)
				(type solid)
			)
			(layer "F.Fab")
		)
		(fp_line
			(start -0.199 0)
			(end -0.597 0)
			(stroke
				(width 0.15)
				(type solid)
			)
			(layer "F.Fab")
		)
		(fp_line
			(start -0.101 0)
			(end 0.201 0.2)
			(stroke
				(width 0.15)
				(type solid)
			)
			(layer "F.Fab")
		)
		(fp_line
			(start 0.201 0)
			(end 0.201 -0.202)
			(stroke
				(width 0.15)
				(type solid)
			)
			(layer "F.Fab")
		)
		(fp_line
			(start 0.599 0)
			(end 0.201 0)
			(stroke
				(width 0.15)
				(type solid)
			)
			(layer "F.Fab")
		)
		(fp_line
			(start -0.199 -0.202)
			(end -0.199 0.1)
			(stroke
				(width 0.15)
				(type solid)
			)
			(layer "F.Fab")
		)
		(fp_line
			(start 0.201 -0.202)
			(end -0.101 0)
			(stroke
				(width 0.15)
				(type solid)
			)
			(layer "F.Fab")
		)
		(fp_rect
			(start 0.848 0.4)
			(end -0.85 -0.402)
			(stroke
				(width 0.15)
				(type solid)
			)
			(fill no)
			(layer "F.Fab")
		)
		(fp_text user "${REFERENCE}"
			(at -1.4224 5.999 90)
			(layer "F.Fab")
			(effects
				(font
					(size 0.7 0.7)
					(thickness 0.15)
				)
				(justify right top)
			)
		)
		(fp_text user "License: Apache-2.0"
			(at -1.4224 3.599 90)
			(layer "F.Fab")
			(effects
				(font
					(size 0.7 0.7)
					(thickness 0.15)
				)
				(justify right top)
			)
		)
		(fp_text user "Author: Antmicro"
			(at -1.4224 4.799 90)
			(layer "F.Fab")
			(effects
				(font
					(size 0.7 0.7)
					(thickness 0.15)
				)
				(justify right top)
			)
		)
		(pad "1" smd roundrect
			(at -0.7 0 90)
			(size 0.8 1)
			(layers "F.Cu" "F.Mask" "F.Paste")
			(roundrect_rratio 0.2)
			(net 1 "GND")
			(pinfunction "C")
			(pintype "passive")
		)
		(pad "2" smd roundrect
			(at 0.7 0 90)
			(size 0.8 1)
			(layers "F.Cu" "F.Mask" "F.Paste")
			(roundrect_rratio 0.2)
			(net 639 "Net-(D31-A)")
			(pinfunction "A")
			(pintype "passive")
		)
	)
	(footprint "antmicro-footprints:C_0402_1005Metric"
		(layer "F.Cu")
		(at 105.869999 55.25 180)
		(descr "Capacitor SMD 0402")
		(tags "capacitor SMD 0402")
		(property "Reference" "C387"
			(at -0.930001 1.2 0)
			(layer "F.SilkS")
			(effects
				(font
					(size 0.7 0.7)
					(thickness 0.15)
				)
				(justify right top)
			)
		)
		(property "Value" "C_100n_0402"
			(at -1.022927 2.155213 0)
			(layer "F.Fab")
			(effects
				(font
					(size 0.7 0.7)
					(thickness 0.15)
				)
				(justify right top)
			)
		)
		(property "Datasheet" "https://www.murata.com/products/productdetail?partno=GRM155R61H104KE14%23"
			(at 0 0 0)
			(layer "F.Fab")
			(hide yes)
			(effects
				(font
					(size 1.27 1.27)
					(thickness 0.15)
				)
			)
		)
		(property "Description" "SMD Multilayer Ceramic Capacitor, 0.1 µF, 50 V, 0402 [1005 Metric], ± 10%, X5R, GRM Series"
			(at 0 0 0)
			(layer "F.Fab")
			(hide yes)
			(effects
				(font
					(size 1.27 1.27)
					(thickness 0.15)
				)
			)
		)
		(property "MPN" "GRM155R61H104KE14D"
			(at 0 0 180)
			(unlocked yes)
			(layer "F.Fab")
			(hide yes)
			(effects
				(font
					(size 1 1)
					(thickness 0.15)
				)
			)
		)
		(property "Manufacturer" "Murata"
			(at 0 0 180)
			(unlocked yes)
			(layer "F.Fab")
			(hide yes)
			(effects
				(font
					(size 1 1)
					(thickness 0.15)
				)
			)
		)
		(property "License" "Apache-2.0"
			(at 0 0 180)
			(unlocked yes)
			(layer "F.Fab")
			(hide yes)
			(effects
				(font
					(size 1 1)
					(thickness 0.15)
				)
			)
		)
		(property "Author" "Antmicro"
			(at 0 0 180)
			(unlocked yes)
			(layer "F.Fab")
			(hide yes)
			(effects
				(font
					(size 1 1)
					(thickness 0.15)
				)
			)
		)
		(property "Val" "100n"
			(at 0 0 180)
			(unlocked yes)
			(layer "F.Fab")
			(hide yes)
			(effects
				(font
					(size 1 1)
					(thickness 0.15)
				)
			)
		)
		(property "Voltage" "50V"
			(at 0 0 180)
			(unlocked yes)
			(layer "F.Fab")
			(hide yes)
			(effects
				(font
					(size 1 1)
					(thickness 0.15)
				)
			)
		)
		(property "Dielectric" "X5R"
			(at 0 0 180)
			(unlocked yes)
			(layer "F.Fab")
			(hide yes)
			(effects
				(font
					(size 1 1)
					(thickness 0.15)
				)
			)
		)
		(property "Public" "False"
			(at 0 0 180)
			(unlocked yes)
			(layer "F.Fab")
			(hide yes)
			(effects
				(font
					(size 1 1)
					(thickness 0.15)
				)
			)
		)
		(sheetname "/DCDC/")
		(sheetfile "dcdc.kicad_sch")
		(attr smd)
		(fp_poly
			(pts
				(xy -0.925 -0.47) (xy 0.925 -0.47) (xy 0.925 0.47) (xy -0.925 0.47)
			)
			(stroke
				(width 0.05)
				(type default)
			)
			(fill no)
			(layer "F.CrtYd")
		)
		(fp_line
			(start 0.504 0.248)
			(end -0.494 0.248)
			(stroke
				(width 0.15)
				(type solid)
			)
			(layer "F.Fab")
		)
		(fp_line
			(start 0.504 -0.25)
			(end 0.504 0.248)
			(stroke
				(width 0.15)
				(type solid)
			)
			(layer "F.Fab")
		)
		(fp_line
			(start -0.494 0.248)
			(end -0.494 -0.25)
			(stroke
				(width 0.15)
				(type solid)
			)
			(layer "F.Fab")
		)
		(fp_line
			(start -0.494 -0.25)
			(end 0.504 -0.25)
			(stroke
				(width 0.15)
				(type solid)
			)
			(layer "F.Fab")
		)
		(fp_text user "Author: Antmicro"
			(at -0.939 3.399 0)
			(layer "F.Fab")
			(effects
				(font
					(size 0.7 0.7)
					(thickness 0.15)
				)
				(justify right top)
			)
		)
		(fp_text user "License: Apache-2.0"
			(at -0.939 5.799 0)
			(layer "F.Fab")
			(effects
				(font
					(size 0.7 0.7)
					(thickness 0.15)
				)
				(justify right top)
			)
		)
		(fp_text user "${REFERENCE}"
			(at -0.939 4.599 0)
			(layer "F.Fab")
			(effects
				(font
					(size 0.7 0.7)
					(thickness 0.15)
				)
				(justify right top)
			)
		)
		(pad "1" smd roundrect
			(at -0.48 0 180)
			(size 0.59 0.64)
			(layers "F.Cu" "F.Mask" "F.Paste")
			(roundrect_rratio 0.25)
			(net 1 "GND")
			(pintype "passive")
		)
		(pad "2" smd roundrect
			(at 0.48 0 180)
			(size 0.59 0.64)
			(layers "F.Cu" "F.Mask" "F.Paste")
			(roundrect_rratio 0.25)
			(net 4 "+3V3_AON")
			(pintype "passive")
		)
	)
	(footprint "antmicro-footprints:R_0805_2012Metric"
		(layer "F.Cu")
		(at 162.829468 76.21 180)
		(property "Reference" "R284"
			(at 2.029468 0.71 0)
			(layer "F.SilkS")
			(effects
				(font
					(size 0.7 0.7)
					(thickness 0.15)
				)
				(justify right top)
			)
		)
		(property "Value" "R_0R001_0805"
			(at 0 1.8 0)
			(layer "F.Fab")
			(effects
				(font
					(size 0.7 0.7)
					(thickness 0.15)
				)
				(justify right top)
			)
		)
		(property "Datasheet" "https://www.eaton.com/content/dam/eaton/products/electronic-components/resources/data-sheet/eaton-msma-automotive-smd-current-sense-resistor-metal-strip-data-sheet-elx1179.pdf"
			(at 0 0 0)
			(layer "F.Fab")
			(hide yes)
			(effects
				(font
					(size 1.27 1.27)
					(thickness 0.15)
				)
			)
		)
		(property "Description" "Current Sense Resistors - SMD MSMA, 0805 SIZE, 1/2 Watt, 1 mohm, 50 TCR MnCu Metal AEC-Q"
			(at 0 0 0)
			(layer "F.Fab")
			(hide yes)
			(effects
				(font
					(size 1.27 1.27)
					(thickness 0.15)
				)
			)
		)
		(property "MPN" "MSMA0805R0010FSM"
			(at 0 0 180)
			(unlocked yes)
			(layer "F.Fab")
			(hide yes)
			(effects
				(font
					(size 1 1)
					(thickness 0.15)
				)
			)
		)
		(property "Manufacturer" "Eaton"
			(at 0 0 180)
			(unlocked yes)
			(layer "F.Fab")
			(hide yes)
			(effects
				(font
					(size 1 1)
					(thickness 0.15)
				)
			)
		)
		(property "License" "Apache-2.0"
			(at 0 0 180)
			(unlocked yes)
			(layer "F.Fab")
			(hide yes)
			(effects
				(font
					(size 1 1)
					(thickness 0.15)
				)
			)
		)
		(property "Author" "Antmicro"
			(at 0 0 180)
			(unlocked yes)
			(layer "F.Fab")
			(hide yes)
			(effects
				(font
					(size 1 1)
					(thickness 0.15)
				)
			)
		)
		(property "Val" "0R001"
			(at 0 0 180)
			(unlocked yes)
			(layer "F.Fab")
			(hide yes)
			(effects
				(font
					(size 1 1)
					(thickness 0.15)
				)
			)
		)
		(property "Tolerance" "1%"
			(at 0 0 180)
			(unlocked yes)
			(layer "F.Fab")
			(hide yes)
			(effects
				(font
					(size 1 1)
					(thickness 0.15)
				)
			)
		)
		(property "Public" "False"
			(at 0 0 180)
			(unlocked yes)
			(layer "F.Fab")
			(hide yes)
			(effects
				(font
					(size 1 1)
					(thickness 0.15)
				)
			)
		)
		(component_classes
			(class "DCDC_20V")
		)
		(sheetname "/DCDC/")
		(sheetfile "dcdc.kicad_sch")
		(attr smd)
		(fp_line
			(start -0.3 -0.701)
			(end 0.298 -0.701)
			(stroke
				(width 0.15)
				(type solid)
			)
			(layer "F.SilkS")
		)
		(fp_line
			(start -0.32 0.699)
			(end 0.28 0.699)
			(stroke
				(width 0.15)
				(type solid)
			)
			(layer "F.SilkS")
		)
		(fp_rect
			(start 1.95 -0.9)
			(end -1.95 0.9)
			(stroke
				(width 0.05)
				(type default)
			)
			(fill no)
			(layer "F.CrtYd")
		)
		(fp_line
			(start 0.949 -0.677)
			(end 0.949 0.675)
			(stroke
				(width 0.15)
				(type solid)
			)
			(layer "F.Fab")
		)
		(fp_line
			(start -0.951 0.68)
			(end 0.949 0.68)
			(stroke
				(width 0.15)
				(type solid)
			)
			(layer "F.Fab")
		)
		(fp_line
			(start -0.951 -0.677)
			(end -0.951 0.675)
			(stroke
				(width 0.15)
				(type solid)
			)
			(layer "F.Fab")
		)
		(fp_line
			(start -0.951 -0.682)
			(end 0.949 -0.682)
			(stroke
				(width 0.15)
				(type solid)
			)
			(layer "F.Fab")
		)
		(fp_text user "License: Apache-2.0"
			(at -1.9 5.75 0)
			(layer "F.Fab")
			(effects
				(font
					(size 0.7 0.7)
					(thickness 0.15)
				)
				(justify right top)
			)
		)
		(fp_text user "Author: Antmicro"
			(at -1.9 4.4 0)
			(layer "F.Fab")
			(effects
				(font
					(size 0.7 0.7)
					(thickness 0.15)
				)
				(justify right top)
			)
		)
		(fp_text user "${REFERENCE}"
			(at -1.9 3.1 0)
			(layer "F.Fab")
			(effects
				(font
					(size 0.7 0.7)
					(thickness 0.15)
				)
				(justify right top)
			)
		)
		(pad "1" smd roundrect
			(at -1.1 0 180)
			(size 1.2 1.3)
			(layers "F.Cu" "F.Mask" "F.Paste")
			(roundrect_rratio 0.25)
			(net 1105 "/DCDC/20V_OUT")
			(pintype "passive")
		)
		(pad "2" smd roundrect
			(at 1.1 0 180)
			(size 1.2 1.3)
			(layers "F.Cu" "F.Mask" "F.Paste")
			(roundrect_rratio 0.25)
			(net 904 "+20V")
			(pintype "passive")
		)
	)
	(footprint "antmicro-footprints:R_0402_1005Metric"
		(layer "F.Cu")
		(at 183.25 139.95 180)
		(descr "Resistor SMD 0402")
		(tags "resistor SMD 0402")
		(property "Reference" "R326"
			(at -2.05 2.35 0)
			(layer "F.SilkS")
			(effects
				(font
					(size 0.7 0.7)
					(thickness 0.15)
				)
				(justify right top)
			)
		)
		(property "Value" "R_191k_0402"
			(at -1.011843 1.772047 0)
			(layer "F.Fab")
			(effects
				(font
					(size 0.7 0.7)
					(thickness 0.15)
				)
				(justify right top)
			)
		)
		(property "Datasheet" "https://www.bourns.com/docs/product-datasheets/cr.pdf"
			(at 0 0 0)
			(layer "F.Fab")
			(hide yes)
			(effects
				(font
					(size 1.27 1.27)
					(thickness 0.15)
				)
			)
		)
		(property "Description" "SMD Chip Resistor, 191 kohm, ± 1%, 100 mW, 0402 [1005 Metric], Thick Film, Precision"
			(at 0 0 0)
			(layer "F.Fab")
			(hide yes)
			(effects
				(font
					(size 1.27 1.27)
					(thickness 0.15)
				)
			)
		)
		(property "MPN" "CR0402-FX-1913GLF"
			(at 0 0 180)
			(unlocked yes)
			(layer "F.Fab")
			(hide yes)
			(effects
				(font
					(size 1 1)
					(thickness 0.15)
				)
			)
		)
		(property "Manufacturer" "Bourns"
			(at 0 0 180)
			(unlocked yes)
			(layer "F.Fab")
			(hide yes)
			(effects
				(font
					(size 1 1)
					(thickness 0.15)
				)
			)
		)
		(property "License" "Apache-2.0"
			(at 0 0 180)
			(unlocked yes)
			(layer "F.Fab")
			(hide yes)
			(effects
				(font
					(size 1 1)
					(thickness 0.15)
				)
			)
		)
		(property "Author" "Antmicro"
			(at 0 0 180)
			(unlocked yes)
			(layer "F.Fab")
			(hide yes)
			(effects
				(font
					(size 1 1)
					(thickness 0.15)
				)
			)
		)
		(property "Val" "191k"
			(at 0 0 180)
			(unlocked yes)
			(layer "F.Fab")
			(hide yes)
			(effects
				(font
					(size 1 1)
					(thickness 0.15)
				)
			)
		)
		(property "Tolerance" "1%"
			(at 0 0 180)
			(unlocked yes)
			(layer "F.Fab")
			(hide yes)
			(effects
				(font
					(size 1 1)
					(thickness 0.15)
				)
			)
		)
		(sheetname "/DCDC/")
		(sheetfile "dcdc.kicad_sch")
		(attr smd)
		(fp_rect
			(start -0.925 -0.47)
			(end 0.925 0.47)
			(stroke
				(width 0.05)
				(type default)
			)
			(fill no)
			(layer "F.CrtYd")
		)
		(fp_rect
			(start -0.5 -0.25)
			(end 0.5 0.25)
			(stroke
				(width 0.15)
				(type solid)
			)
			(fill no)
			(layer "F.Fab")
		)
		(fp_text user "${REFERENCE}"
			(at -0.95 3.168 0)
			(layer "F.Fab")
			(effects
				(font
					(size 0.7 0.7)
					(thickness 0.15)
				)
				(justify right top)
			)
		)
		(fp_text user "Author: Antmicro"
			(at -0.95 4.169 0)
			(layer "F.Fab")
			(effects
				(font
					(size 0.7 0.7)
					(thickness 0.15)
				)
				(justify right top)
			)
		)
		(fp_text user "License: Apache-2.0"
			(at -0.95 5.169 0)
			(layer "F.Fab")
			(effects
				(font
					(size 0.7 0.7)
					(thickness 0.15)
				)
				(justify right top)
			)
		)
		(pad "1" smd roundrect
			(at -0.48 0 180)
			(size 0.59 0.64)
			(layers "F.Cu" "F.Mask" "F.Paste")
			(roundrect_rratio 0.25)
			(net 1206 "/DCDC/12V_FB")
			(pintype "passive")
		)
		(pad "2" smd roundrect
			(at 0.48 0 180)
			(size 0.59 0.64)
			(layers "F.Cu" "F.Mask" "F.Paste")
			(roundrect_rratio 0.25)
			(net 880 "/DCDC/12V_OUT")
			(pintype "passive")
		)
	)
	(footprint "antmicro-footprints:TP_SMD_0.75mm"
		(layer "F.Cu")
		(at 201.15 73.45 -90)
		(property "Reference" "TP11"
			(at -3.45 0.15 270)
			(layer "F.SilkS")
			(effects
				(font
					(size 0.7 0.7)
					(thickness 0.15)
				)
				(justify right top)
			)
		)
		(property "Value" "TP_0.75mm_SMD"
			(at 0 1.2 90)
			(layer "F.Fab")
			(effects
				(font
					(size 0.7 0.7)
					(thickness 0.15)
				)
				(justify right top)
			)
		)
		(property "Description" "SMT test point"
			(at 0 0 90)
			(layer "F.Fab")
			(hide yes)
			(effects
				(font
					(size 1.27 1.27)
					(thickness 0.15)
				)
			)
		)
		(property "MPN" ""
			(at 0 0 270)
			(unlocked yes)
			(layer "F.Fab")
			(hide yes)
			(effects
				(font
					(size 1 1)
					(thickness 0.15)
				)
			)
		)
		(property "Manufacturer" ""
			(at 0 0 270)
			(unlocked yes)
			(layer "F.Fab")
			(hide yes)
			(effects
				(font
					(size 1 1)
					(thickness 0.15)
				)
			)
		)
		(property "Author" "Antmicro"
			(at 0 0 270)
			(unlocked yes)
			(layer "F.Fab")
			(hide yes)
			(effects
				(font
					(size 1 1)
					(thickness 0.15)
				)
			)
		)
		(property "License" "Apache-2.0"
			(at 0 0 270)
			(unlocked yes)
			(layer "F.Fab")
			(hide yes)
			(effects
				(font
					(size 1 1)
					(thickness 0.15)
				)
			)
		)
		(sheetname "/USB Debug, PD/")
		(sheetfile "usb_debug_pd.kicad_sch")
		(attr exclude_from_pos_files exclude_from_bom)
		(fp_circle
			(center 0 0)
			(end 0.475 0)
			(stroke
				(width 0.05)
				(type default)
			)
			(fill no)
			(layer "F.CrtYd")
		)
		(fp_text user "Author: Antmicro"
			(at -0.4 3.901 90)
			(layer "F.Fab")
			(effects
				(font
					(size 0.7 0.7)
					(thickness 0.15)
				)
				(justify right top)
			)
		)
		(fp_text user "License: Apache-2.0"
			(at -0.4 5.101 90)
			(layer "F.Fab")
			(effects
				(font
					(size 0.7 0.7)
					(thickness 0.15)
				)
				(justify right top)
			)
		)
		(fp_text user "${REFERENCE}"
			(at -0.4 2.7 90)
			(layer "F.Fab")
			(effects
				(font
					(size 0.7 0.7)
					(thickness 0.15)
				)
				(justify right top)
			)
		)
		(pad "1" smd circle
			(at 0 0 270)
			(size 0.75 0.75)
			(layers "F.Cu" "F.Mask")
			(net 1040 "/USB Debug, PD/PDC_I2C3_SDA")
			(pinfunction "1")
			(pintype "passive")
		)
	)
	(footprint "antmicro-footprints:SOD-523"
		(layer "F.Cu")
		(at 169.1 129.099 90)
		(property "Reference" "D9"
			(at -0.701 -0.75 90)
			(layer "F.SilkS")
			(effects
				(font
					(size 0.7 0.7)
					(thickness 0.15)
				)
				(justify left bottom)
			)
		)
		(property "Value" "PESD5Z5.0F"
			(at 0 1.499 90)
			(layer "F.Fab")
			(effects
				(font
					(size 0.7 0.7)
					(thickness 0.15)
				)
				(justify left bottom)
			)
		)
		(property "Datasheet" "https://assets.nexperia.com/documents/data-sheet/PESD5Z5_0.pdf"
			(at 0 0 90)
			(layer "F.Fab")
			(hide yes)
			(effects
				(font
					(size 1.27 1.27)
					(thickness 0.15)
				)
			)
		)
		(property "Description" "Unidirectional TVS, 30 kV,  SOD-523, 5 V, 89 pF"
			(at 0 0 90)
			(layer "F.Fab")
			(hide yes)
			(effects
				(font
					(size 1.27 1.27)
					(thickness 0.15)
				)
			)
		)
		(property "Manufacturer" "Nexperia"
			(at 0 0 90)
			(unlocked yes)
			(layer "F.Fab")
			(hide yes)
			(effects
				(font
					(size 1 1)
					(thickness 0.15)
				)
			)
		)
		(property "MPN" "PESD5Z5.0F"
			(at 0 0 90)
			(unlocked yes)
			(layer "F.Fab")
			(hide yes)
			(effects
				(font
					(size 1 1)
					(thickness 0.15)
				)
			)
		)
		(property "Author" "Antmicro"
			(at 0 0 90)
			(unlocked yes)
			(layer "F.Fab")
			(hide yes)
			(effects
				(font
					(size 1 1)
					(thickness 0.15)
				)
			)
		)
		(property "License" "Apache-2.0"
			(at 0 0 90)
			(unlocked yes)
			(layer "F.Fab")
			(hide yes)
			(effects
				(font
					(size 1 1)
					(thickness 0.15)
				)
			)
		)
		(sheetname "/DCDC/")
		(sheetfile "dcdc.kicad_sch")
		(attr smd)
		(fp_line
			(start -0.35 -0.5)
			(end -0.35 0.5)
			(stroke
				(width 0.15)
				(type solid)
			)
			(layer "F.SilkS")
		)
		(fp_rect
			(start -1 -0.6)
			(end 1 0.6)
			(stroke
				(width 0.05)
				(type solid)
			)
			(fill no)
			(layer "F.CrtYd")
		)
		(fp_line
			(start 0.65 -0.425)
			(end 0.65 0.423)
			(stroke
				(width 0.15)
				(type solid)
			)
			(layer "F.Fab")
		)
		(fp_line
			(start -0.652 -0.425)
			(end 0.65 -0.425)
			(stroke
				(width 0.15)
				(type solid)
			)
			(layer "F.Fab")
		)
		(fp_line
			(start -0.35 -0.4)
			(end -0.35 0.4)
			(stroke
				(width 0.15)
				(type solid)
			)
			(layer "F.Fab")
		)
		(fp_line
			(start -0.652 0.423)
			(end -0.652 -0.425)
			(stroke
				(width 0.15)
				(type solid)
			)
			(layer "F.Fab")
		)
		(fp_line
			(start -0.652 0.423)
			(end 0.65 0.423)
			(stroke
				(width 0.15)
				(type solid)
			)
			(layer "F.Fab")
		)
		(fp_text user "License: Apache-2.0"
			(at -1.276 5.9 90)
			(layer "F.Fab")
			(effects
				(font
					(size 0.7 0.7)
					(thickness 0.15)
				)
				(justify left bottom)
			)
		)
		(fp_text user "Author: Antmicro"
			(at -1.276 4.7 90)
			(layer "F.Fab")
			(effects
				(font
					(size 0.7 0.7)
					(thickness 0.15)
				)
				(justify left bottom)
			)
		)
		(fp_text user "${REFERENCE}"
			(at -1.276 3.499 90)
			(layer "F.Fab")
			(effects
				(font
					(size 0.7 0.7)
					(thickness 0.15)
				)
				(justify left bottom)
			)
		)
		(pad "1" smd roundrect
			(at -0.701 0 90)
			(size 0.5 0.6)
			(layers "F.Cu" "F.Mask" "F.Paste")
			(roundrect_rratio 0.25)
			(net 2 "+3V3")
			(pinfunction "C")
			(pintype "passive")
		)
		(pad "2" smd roundrect
			(at 0.699 0 90)
			(size 0.5 0.6)
			(layers "F.Cu" "F.Mask" "F.Paste")
			(roundrect_rratio 0.25)
			(net 1 "GND")
			(pinfunction "A")
			(pintype "passive")
		)
	)
	(footprint "antmicro-footprints:C_0805_2012Metric"
		(layer "F.Cu")
		(at 126.17 55.68)
		(descr "Capacitor SMD 0805")
		(tags "capacitor SMD 0805")
		(property "Reference" "C372"
			(at -8.76 9.73 0)
			(layer "F.SilkS")
			(effects
				(font
					(size 0.7 0.7)
					(thickness 0.15)
				)
				(justify left bottom)
			)
		)
		(property "Value" "C_22u_25V_0805"
			(at -2.055717 1.963153 0)
			(layer "F.Fab")
			(effects
				(font
					(size 0.7 0.7)
					(thickness 0.15)
				)
				(justify left bottom)
			)
		)
		(property "Datasheet" "https://product.samsungsem.com/mlcc/CL21A226MAYNNN.do"
			(at 0 0 0)
			(layer "F.Fab")
			(hide yes)
			(effects
				(font
					(size 1.27 1.27)
					(thickness 0.15)
				)
			)
		)
		(property "Description" "SMT Multilayer Ceramic Capacitor, 22uF, +/-20%, 25V, X5R, 0805 [2012 Metric]"
			(at 0 0 0)
			(layer "F.Fab")
			(hide yes)
			(effects
				(font
					(size 1.27 1.27)
					(thickness 0.15)
				)
			)
		)
		(property "MPN" "CL21A226MAYNNNE"
			(at 0 0 0)
			(unlocked yes)
			(layer "F.Fab")
			(hide yes)
			(effects
				(font
					(size 1 1)
					(thickness 0.15)
				)
			)
		)
		(property "Manufacturer" "Samsung Electro-Mechanics"
			(at 0 0 0)
			(unlocked yes)
			(layer "F.Fab")
			(hide yes)
			(effects
				(font
					(size 1 1)
					(thickness 0.15)
				)
			)
		)
		(property "License" "Apache-2.0"
			(at 0 0 0)
			(unlocked yes)
			(layer "F.Fab")
			(hide yes)
			(effects
				(font
					(size 1 1)
					(thickness 0.15)
				)
			)
		)
		(property "Author" "Antmicro"
			(at 0 0 0)
			(unlocked yes)
			(layer "F.Fab")
			(hide yes)
			(effects
				(font
					(size 1 1)
					(thickness 0.15)
				)
			)
		)
		(property "Val" "22u"
			(at 0 0 0)
			(unlocked yes)
			(layer "F.Fab")
			(hide yes)
			(effects
				(font
					(size 1 1)
					(thickness 0.15)
				)
			)
		)
		(property "Voltage" "25V"
			(at 0 0 0)
			(unlocked yes)
			(layer "F.Fab")
			(hide yes)
			(effects
				(font
					(size 1 1)
					(thickness 0.15)
				)
			)
		)
		(property "Dielectric" "X5R"
			(at 0 0 0)
			(unlocked yes)
			(layer "F.Fab")
			(hide yes)
			(effects
				(font
					(size 1 1)
					(thickness 0.15)
				)
			)
		)
		(property "Public" "False"
			(at 0 0 0)
			(unlocked yes)
			(layer "F.Fab")
			(hide yes)
			(effects
				(font
					(size 1 1)
					(thickness 0.15)
				)
			)
		)
		(sheetname "/DCDC/")
		(sheetfile "dcdc.kicad_sch")
		(attr smd)
		(fp_line
			(start -0.3 -0.7)
			(end 0.3 -0.7)
			(stroke
				(width 0.15)
				(type solid)
			)
			(layer "F.SilkS")
		)
		(fp_line
			(start -0.3 0.7)
			(end 0.3 0.7)
			(stroke
				(width 0.15)
				(type solid)
			)
			(layer "F.SilkS")
		)
		(fp_poly
			(pts
				(xy 1.95 -0.9) (xy 1.95 0.9) (xy -1.95 0.9) (xy -1.95 -0.9)
			)
			(stroke
				(width 0.05)
				(type default)
			)
			(fill no)
			(layer "F.CrtYd")
		)
		(fp_poly
			(pts
				(xy -0.95 -0.675001) (xy -0.95 0.675001) (xy 0.95 0.675001) (xy 0.95 -0.675001)
			)
			(stroke
				(width 0.15)
				(type solid)
			)
			(fill no)
			(layer "F.Fab")
		)
		(fp_text user "${REFERENCE}"
			(at -1.899999 3.947 0)
			(layer "F.Fab")
			(effects
				(font
					(size 0.7 0.7)
					(thickness 0.15)
				)
				(justify left bottom)
			)
		)
		(fp_text user "License: Apache-2.0"
			(at -1.9 4.947 0)
			(layer "F.Fab")
			(effects
				(font
					(size 0.7 0.7)
					(thickness 0.15)
				)
				(justify left bottom)
			)
		)
		(fp_text user "Author: Antmicro"
			(at -1.9 5.947 0)
			(layer "F.Fab")
			(effects
				(font
					(size 0.7 0.7)
					(thickness 0.15)
				)
				(justify left bottom)
			)
		)
		(pad "1" smd roundrect
			(at -1.099999 0)
			(size 1.2 1.3)
			(layers "F.Cu" "F.Mask" "F.Paste")
			(roundrect_rratio 0.25)
			(net 1 "GND")
			(pintype "passive")
		)
		(pad "2" smd roundrect
			(at 1.099999 0)
			(size 1.2 1.3)
			(layers "F.Cu" "F.Mask" "F.Paste")
			(roundrect_rratio 0.25)
			(net 13 "VCC")
			(pintype "passive")
		)
	)
	(footprint "antmicro-footprints:C_0402_1005Metric"
		(layer "F.Cu")
		(at 214.554132 84.282 -90)
		(descr "Capacitor SMD 0402")
		(tags "capacitor SMD 0402")
		(property "Reference" "C127"
			(at -3.682 0.324132 90)
			(layer "F.SilkS")
			(effects
				(font
					(size 0.7 0.7)
					(thickness 0.15)
				)
				(justify right top)
			)
		)
		(property "Value" "C_100n_0402"
			(at -1.022927 2.155213 90)
			(layer "F.Fab")
			(effects
				(font
					(size 0.7 0.7)
					(thickness 0.15)
				)
				(justify right top)
			)
		)
		(property "Datasheet" "https://www.murata.com/products/productdetail?partno=GRM155R61H104KE14%23"
			(at 0 0 90)
			(layer "F.Fab")
			(hide yes)
			(effects
				(font
					(size 1.27 1.27)
					(thickness 0.15)
				)
			)
		)
		(property "Description" "SMD Multilayer Ceramic Capacitor, 0.1 µF, 50 V, 0402 [1005 Metric], ± 10%, X5R, GRM Series"
			(at 0 0 90)
			(layer "F.Fab")
			(hide yes)
			(effects
				(font
					(size 1.27 1.27)
					(thickness 0.15)
				)
			)
		)
		(property "Manufacturer" "Murata"
			(at 0 0 270)
			(unlocked yes)
			(layer "F.Fab")
			(hide yes)
			(effects
				(font
					(size 1 1)
					(thickness 0.15)
				)
			)
		)
		(property "MPN" "GRM155R61H104KE14D"
			(at 0 0 270)
			(unlocked yes)
			(layer "F.Fab")
			(hide yes)
			(effects
				(font
					(size 1 1)
					(thickness 0.15)
				)
			)
		)
		(property "Val" "100n"
			(at 0 0 270)
			(unlocked yes)
			(layer "F.Fab")
			(hide yes)
			(effects
				(font
					(size 1 1)
					(thickness 0.15)
				)
			)
		)
		(property "License" "Apache-2.0"
			(at 0 0 270)
			(unlocked yes)
			(layer "F.Fab")
			(hide yes)
			(effects
				(font
					(size 1 1)
					(thickness 0.15)
				)
			)
		)
		(property "Author" "Antmicro"
			(at 0 0 270)
			(unlocked yes)
			(layer "F.Fab")
			(hide yes)
			(effects
				(font
					(size 1 1)
					(thickness 0.15)
				)
			)
		)
		(property "Voltage" "50V"
			(at 0 0 270)
			(unlocked yes)
			(layer "F.Fab")
			(hide yes)
			(effects
				(font
					(size 1 1)
					(thickness 0.15)
				)
			)
		)
		(property "Dielectric" "X5R"
			(at 0 0 270)
			(unlocked yes)
			(layer "F.Fab")
			(hide yes)
			(effects
				(font
					(size 1 1)
					(thickness 0.15)
				)
			)
		)
		(sheetname "/USB DP Alt mode/")
		(sheetfile "usb_dp.kicad_sch")
		(attr smd)
		(fp_rect
			(start -0.925 -0.47)
			(end 0.925 0.47)
			(stroke
				(width 0.05)
				(type default)
			)
			(fill no)
			(layer "F.CrtYd")
		)
		(fp_line
			(start -0.494 0.248)
			(end -0.494 -0.25)
			(stroke
				(width 0.15)
				(type solid)
			)
			(layer "F.Fab")
		)
		(fp_line
			(start 0.504 0.248)
			(end -0.494 0.248)
			(stroke
				(width 0.15)
				(type solid)
			)
			(layer "F.Fab")
		)
		(fp_line
			(start -0.494 -0.25)
			(end 0.504 -0.25)
			(stroke
				(width 0.15)
				(type solid)
			)
			(layer "F.Fab")
		)
		(fp_line
			(start 0.504 -0.25)
			(end 0.504 0.248)
			(stroke
				(width 0.15)
				(type solid)
			)
			(layer "F.Fab")
		)
		(fp_text user "License: Apache-2.0"
			(at -0.939 5.799 90)
			(layer "F.Fab")
			(effects
				(font
					(size 0.7 0.7)
					(thickness 0.15)
				)
				(justify right top)
			)
		)
		(fp_text user "${REFERENCE}"
			(at -0.939 4.599 90)
			(layer "F.Fab")
			(effects
				(font
					(size 0.7 0.7)
					(thickness 0.15)
				)
				(justify right top)
			)
		)
		(fp_text user "Author: Antmicro"
			(at -0.939 3.399 90)
			(layer "F.Fab")
			(effects
				(font
					(size 0.7 0.7)
					(thickness 0.15)
				)
				(justify right top)
			)
		)
		(pad "1" smd roundrect
			(at -0.48 0 270)
			(size 0.59 0.64)
			(layers "F.Cu" "F.Mask" "F.Paste")
			(roundrect_rratio 0.25)
			(net 299 "/SoM_IO2/USBSS1.RX+")
			(pintype "passive")
		)
		(pad "2" smd roundrect
			(at 0.48 0 270)
			(size 0.59 0.64)
			(layers "F.Cu" "F.Mask" "F.Paste")
			(roundrect_rratio 0.25)
			(net 302 "/USB DP Alt mode/USBSS1_RX_C_P")
			(pintype "passive")
		)
	)
	(footprint "antmicro-footprints:R_0402_1005Metric"
		(layer "F.Cu")
		(at 136 110.1 180)
		(descr "Resistor SMD 0402")
		(tags "resistor SMD 0402")
		(property "Reference" "R347"
			(at 1 0.3 0)
			(layer "F.SilkS")
			(effects
				(font
					(size 0.7 0.7)
					(thickness 0.15)
				)
				(justify right top)
			)
		)
		(property "Value" "R_0R_0402"
			(at -1.011843 1.772047 0)
			(layer "F.Fab")
			(effects
				(font
					(size 0.7 0.7)
					(thickness 0.15)
				)
				(justify right top)
			)
		)
		(property "Datasheet" "https://industrial.panasonic.com/cdbs/www-data/pdf/RDA0000/AOA0000C301.pdf"
			(at 0 0 0)
			(layer "F.Fab")
			(hide yes)
			(effects
				(font
					(size 1.27 1.27)
					(thickness 0.15)
				)
			)
		)
		(property "Description" "SMD Chip Resistor, Jumper, 0 ohm, 100 mW, 0402 [1005 Metric], Thick Film, General Purpose"
			(at 0 0 0)
			(layer "F.Fab")
			(hide yes)
			(effects
				(font
					(size 1.27 1.27)
					(thickness 0.15)
				)
			)
		)
		(property "MPN" "ERJ2GE0R00X"
			(at 0 0 180)
			(unlocked yes)
			(layer "F.Fab")
			(hide yes)
			(effects
				(font
					(size 1 1)
					(thickness 0.15)
				)
			)
		)
		(property "Manufacturer" "Panasonic"
			(at 0 0 180)
			(unlocked yes)
			(layer "F.Fab")
			(hide yes)
			(effects
				(font
					(size 1 1)
					(thickness 0.15)
				)
			)
		)
		(property "License" "Apache-2.0"
			(at 0 0 180)
			(unlocked yes)
			(layer "F.Fab")
			(hide yes)
			(effects
				(font
					(size 1 1)
					(thickness 0.15)
				)
			)
		)
		(property "Author" "Antmicro"
			(at 0 0 180)
			(unlocked yes)
			(layer "F.Fab")
			(hide yes)
			(effects
				(font
					(size 1 1)
					(thickness 0.15)
				)
			)
		)
		(property "Val" "0R"
			(at 0 0 180)
			(unlocked yes)
			(layer "F.Fab")
			(hide yes)
			(effects
				(font
					(size 1 1)
					(thickness 0.15)
				)
			)
		)
		(property "Tolerance" "~"
			(at 0 0 180)
			(unlocked yes)
			(layer "F.Fab")
			(hide yes)
			(effects
				(font
					(size 1 1)
					(thickness 0.15)
				)
			)
		)
		(property "Current" "1A"
			(at 0 0 180)
			(unlocked yes)
			(layer "F.Fab")
			(hide yes)
			(effects
				(font
					(size 1 1)
					(thickness 0.15)
				)
			)
		)
		(sheetname "/Peripherals/")
		(sheetfile "peripherals.kicad_sch")
		(attr smd)
		(fp_rect
			(start -0.925 -0.47)
			(end 0.925 0.47)
			(stroke
				(width 0.05)
				(type default)
			)
			(fill no)
			(layer "F.CrtYd")
		)
		(fp_rect
			(start -0.5 -0.25)
			(end 0.5 0.25)
			(stroke
				(width 0.15)
				(type solid)
			)
			(fill no)
			(layer "F.Fab")
		)
		(fp_text user "${REFERENCE}"
			(at -0.95 3.168 0)
			(layer "F.Fab")
			(effects
				(font
					(size 0.7 0.7)
					(thickness 0.15)
				)
				(justify right top)
			)
		)
		(fp_text user "Author: Antmicro"
			(at -0.95 4.169 0)
			(layer "F.Fab")
			(effects
				(font
					(size 0.7 0.7)
					(thickness 0.15)
				)
				(justify right top)
			)
		)
		(fp_text user "License: Apache-2.0"
			(at -0.95 5.169 0)
			(layer "F.Fab")
			(effects
				(font
					(size 0.7 0.7)
					(thickness 0.15)
				)
				(justify right top)
			)
		)
		(pad "1" smd roundrect
			(at -0.48 0 180)
			(size 0.59 0.64)
			(layers "F.Cu" "F.Mask" "F.Paste")
			(roundrect_rratio 0.25)
			(net 1313 "/Peripherals/GPIOEX_P0_2")
			(pintype "passive")
		)
		(pad "2" smd roundrect
			(at 0.48 0 180)
			(size 0.59 0.64)
			(layers "F.Cu" "F.Mask" "F.Paste")
			(roundrect_rratio 0.25)
			(net 98 "/CSI/CAM_CTRL.CSIA_FLG")
			(pintype "passive")
		)
	)
	(footprint "antmicro-footprints:C_0402_1005Metric"
		(layer "F.Cu")
		(at 109.8 129.5)
		(descr "Capacitor SMD 0402")
		(tags "capacitor SMD 0402")
		(property "Reference" "C194"
			(at -0.9 -0.4 180)
			(layer "F.SilkS")
			(effects
				(font
					(size 0.7 0.7)
					(thickness 0.15)
				)
				(justify right top)
			)
		)
		(property "Value" "C_220n_0402"
			(at -1.022927 2.155213 180)
			(layer "F.Fab")
			(effects
				(font
					(size 0.7 0.7)
					(thickness 0.15)
				)
				(justify right top)
			)
		)
		(property "Datasheet" "https://www.yageo.com/en/Chart/Download/pdf/CC0402KRX5R6BB224"
			(at 0 0 180)
			(layer "F.Fab")
			(hide yes)
			(effects
				(font
					(size 1.27 1.27)
					(thickness 0.15)
				)
			)
		)
		(property "Description" "SMD Multilayer Ceramic Capacitor, 0.22 µF, 10 V, 0402 [1005 Metric], ± 10%, X5R, CC Series"
			(at 0 0 180)
			(layer "F.Fab")
			(hide yes)
			(effects
				(font
					(size 1.27 1.27)
					(thickness 0.15)
				)
			)
		)
		(property "MPN" "CC0402KRX5R6BB224"
			(at 0 0 180)
			(unlocked yes)
			(layer "F.Fab")
			(hide yes)
			(effects
				(font
					(size 1 1)
					(thickness 0.15)
				)
			)
		)
		(property "Val" "220n"
			(at 0 0 180)
			(unlocked yes)
			(layer "F.Fab")
			(hide yes)
			(effects
				(font
					(size 1 1)
					(thickness 0.15)
				)
			)
		)
		(property "Voltage" "25V"
			(at 0 0 180)
			(unlocked yes)
			(layer "F.Fab")
			(hide yes)
			(effects
				(font
					(size 1 1)
					(thickness 0.15)
				)
			)
		)
		(property "Dielectric" "X7R"
			(at 0 0 180)
			(unlocked yes)
			(layer "F.Fab")
			(hide yes)
			(effects
				(font
					(size 1 1)
					(thickness 0.15)
				)
			)
		)
		(property "Manufacturer" "YAGEO"
			(at 0 0 180)
			(unlocked yes)
			(layer "F.Fab")
			(hide yes)
			(effects
				(font
					(size 1 1)
					(thickness 0.15)
				)
			)
		)
		(property "License" "Apache-2.0"
			(at 0 0 180)
			(unlocked yes)
			(layer "F.Fab")
			(hide yes)
			(effects
				(font
					(size 1 1)
					(thickness 0.15)
				)
			)
		)
		(property "Author" "Antmicro"
			(at 0 0 180)
			(unlocked yes)
			(layer "F.Fab")
			(hide yes)
			(effects
				(font
					(size 1 1)
					(thickness 0.15)
				)
			)
		)
		(property "Public" "False"
			(at 0 0 180)
			(unlocked yes)
			(layer "F.Fab")
			(hide yes)
			(effects
				(font
					(size 1 1)
					(thickness 0.15)
				)
			)
		)
		(sheetname "/M.2/")
		(sheetfile "m2.kicad_sch")
		(attr smd)
		(fp_poly
			(pts
				(xy -0.925 -0.47) (xy -0.925 0.47) (xy 0.925 0.47) (xy 0.925 -0.47)
			)
			(stroke
				(width 0.05)
				(type default)
			)
			(fill no)
			(layer "F.CrtYd")
		)
		(fp_line
			(start -0.494 -0.25)
			(end 0.504 -0.25)
			(stroke
				(width 0.15)
				(type solid)
			)
			(layer "F.Fab")
		)
		(fp_line
			(start -0.494 0.248)
			(end -0.494 -0.25)
			(stroke
				(width 0.15)
				(type solid)
			)
			(layer "F.Fab")
		)
		(fp_line
			(start 0.504 -0.25)
			(end 0.504 0.248)
			(stroke
				(width 0.15)
				(type solid)
			)
			(layer "F.Fab")
		)
		(fp_line
			(start 0.504 0.248)
			(end -0.494 0.248)
			(stroke
				(width 0.15)
				(type solid)
			)
			(layer "F.Fab")
		)
		(fp_text user "${REFERENCE}"
			(at -0.939 4.599 180)
			(layer "F.Fab")
			(effects
				(font
					(size 0.7 0.7)
					(thickness 0.15)
				)
				(justify right top)
			)
		)
		(fp_text user "Author: Antmicro"
			(at -0.939 3.399 180)
			(layer "F.Fab")
			(effects
				(font
					(size 0.7 0.7)
					(thickness 0.15)
				)
				(justify right top)
			)
		)
		(fp_text user "License: Apache-2.0"
			(at -0.939 5.799 180)
			(layer "F.Fab")
			(effects
				(font
					(size 0.7 0.7)
					(thickness 0.15)
				)
				(justify right top)
			)
		)
		(pad "1" smd roundrect
			(at -0.48 0)
			(size 0.59 0.64)
			(layers "F.Cu" "F.Mask" "F.Paste")
			(roundrect_rratio 0.25)
			(net 15 "/M.2/PCIe_{C1x1}.TX0+")
			(pintype "passive")
		)
		(pad "2" smd roundrect
			(at 0.48 0)
			(size 0.59 0.64)
			(layers "F.Cu" "F.Mask" "F.Paste")
			(roundrect_rratio 0.25)
			(net 440 "/M.2/M2_E_PET0_P")
			(pintype "passive")
		)
	)
	(footprint "antmicro-footprints:SOT-23-8"
		(layer "F.Cu")
		(at 169.904468 137.22 -90)
		(descr "http://www.ti.com/lit/ds/symlink/ina219.pdf")
		(property "Reference" "U60"
			(at 1.18 -2.695532 90)
			(layer "F.SilkS")
			(effects
				(font
					(size 0.7 0.7)
					(thickness 0.15)
				)
				(justify left bottom)
			)
		)
		(property "Value" "INA219AIDCNR"
			(at -2.925 2.8 90)
			(layer "F.Fab")
			(effects
				(font
					(size 0.7 0.7)
					(thickness 0.15)
				)
				(justify right top)
			)
		)
		(property "Datasheet" "https://www.ti.com/lit/ds/symlink/ina219.pdf?ts=1713856455637&ref_url=https%253A%252F%252Fwww.mouser.es%252F"
			(at 0 0 90)
			(layer "F.Fab")
			(hide yes)
			(effects
				(font
					(size 1.27 1.27)
					(thickness 0.15)
				)
			)
		)
		(property "Description" "Zerø-Drift, Bidirectional Current/Power Monitor With I2C Interface"
			(at 0 0 90)
			(layer "F.Fab")
			(hide yes)
			(effects
				(font
					(size 1.27 1.27)
					(thickness 0.15)
				)
			)
		)
		(property "Manufacturer" "Texas Instruments"
			(at 0 0 270)
			(unlocked yes)
			(layer "F.Fab")
			(hide yes)
			(effects
				(font
					(size 1 1)
					(thickness 0.15)
				)
			)
		)
		(property "MPN" "INA219AIDCNR"
			(at 0 0 270)
			(unlocked yes)
			(layer "F.Fab")
			(hide yes)
			(effects
				(font
					(size 1 1)
					(thickness 0.15)
				)
			)
		)
		(property "Author" "Antmicro"
			(at 0 0 270)
			(unlocked yes)
			(layer "F.Fab")
			(hide yes)
			(effects
				(font
					(size 1 1)
					(thickness 0.15)
				)
			)
		)
		(property "License" "Apache-2.0"
			(at 0 0 270)
			(unlocked yes)
			(layer "F.Fab")
			(hide yes)
			(effects
				(font
					(size 1 1)
					(thickness 0.15)
				)
			)
		)
		(sheetname "/DCDC/")
		(sheetfile "dcdc.kicad_sch")
		(attr smd)
		(fp_line
			(start -0.987 1.6)
			(end -0.987 1.324)
			(stroke
				(width 0.15)
				(type solid)
			)
			(layer "F.SilkS")
		)
		(fp_line
			(start -0.613 1.6)
			(end -0.987 1.6)
			(stroke
				(width 0.15)
				(type solid)
			)
			(layer "F.SilkS")
		)
		(fp_line
			(start 1 1.6)
			(end 0.6 1.6)
			(stroke
				(width 0.15)
				(type solid)
			)
			(layer "F.SilkS")
		)
		(fp_line
			(start 1 1.3)
			(end 1 1.6)
			(stroke
				(width 0.15)
				(type solid)
			)
			(layer "F.SilkS")
		)
		(fp_line
			(start -1 -1.3)
			(end -1 -1.6)
			(stroke
				(width 0.15)
				(type solid)
			)
			(layer "F.SilkS")
		)
		(fp_line
			(start 1 -1.3)
			(end 1 -1.6)
			(stroke
				(width 0.15)
				(type solid)
			)
			(layer "F.SilkS")
		)
		(fp_line
			(start -1 -1.6)
			(end -0.6 -1.6)
			(stroke
				(width 0.15)
				(type solid)
			)
			(layer "F.SilkS")
		)
		(fp_line
			(start 1 -1.6)
			(end 0.625 -1.6)
			(stroke
				(width 0.15)
				(type solid)
			)
			(layer "F.SilkS")
		)
		(fp_circle
			(center -1.3 -1.4)
			(end -1.25 -1.4)
			(stroke
				(width 0.15)
				(type solid)
			)
			(fill yes)
			(layer "F.SilkS")
		)
		(fp_rect
			(start -1.9 -1.75)
			(end 1.898 1.75)
			(stroke
				(width 0.05)
				(type solid)
			)
			(fill no)
			(layer "F.CrtYd")
		)
		(fp_line
			(start -1.4 -1.25)
			(end -1.2 -1.45)
			(stroke
				(width 0.15)
				(type solid)
			)
			(layer "F.Fab")
		)
		(fp_rect
			(start -1.401 -1.45)
			(end 1.398 1.449)
			(stroke
				(width 0.15)
				(type solid)
			)
			(fill no)
			(layer "F.Fab")
		)
		(fp_text user "License: Apache-2.0"
			(at -2.925 6 90)
			(layer "F.Fab")
			(effects
				(font
					(size 0.7 0.7)
					(thickness 0.15)
				)
				(justify right top)
			)
		)
		(fp_text user "Author: Antmicro"
			(at -2.925 7.2 90)
			(layer "F.Fab")
			(effects
				(font
					(size 0.7 0.7)
					(thickness 0.15)
				)
				(justify right top)
			)
		)
		(fp_text user "${REFERENCE}"
			(at -2.925 4.8 90)
			(layer "F.Fab")
			(effects
				(font
					(size 0.7 0.7)
					(thickness 0.15)
				)
				(justify right top)
			)
		)
		(pad "1" smd roundrect
			(at -1.3 -0.975 180)
			(size 0.45 1.1)
			(layers "F.Cu" "F.Mask" "F.Paste")
			(roundrect_rratio 0.25)
			(net 1282 "Net-(U60-IN+)")
			(pinfunction "IN+")
			(pintype "passive")
		)
		(pad "2" smd roundrect
			(at -1.3 -0.325 180)
			(size 0.45 1.1)
			(layers "F.Cu" "F.Mask" "F.Paste")
			(roundrect_rratio 0.25)
			(net 1162 "Net-(U60-IN-)")
			(pinfunction "IN-")
			(pintype "passive")
		)
		(pad "3" smd roundrect
			(at -1.3 0.325 180)
			(size 0.45 1.1)
			(layers "F.Cu" "F.Mask" "F.Paste")
			(roundrect_rratio 0.25)
			(net 1 "GND")
			(pinfunction "GND")
			(pintype "power_in")
		)
		(pad "4" smd roundrect
			(at -1.3 0.975 180)
			(size 0.45 1.1)
			(layers "F.Cu" "F.Mask" "F.Paste")
			(roundrect_rratio 0.25)
			(net 4 "+3V3_AON")
			(pinfunction "V_{S}")
			(pintype "power_in")
		)
		(pad "5" smd roundrect
			(at 1.3 0.975 180)
			(size 0.45 1.1)
			(layers "F.Cu" "F.Mask" "F.Paste")
			(roundrect_rratio 0.25)
			(net 853 "/I2C_{SYS}.SCL")
			(pinfunction "SCL")
			(pintype "open_collector")
		)
		(pad "6" smd roundrect
			(at 1.3 0.325 180)
			(size 0.45 1.1)
			(layers "F.Cu" "F.Mask" "F.Paste")
			(roundrect_rratio 0.25)
			(net 850 "/I2C_{SYS}.SDA")
			(pinfunction "SDA")
			(pintype "open_collector")
		)
		(pad "7" smd roundrect
			(at 1.3 -0.325 180)
			(size 0.45 1.1)
			(layers "F.Cu" "F.Mask" "F.Paste")
			(roundrect_rratio 0.25)
			(net 850 "/I2C_{SYS}.SDA")
			(pinfunction "A0")
			(pintype "passive")
		)
		(pad "8" smd roundrect
			(at 1.3 -0.975 180)
			(size 0.45 1.1)
			(layers "F.Cu" "F.Mask" "F.Paste")
			(roundrect_rratio 0.25)
			(net 1 "GND")
			(pinfunction "A1")
			(pintype "passive")
		)
	)
	(footprint "antmicro-footprints:L_Coilcraft-XAL7070"
		(layer "F.Cu")
		(at 180 77.5 180)
		(property "Reference" "L4"
			(at -4.4 -2.2 90)
			(layer "F.SilkS")
			(effects
				(font
					(size 0.7 0.7)
					(thickness 0.15)
				)
				(justify right top)
			)
		)
		(property "Value" "L_3u3_15.1A_Coilcraft-XAL7070"
			(at 0 5.2 0)
			(layer "F.Fab")
			(effects
				(font
					(size 0.7 0.7)
					(thickness 0.15)
				)
				(justify right top)
			)
		)
		(property "Datasheet" "https://www.coilcraft.com/en-us/products/power/shielded-inductors/molded-inductor/xal/xal7070/xal7070-332/"
			(at 0 0 0)
			(layer "F.Fab")
			(hide yes)
			(effects
				(font
					(size 1.27 1.27)
					(thickness 0.15)
				)
			)
		)
		(property "Description" "Power Inductor (SMD), 3.3 µH, 15.1 A, Shielded, 19.4 A, XAL7070"
			(at 0 0 0)
			(layer "F.Fab")
			(hide yes)
			(effects
				(font
					(size 1.27 1.27)
					(thickness 0.15)
				)
			)
		)
		(property "Val" "3u3/15.1A"
			(at 0 0 180)
			(unlocked yes)
			(layer "F.Fab")
			(hide yes)
			(effects
				(font
					(size 1 1)
					(thickness 0.15)
				)
			)
		)
		(property "Manufacturer" "Coilcraft"
			(at 0 0 180)
			(unlocked yes)
			(layer "F.Fab")
			(hide yes)
			(effects
				(font
					(size 1 1)
					(thickness 0.15)
				)
			)
		)
		(property "MPN" "XAL7070-332MEB"
			(at 0 0 180)
			(unlocked yes)
			(layer "F.Fab")
			(hide yes)
			(effects
				(font
					(size 1 1)
					(thickness 0.15)
				)
			)
		)
		(property "ISat" "19.4 A"
			(at 0 0 180)
			(unlocked yes)
			(layer "F.Fab")
			(hide yes)
			(effects
				(font
					(size 1 1)
					(thickness 0.15)
				)
			)
		)
		(property "IMax" "15.1 A"
			(at 0 0 180)
			(unlocked yes)
			(layer "F.Fab")
			(hide yes)
			(effects
				(font
					(size 1 1)
					(thickness 0.15)
				)
			)
		)
		(property "Size" "7.7x8"
			(at 0 0 180)
			(unlocked yes)
			(layer "F.Fab")
			(hide yes)
			(effects
				(font
					(size 1 1)
					(thickness 0.15)
				)
			)
		)
		(property "Author" "Antmicro"
			(at 0 0 180)
			(unlocked yes)
			(layer "F.Fab")
			(hide yes)
			(effects
				(font
					(size 1 1)
					(thickness 0.15)
				)
			)
		)
		(property "License" "Apache-2.0"
			(at 0 0 180)
			(unlocked yes)
			(layer "F.Fab")
			(hide yes)
			(effects
				(font
					(size 1 1)
					(thickness 0.15)
				)
			)
		)
		(component_classes
			(class "DCDC_20V")
		)
		(sheetname "/DCDC/")
		(sheetfile "dcdc.kicad_sch")
		(attr smd)
		(fp_line
			(start 3.85 -4)
			(end 3.85 4)
			(stroke
				(width 0.15)
				(type solid)
			)
			(layer "F.SilkS")
		)
		(fp_line
			(start 3.85 -4)
			(end -3.85 -4)
			(stroke
				(width 0.15)
				(type solid)
			)
			(layer "F.SilkS")
		)
		(fp_line
			(start -3.85 4)
			(end 3.85 4)
			(stroke
				(width 0.15)
				(type solid)
			)
			(layer "F.SilkS")
		)
		(fp_line
			(start -3.85 4)
			(end -3.85 -4)
			(stroke
				(width 0.15)
				(type solid)
			)
			(layer "F.SilkS")
		)
		(fp_rect
			(start -4.09 -4.25)
			(end 4.09 4.25)
			(stroke
				(width 0.05)
				(type solid)
			)
			(fill no)
			(layer "F.CrtYd")
		)
		(fp_line
			(start 3.85 4)
			(end -3.85 4)
			(stroke
				(width 0.15)
				(type solid)
			)
			(layer "F.Fab")
		)
		(fp_line
			(start 3.85 -4)
			(end 3.85 4)
			(stroke
				(width 0.15)
				(type solid)
			)
			(layer "F.Fab")
		)
		(fp_line
			(start -3.85 4)
			(end -3.85 -4)
			(stroke
				(width 0.15)
				(type solid)
			)
			(layer "F.Fab")
		)
		(fp_line
			(start -3.85 -4)
			(end 3.85 -4)
			(stroke
				(width 0.15)
				(type solid)
			)
			(layer "F.Fab")
		)
		(fp_text user "${REFERENCE}"
			(at -4.09 8.4 0)
			(layer "F.Fab")
			(effects
				(font
					(size 0.7 0.7)
					(thickness 0.15)
				)
				(justify right top)
			)
		)
		(fp_text user "License: Apache-2.0"
			(at -4.09 9.6 0)
			(layer "F.Fab")
			(effects
				(font
					(size 0.7 0.7)
					(thickness 0.15)
				)
				(justify right top)
			)
		)
		(fp_text user "Author: Antmicro"
			(at -4.09 7.2 0)
			(layer "F.Fab")
			(effects
				(font
					(size 0.7 0.7)
					(thickness 0.15)
				)
				(justify right top)
			)
		)
		(pad "1" smd roundrect
			(at -2.41 0 180)
			(size 1.92 6.5)
			(layers "F.Cu" "F.Mask" "F.Paste")
			(roundrect_rratio 0.1)
			(net 1184 "/DCDC/20V_SW")
			(pintype "passive")
		)
		(pad "2" smd roundrect
			(at 2.41 0 180)
			(size 1.92 6.5)
			(layers "F.Cu" "F.Mask" "F.Paste")
			(roundrect_rratio 0.1)
			(net 1105 "/DCDC/20V_OUT")
			(pintype "passive")
		)
	)
	(footprint "antmicro-footprints:TP_SMD_0.75mm"
		(layer "F.Cu")
		(at 69.279 63.231 90)
		(property "Reference" "TP21"
			(at 0.39 3.17 0)
			(layer "F.SilkS")
			(effects
				(font
					(size 0.7 0.7)
					(thickness 0.15)
				)
				(justify right top)
			)
		)
		(property "Value" "TP_0.75mm_SMD"
			(at 0 1.2 90)
			(layer "F.Fab")
			(effects
				(font
					(size 0.7 0.7)
					(thickness 0.15)
				)
				(justify left bottom)
			)
		)
		(property "Description" "SMT test point"
			(at 0 0 90)
			(layer "F.Fab")
			(hide yes)
			(effects
				(font
					(size 1.27 1.27)
					(thickness 0.15)
				)
			)
		)
		(property "MPN" ""
			(at 0 0 90)
			(unlocked yes)
			(layer "F.Fab")
			(hide yes)
			(effects
				(font
					(size 1 1)
					(thickness 0.15)
				)
			)
		)
		(property "Manufacturer" ""
			(at 0 0 90)
			(unlocked yes)
			(layer "F.Fab")
			(hide yes)
			(effects
				(font
					(size 1 1)
					(thickness 0.15)
				)
			)
		)
		(property "Author" "Antmicro"
			(at 0 0 90)
			(unlocked yes)
			(layer "F.Fab")
			(hide yes)
			(effects
				(font
					(size 1 1)
					(thickness 0.15)
				)
			)
		)
		(property "License" "Apache-2.0"
			(at 0 0 90)
			(unlocked yes)
			(layer "F.Fab")
			(hide yes)
			(effects
				(font
					(size 1 1)
					(thickness 0.15)
				)
			)
		)
		(sheetname "/CSI/")
		(sheetfile "csi.kicad_sch")
		(attr exclude_from_pos_files exclude_from_bom)
		(fp_circle
			(center 0 0)
			(end 0.475 0)
			(stroke
				(width 0.05)
				(type default)
			)
			(fill no)
			(layer "F.CrtYd")
		)
		(fp_text user "Author: Antmicro"
			(at -0.4 3.901 90)
			(layer "F.Fab")
			(effects
				(font
					(size 0.7 0.7)
					(thickness 0.15)
				)
				(justify left bottom)
			)
		)
		(fp_text user "${REFERENCE}"
			(at -0.4 2.7 90)
			(layer "F.Fab")
			(effects
				(font
					(size 0.7 0.7)
					(thickness 0.15)
				)
				(justify left bottom)
			)
		)
		(fp_text user "License: Apache-2.0"
			(at -0.4 5.101 90)
			(layer "F.Fab")
			(effects
				(font
					(size 0.7 0.7)
					(thickness 0.15)
				)
				(justify left bottom)
			)
		)
		(pad "1" smd circle
			(at 0 0 90)
			(size 0.75 0.75)
			(layers "F.Cu" "F.Mask")
			(net 1045 "/CSI/MUX_I2C_4_SDA")
			(pinfunction "1")
			(pintype "passive")
		)
	)
	(footprint "antmicro-footprints:C_0402_1005Metric"
		(layer "F.Cu")
		(at 91.1 101.2)
		(descr "Capacitor SMD 0402")
		(tags "capacitor SMD 0402")
		(property "Reference" "C348"
			(at 1.1 0.5 0)
			(layer "F.SilkS")
			(effects
				(font
					(size 0.7 0.7)
					(thickness 0.15)
				)
				(justify left bottom)
			)
		)
		(property "Value" "C_100n_0402"
			(at -1.022927 2.155213 0)
			(layer "F.Fab")
			(effects
				(font
					(size 0.7 0.7)
					(thickness 0.15)
				)
				(justify left bottom)
			)
		)
		(property "Datasheet" "https://www.murata.com/products/productdetail?partno=GRM155R61H104KE14%23"
			(at 0 0 0)
			(layer "F.Fab")
			(hide yes)
			(effects
				(font
					(size 1.27 1.27)
					(thickness 0.15)
				)
			)
		)
		(property "Description" "SMD Multilayer Ceramic Capacitor, 0.1 µF, 50 V, 0402 [1005 Metric], ± 10%, X5R, GRM Series"
			(at 0 0 0)
			(layer "F.Fab")
			(hide yes)
			(effects
				(font
					(size 1.27 1.27)
					(thickness 0.15)
				)
			)
		)
		(property "Manufacturer" "Murata"
			(at 0 0 0)
			(unlocked yes)
			(layer "F.Fab")
			(hide yes)
			(effects
				(font
					(size 1 1)
					(thickness 0.15)
				)
			)
		)
		(property "MPN" "GRM155R61H104KE14D"
			(at 0 0 0)
			(unlocked yes)
			(layer "F.Fab")
			(hide yes)
			(effects
				(font
					(size 1 1)
					(thickness 0.15)
				)
			)
		)
		(property "Val" "100n"
			(at 0 0 0)
			(unlocked yes)
			(layer "F.Fab")
			(hide yes)
			(effects
				(font
					(size 1 1)
					(thickness 0.15)
				)
			)
		)
		(property "License" "Apache-2.0"
			(at 0 0 0)
			(unlocked yes)
			(layer "F.Fab")
			(hide yes)
			(effects
				(font
					(size 1 1)
					(thickness 0.15)
				)
			)
		)
		(property "Author" "Antmicro"
			(at 0 0 0)
			(unlocked yes)
			(layer "F.Fab")
			(hide yes)
			(effects
				(font
					(size 1 1)
					(thickness 0.15)
				)
			)
		)
		(property "Voltage" "50V"
			(at 0 0 0)
			(unlocked yes)
			(layer "F.Fab")
			(hide yes)
			(effects
				(font
					(size 1 1)
					(thickness 0.15)
				)
			)
		)
		(property "Dielectric" "X5R"
			(at 0 0 0)
			(unlocked yes)
			(layer "F.Fab")
			(hide yes)
			(effects
				(font
					(size 1 1)
					(thickness 0.15)
				)
			)
		)
		(sheetname "/SoM_IO2/")
		(sheetfile "som_io2.kicad_sch")
		(attr smd)
		(fp_poly
			(pts
				(xy -0.925 -0.47) (xy 0.925 -0.47) (xy 0.925 0.47) (xy -0.925 0.47)
			)
			(stroke
				(width 0.05)
				(type default)
			)
			(fill no)
			(layer "F.CrtYd")
		)
		(fp_line
			(start -0.494 -0.25)
			(end 0.504 -0.25)
			(stroke
				(width 0.15)
				(type solid)
			)
			(layer "F.Fab")
		)
		(fp_line
			(start -0.494 0.248)
			(end -0.494 -0.25)
			(stroke
				(width 0.15)
				(type solid)
			)
			(layer "F.Fab")
		)
		(fp_line
			(start 0.504 -0.25)
			(end 0.504 0.248)
			(stroke
				(width 0.15)
				(type solid)
			)
			(layer "F.Fab")
		)
		(fp_line
			(start 0.504 0.248)
			(end -0.494 0.248)
			(stroke
				(width 0.15)
				(type solid)
			)
			(layer "F.Fab")
		)
		(fp_text user "Author: Antmicro"
			(at -0.939 3.399 0)
			(layer "F.Fab")
			(effects
				(font
					(size 0.7 0.7)
					(thickness 0.15)
				)
				(justify left bottom)
			)
		)
		(fp_text user "License: Apache-2.0"
			(at -0.939 5.799 0)
			(layer "F.Fab")
			(effects
				(font
					(size 0.7 0.7)
					(thickness 0.15)
				)
				(justify left bottom)
			)
		)
		(fp_text user "${REFERENCE}"
			(at -0.939 4.599 0)
			(layer "F.Fab")
			(effects
				(font
					(size 0.7 0.7)
					(thickness 0.15)
				)
				(justify left bottom)
			)
		)
		(pad "1" smd roundrect
			(at -0.48 0)
			(size 0.59 0.64)
			(layers "F.Cu" "F.Mask" "F.Paste")
			(roundrect_rratio 0.25)
			(net 665 "/Expansion connector/DP3.TX0-")
			(pintype "passive")
		)
		(pad "2" smd roundrect
			(at 0.48 0)
			(size 0.59 0.64)
			(layers "F.Cu" "F.Mask" "F.Paste")
			(roundrect_rratio 0.25)
			(net 1268 "/SoM_IO2/DP3.TX0_C-")
			(pintype "passive")
		)
	)
	(footprint "antmicro-footprints:R_0402_1005Metric"
		(layer "F.Cu")
		(at 219.77 73.599951 180)
		(descr "Resistor SMD 0402")
		(tags "resistor SMD 0402")
		(property "Reference" "R119"
			(at 1.37 -2.550049 180)
			(layer "F.SilkS")
			(effects
				(font
					(size 0.7 0.7)
					(thickness 0.15)
				)
				(justify left bottom)
			)
		)
		(property "Value" "R_200R_0402"
			(at -1.011843 1.772047 180)
			(layer "F.Fab")
			(effects
				(font
					(size 0.7 0.7)
					(thickness 0.15)
				)
				(justify left bottom)
			)
		)
		(property "Datasheet" "https://www.bourns.com/docs/product-datasheets/cr.pdf"
			(at 0 0 180)
			(layer "F.Fab")
			(hide yes)
			(effects
				(font
					(size 1.27 1.27)
					(thickness 0.15)
				)
			)
		)
		(property "Description" "SMD Chip Resistor, 200 ohm, ± 1%, 62.5 mW, 0402 [1005 Metric], Thick Film, General Purpose"
			(at 0 0 180)
			(layer "F.Fab")
			(hide yes)
			(effects
				(font
					(size 1.27 1.27)
					(thickness 0.15)
				)
			)
		)
		(property "Manufacturer" "Bourns"
			(at 0 0 180)
			(unlocked yes)
			(layer "F.Fab")
			(hide yes)
			(effects
				(font
					(size 1 1)
					(thickness 0.15)
				)
			)
		)
		(property "MPN" "CR0402-FX-2000GLF"
			(at 0 0 180)
			(unlocked yes)
			(layer "F.Fab")
			(hide yes)
			(effects
				(font
					(size 1 1)
					(thickness 0.15)
				)
			)
		)
		(property "Val" "200R"
			(at 0 0 180)
			(unlocked yes)
			(layer "F.Fab")
			(hide yes)
			(effects
				(font
					(size 1 1)
					(thickness 0.15)
				)
			)
		)
		(property "License" "Apache-2.0"
			(at 0 0 180)
			(unlocked yes)
			(layer "F.Fab")
			(hide yes)
			(effects
				(font
					(size 1 1)
					(thickness 0.15)
				)
			)
		)
		(property "Author" "Antmicro"
			(at 0 0 180)
			(unlocked yes)
			(layer "F.Fab")
			(hide yes)
			(effects
				(font
					(size 1 1)
					(thickness 0.15)
				)
			)
		)
		(property "Tolerance" "1%"
			(at 0 0 180)
			(unlocked yes)
			(layer "F.Fab")
			(hide yes)
			(effects
				(font
					(size 1 1)
					(thickness 0.15)
				)
			)
		)
		(sheetname "/USB Debug, PD/")
		(sheetfile "usb_debug_pd.kicad_sch")
		(attr smd)
		(fp_rect
			(start -0.925 -0.47)
			(end 0.925 0.47)
			(stroke
				(width 0.05)
				(type default)
			)
			(fill no)
			(layer "F.CrtYd")
		)
		(fp_rect
			(start -0.5 -0.25)
			(end 0.5 0.25)
			(stroke
				(width 0.15)
				(type solid)
			)
			(fill no)
			(layer "F.Fab")
		)
		(fp_text user "Author: Antmicro"
			(at -0.95 4.169 180)
			(layer "F.Fab")
			(effects
				(font
					(size 0.7 0.7)
					(thickness 0.15)
				)
				(justify left bottom)
			)
		)
		(fp_text user "License: Apache-2.0"
			(at -0.95 5.169 180)
			(layer "F.Fab")
			(effects
				(font
					(size 0.7 0.7)
					(thickness 0.15)
				)
				(justify left bottom)
			)
		)
		(fp_text user "${REFERENCE}"
			(at -0.95 3.168 180)
			(layer "F.Fab")
			(effects
				(font
					(size 0.7 0.7)
					(thickness 0.15)
				)
				(justify left bottom)
			)
		)
		(pad "1" smd roundrect
			(at -0.48 0 180)
			(size 0.59 0.64)
			(layers "F.Cu" "F.Mask" "F.Paste")
			(roundrect_rratio 0.25)
			(net 535 "Net-(D20-A)")
			(pintype "passive")
		)
		(pad "2" smd roundrect
			(at 0.48 0 180)
			(size 0.59 0.64)
			(layers "F.Cu" "F.Mask" "F.Paste")
			(roundrect_rratio 0.25)
			(net 334 "/USB Debug, PD/FTDI_3V3")
			(pintype "passive")
		)
	)
	(footprint "antmicro-footprints:WQFN-40_1EP_6x3mm_Pitch0.4mm_EP4.7x2.7mm"
		(layer "F.Cu")
		(at 214.463632 89.772856 -90)
		(property "Reference" "U33"
			(at -3.500856 2.663632 180)
			(layer "F.SilkS")
			(effects
				(font
					(size 0.7 0.7)
					(thickness 0.15)
				)
				(justify right top)
			)
		)
		(property "Value" "TUSB1046-DCIRNQ"
			(at 0 3.4 270)
			(unlocked yes)
			(layer "F.Fab")
			(effects
				(font
					(size 0.7 0.7)
					(thickness 0.15)
				)
				(justify left bottom)
			)
		)
		(property "Datasheet" "https://www.ti.com/lit/ds/sllsew2d/sllsew2d.pdf?ts=1662107117482&ref_url=https%253A%252F%252Fwww.google.com%252F"
			(at 0 0 90)
			(layer "F.Fab")
			(hide yes)
			(effects
				(font
					(size 1.27 1.27)
					(thickness 0.15)
				)
			)
		)
		(property "Description" "Analog & Digital Crosspoint ICs USB Type-C DP ALT Mode, 10-Gbps linear redriver crosspoint switch 40-WQFN 0°C to 70°C"
			(at 0 0 90)
			(layer "F.Fab")
			(hide yes)
			(effects
				(font
					(size 1.27 1.27)
					(thickness 0.15)
				)
			)
		)
		(property "MPN" "TUSB1046-DCIRNQT"
			(at 0 0 270)
			(unlocked yes)
			(layer "F.Fab")
			(hide yes)
			(effects
				(font
					(size 1 1)
					(thickness 0.15)
				)
			)
		)
		(property "Manufacturer" "Texas Instruments"
			(at 0 0 270)
			(unlocked yes)
			(layer "F.Fab")
			(hide yes)
			(effects
				(font
					(size 1 1)
					(thickness 0.15)
				)
			)
		)
		(property "Author" "Antmicro"
			(at 0 0 270)
			(unlocked yes)
			(layer "F.Fab")
			(hide yes)
			(effects
				(font
					(size 1 1)
					(thickness 0.15)
				)
			)
		)
		(property "License" "Apache-2.0"
			(at 0 0 270)
			(unlocked yes)
			(layer "F.Fab")
			(hide yes)
			(effects
				(font
					(size 1 1)
					(thickness 0.15)
				)
			)
		)
		(sheetname "/USB DP Alt mode/")
		(sheetfile "usb_dp.kicad_sch")
		(attr smd)
		(fp_line
			(start -3.101 2.1)
			(end -3.101 1.6)
			(stroke
				(width 0.15)
				(type solid)
			)
			(layer "F.SilkS")
		)
		(fp_line
			(start -2.4 2.1)
			(end -3.101 2.1)
			(stroke
				(width 0.15)
				(type solid)
			)
			(layer "F.SilkS")
		)
		(fp_line
			(start 3.1 2.1)
			(end 2.398 2.1)
			(stroke
				(width 0.15)
				(type solid)
			)
			(layer "F.SilkS")
		)
		(fp_line
			(start 3.1 1.6)
			(end 3.1 2.1)
			(stroke
				(width 0.15)
				(type solid)
			)
			(layer "F.SilkS")
		)
		(fp_line
			(start -2.4 -2.101)
			(end -3.101 -2.101)
			(stroke
				(width 0.15)
				(type solid)
			)
			(layer "F.SilkS")
		)
		(fp_line
			(start 3.1 -2.101)
			(end 3.1 -1.601)
			(stroke
				(width 0.15)
				(type solid)
			)
			(layer "F.SilkS")
		)
		(fp_line
			(start 3.1 -2.101)
			(end 2.398 -2.101)
			(stroke
				(width 0.15)
				(type solid)
			)
			(layer "F.SilkS")
		)
		(fp_circle
			(center -3.8 -1.41)
			(end -3.75 -1.36)
			(stroke
				(width 0.15)
				(type solid)
			)
			(fill yes)
			(layer "F.SilkS")
		)
		(fp_rect
			(start -3.5 -2.5)
			(end 3.499 2.499)
			(stroke
				(width 0.05)
				(type solid)
			)
			(fill no)
			(layer "F.CrtYd")
		)
		(fp_line
			(start -2.9 1.898)
			(end -2.9 -1.2)
			(stroke
				(width 0.15)
				(type solid)
			)
			(layer "F.Fab")
		)
		(fp_line
			(start 2.898 1.898)
			(end -2.9 1.898)
			(stroke
				(width 0.15)
				(type solid)
			)
			(layer "F.Fab")
		)
		(fp_line
			(start -2.9 -1.2)
			(end -2.2 -1.9)
			(stroke
				(width 0.15)
				(type solid)
			)
			(layer "F.Fab")
		)
		(fp_line
			(start -2.2 -1.9)
			(end 2.898 -1.901)
			(stroke
				(width 0.15)
				(type solid)
			)
			(layer "F.Fab")
		)
		(fp_line
			(start 2.898 -1.901)
			(end 2.898 1.898)
			(stroke
				(width 0.15)
				(type solid)
			)
			(layer "F.Fab")
		)
		(fp_text user "${REFERENCE}"
			(at -3.101 4.099 90)
			(layer "F.Fab")
			(effects
				(font
					(size 0.7 0.7)
					(thickness 0.15)
				)
				(justify right top)
			)
		)
		(fp_text user "License: Apache-2.0"
			(at -3.101 6.099 90)
			(layer "F.Fab")
			(effects
				(font
					(size 0.7 0.7)
					(thickness 0.15)
				)
				(justify right top)
			)
		)
		(fp_text user "Author: Antmicro"
			(at -3.101 5.099 90)
			(layer "F.Fab")
			(effects
				(font
					(size 0.7 0.7)
					(thickness 0.15)
				)
				(justify right top)
			)
		)
		(pad "1" smd roundrect
			(at -2.9 -1.401)
			(size 0.2 0.6)
			(layers "F.Cu" "F.Mask" "F.Paste")
			(roundrect_rratio 0.25)
			(net 2 "+3V3")
			(pinfunction "VCC")
			(pintype "power_in")
		)
		(pad "2" smd roundrect
			(at -2.9 -1)
			(size 0.2 0.6)
			(layers "F.Cu" "F.Mask" "F.Paste")
			(roundrect_rratio 0.25)
			(net 967 "/USB DP Alt mode/USBC1_DPEQ1")
			(pinfunction "DPEQ1")
			(pintype "input")
		)
		(pad "3" smd roundrect
			(at -2.9 -0.6)
			(size 0.2 0.6)
			(layers "F.Cu" "F.Mask" "F.Paste")
			(roundrect_rratio 0.25)
			(net 965 "/USB DP Alt mode/USBC1_SSEQ1")
			(pinfunction "SSEQ1")
			(pintype "input")
		)
		(pad "4" smd roundrect
			(at -2.9 -0.202)
			(size 0.2 0.6)
			(layers "F.Cu" "F.Mask" "F.Paste")
			(roundrect_rratio 0.25)
			(net 322 "/USB DP Alt mode/USBSS1_RX_C_N")
			(pinfunction "SSRX_N")
			(pintype "output")
		)
		(pad "5" smd roundrect
			(at -2.9 0.2)
			(size 0.2 0.6)
			(layers "F.Cu" "F.Mask" "F.Paste")
			(roundrect_rratio 0.25)
			(net 302 "/USB DP Alt mode/USBSS1_RX_C_P")
			(pinfunction "SSRX_P")
			(pintype "output")
		)
		(pad "6" smd roundrect
			(at -2.9 0.598)
			(size 0.2 0.6)
			(layers "F.Cu" "F.Mask" "F.Paste")
			(roundrect_rratio 0.25)
			(net 2 "+3V3")
			(pinfunction "VCC")
			(pintype "passive")
		)
		(pad "7" smd roundrect
			(at -2.9 0.998)
			(size 0.2 0.6)
			(layers "F.Cu" "F.Mask" "F.Paste")
			(roundrect_rratio 0.25)
			(net 333 "/USB DP Alt mode/USBSS1_TX_C_N")
			(pinfunction "SSTX_N")
			(pintype "input")
		)
		(pad "8" smd roundrect
			(at -2.9 1.398)
			(size 0.2 0.6)
			(layers "F.Cu" "F.Mask" "F.Paste")
			(roundrect_rratio 0.25)
			(net 310 "/USB DP Alt mode/USBSS1_TX_C_P")
			(pinfunction "SSTX_P")
			(pintype "input")
		)
		(pad "9" smd roundrect
			(at -2.202 1.898 90)
			(size 0.2 0.6)
			(layers "F.Cu" "F.Mask" "F.Paste")
			(roundrect_rratio 0.25)
			(net 583 "/SoM_IO2/DP0.TX0+")
			(pinfunction "DP0_P")
			(pintype "input")
		)
		(pad "10" smd roundrect
			(at -1.801 1.898 90)
			(size 0.2 0.6)
			(layers "F.Cu" "F.Mask" "F.Paste")
			(roundrect_rratio 0.25)
			(net 663 "/SoM_IO2/DP0.TX0-")
			(pinfunction "DP0_N")
			(pintype "input")
		)
		(pad "11" smd roundrect
			(at -1.401 1.898 90)
			(size 0.2 0.6)
			(layers "F.Cu" "F.Mask" "F.Paste")
			(roundrect_rratio 0.25)
			(net 964 "/USB DP Alt mode/USBC1_SSEQ0")
			(pinfunction "SSEQ0/A0")
			(pintype "input")
		)
		(pad "12" smd roundrect
			(at -1 1.898 90)
			(size 0.2 0.6)
			(layers "F.Cu" "F.Mask" "F.Paste")
			(roundrect_rratio 0.25)
			(net 612 "/SoM_IO2/DP0.TX1+")
			(pinfunction "DP1_P")
			(pintype "input")
		)
		(pad "13" smd roundrect
			(at -0.6 1.898 90)
			(size 0.2 0.6)
			(layers "F.Cu" "F.Mask" "F.Paste")
			(roundrect_rratio 0.25)
			(net 792 "/SoM_IO2/DP0.TX1-")
			(pinfunction "DP1_N")
			(pintype "input")
		)
		(pad "14" smd roundrect
			(at -0.202 1.898 90)
			(size 0.2 0.6)
			(layers "F.Cu" "F.Mask" "F.Paste")
			(roundrect_rratio 0.25)
			(net 966 "/USB DP Alt mode/USBC1_DPEQ0")
			(pinfunction "DPEQ0/A1")
			(pintype "input")
		)
		(pad "15" smd roundrect
			(at 0.2 1.898 90)
			(size 0.2 0.6)
			(layers "F.Cu" "F.Mask" "F.Paste")
			(roundrect_rratio 0.25)
			(net 786 "/SoM_IO2/DP0.TX2+")
			(pinfunction "DP2_P")
			(pintype "input")
		)
		(pad "16" smd roundrect
			(at 0.598 1.898 90)
			(size 0.2 0.6)
			(layers "F.Cu" "F.Mask" "F.Paste")
			(roundrect_rratio 0.25)
			(net 666 "/SoM_IO2/DP0.TX2-")
			(pinfunction "DP2_N")
			(pintype "input")
		)
		(pad "17" smd roundrect
			(at 0.998 1.898 90)
			(size 0.2 0.6)
			(layers "F.Cu" "F.Mask" "F.Paste")
			(roundrect_rratio 0.25)
			(net 963 "/USB DP Alt mode/USBC1_I2C_EN")
			(pinfunction "I2C_EN")
			(pintype "input")
		)
		(pad "18" smd roundrect
			(at 1.398 1.898 90)
			(size 0.2 0.6)
			(layers "F.Cu" "F.Mask" "F.Paste")
			(roundrect_rratio 0.25)
			(net 557 "/SoM_IO2/DP0.TX3+")
			(pinfunction "DP3_P")
			(pintype "input")
		)
		(pad "19" smd roundrect
			(at 1.8 1.898 90)
			(size 0.2 0.6)
			(layers "F.Cu" "F.Mask" "F.Paste")
			(roundrect_rratio 0.25)
			(net 553 "/SoM_IO2/DP0.TX3-")
			(pinfunction "DP3_N")
			(pintype "input")
		)
		(pad "20" smd roundrect
			(at 2.2 1.898 90)
			(size 0.2 0.6)
			(layers "F.Cu" "F.Mask" "F.Paste")
			(roundrect_rratio 0.25)
			(net 2 "+3V3")
			(pinfunction "VCC")
			(pintype "passive")
		)
		(pad "21" smd roundrect
			(at 2.898 1.398 180)
			(size 0.2 0.6)
			(layers "F.Cu" "F.Mask" "F.Paste")
			(roundrect_rratio 0.25)
			(net 942 "/USB DP Alt mode/USBC1_FLIP")
			(pinfunction "FLIP/SCL")
			(pintype "input")
		)
		(pad "22" smd roundrect
			(at 2.898 0.998 180)
			(size 0.2 0.6)
			(layers "F.Cu" "F.Mask" "F.Paste")
			(roundrect_rratio 0.25)
			(net 943 "/USB DP Alt mode/USBC1_CTL0")
			(pinfunction "CTL0/SDA")
			(pintype "input")
		)
		(pad "23" smd roundrect
			(at 2.898 0.598 180)
			(size 0.2 0.6)
			(layers "F.Cu" "F.Mask" "F.Paste")
			(roundrect_rratio 0.25)
			(net 944 "/USB DP Alt mode/USBC1_CTL1")
			(pinfunction "CTL1/HPDIN")
			(pintype "input")
		)
		(pad "24" smd roundrect
			(at 2.898 0.2 180)
			(size 0.2 0.6)
			(layers "F.Cu" "F.Mask" "F.Paste")
			(roundrect_rratio 0.25)
			(net 635 "/SoM_IO2/DP0.AUX+")
			(pinfunction "AUX_P")
			(pintype "bidirectional")
		)
		(pad "25" smd roundrect
			(at 2.898 -0.202 180)
			(size 0.2 0.6)
			(layers "F.Cu" "F.Mask" "F.Paste")
			(roundrect_rratio 0.25)
			(net 607 "/SoM_IO2/DP0.AUX-")
			(pinfunction "AUX_N")
			(pintype "bidirectional")
		)
		(pad "26" smd roundrect
			(at 2.898 -0.6 180)
			(size 0.2 0.6)
			(layers "F.Cu" "F.Mask" "F.Paste")
			(roundrect_rratio 0.25)
			(net 815 "/USB DP Alt mode/USBC1_SBU_P")
			(pinfunction "SBU2")
			(pintype "bidirectional")
		)
		(pad "27" smd roundrect
			(at 2.898 -1 180)
			(size 0.2 0.6)
			(layers "F.Cu" "F.Mask" "F.Paste")
			(roundrect_rratio 0.25)
			(net 821 "/USB DP Alt mode/USBC1_SBU_N")
			(pinfunction "SBU1")
			(pintype "bidirectional")
		)
		(pad "28" smd roundrect
			(at 2.898 -1.401 180)
			(size 0.2 0.6)
			(layers "F.Cu" "F.Mask" "F.Paste")
			(roundrect_rratio 0.25)
			(net 2 "+3V3")
			(pinfunction "VCC")
			(pintype "passive")
		)
		(pad "29" smd roundrect
			(at 2.2 -1.901 270)
			(size 0.2 0.6)
			(layers "F.Cu" "F.Mask" "F.Paste")
			(roundrect_rratio 0.25)
			(net 1044 "Net-(U33-CAD_SNK{slash}RSVD1)")
			(pinfunction "CAD_SNK/RSVD1")
			(pintype "bidirectional")
		)
		(pad "30" smd roundrect
			(at 1.8 -1.901 270)
			(size 0.2 0.6)
			(layers "F.Cu" "F.Mask" "F.Paste")
			(roundrect_rratio 0.25)
			(net 822 "/USB DP Alt mode/USBC1_RX1_P")
			(pinfunction "RX1_P")
			(pintype "input")
		)
		(pad "31" smd roundrect
			(at 1.398 -1.901 270)
			(size 0.2 0.6)
			(layers "F.Cu" "F.Mask" "F.Paste")
			(roundrect_rratio 0.25)
			(net 819 "/USB DP Alt mode/USBC1_RX1_N")
			(pinfunction "RX1_N")
			(pintype "input")
		)
		(pad "32" smd roundrect
			(at 0.998 -1.901 270)
			(size 0.2 0.6)
			(layers "F.Cu" "F.Mask" "F.Paste")
			(roundrect_rratio 0.25)
			(net 957 "/USB DP Alt mode/HPDIN")
			(pinfunction "HPDIN/RSVD2")
			(pintype "bidirectional")
		)
		(pad "33" smd roundrect
			(at 0.598 -1.901 270)
			(size 0.2 0.6)
			(layers "F.Cu" "F.Mask" "F.Paste")
			(roundrect_rratio 0.25)
			(net 344 "/USB DP Alt mode/USBC1_TX1_P")
			(pinfunction "TX1_P")
			(pintype "output")
		)
		(pad "34" smd roundrect
			(at 0.2 -1.901 270)
			(size 0.2 0.6)
			(layers "F.Cu" "F.Mask" "F.Paste")
			(roundrect_rratio 0.25)
			(net 370 "/USB DP Alt mode/USBC1_TX1_N")
			(pinfunction "TX1_N")
			(pintype "output")
		)
		(pad "35" smd roundrect
			(at -0.202 -1.901 270)
			(size 0.2 0.6)
			(layers "F.Cu" "F.Mask" "F.Paste")
			(roundrect_rratio 0.25)
			(net 969 "/USB DP Alt mode/USBC1_EQ1")
			(pinfunction "EQ1")
			(pintype "input")
		)
		(pad "36" smd roundrect
			(at -0.6 -1.901 270)
			(size 0.2 0.6)
			(layers "F.Cu" "F.Mask" "F.Paste")
			(roundrect_rratio 0.25)
			(net 372 "/USB DP Alt mode/USBC1_TX2_N")
			(pinfunction "TX2_N")
			(pintype "output")
		)
		(pad "37" smd roundrect
			(at -1 -1.901 270)
			(size 0.2 0.6)
			(layers "F.Cu" "F.Mask" "F.Paste")
			(roundrect_rratio 0.25)
			(net 354 "/USB DP Alt mode/USBC1_TX2_P")
			(pinfunction "TX2_P")
			(pintype "output")
		)
		(pad "38" smd roundrect
			(at -1.401 -1.901 270)
			(size 0.2 0.6)
			(layers "F.Cu" "F.Mask" "F.Paste")
			(roundrect_rratio 0.25)
			(net 968 "/USB DP Alt mode/USBC1_EQ0")
			(pinfunction "EQ0")
			(pintype "input")
		)
		(pad "39" smd roundrect
			(at -1.801 -1.901 270)
			(size 0.2 0.6)
			(layers "F.Cu" "F.Mask" "F.Paste")
			(roundrect_rratio 0.25)
			(net 820 "/USB DP Alt mode/USBC1_RX2_N")
			(pinfunction "RX2_N")
			(pintype "input")
		)
		(pad "40" smd roundrect
			(at -2.202 -1.901 270)
			(size 0.2 0.6)
			(layers "F.Cu" "F.Mask" "F.Paste")
			(roundrect_rratio 0.25)
			(net 818 "/USB DP Alt mode/USBC1_RX2_P")
			(pinfunction "RX2_P")
			(pintype "input")
		)
		(pad "41" smd roundrect
			(at -1.5 -0.652 90)
			(size 1 0.8)
			(layers "F.Cu" "F.Mask" "F.Paste")
			(roundrect_rratio 0.05)
			(net 1 "GND")
			(pinfunction "GND")
			(pintype "power_in")
		)
		(pad "41" smd roundrect
			(at -1.5 0.748 90)
			(size 1 0.8)
			(layers "F.Cu" "F.Mask" "F.Paste")
			(roundrect_rratio 0.05)
			(net 1 "GND")
			(pinfunction "GND")
			(pintype "power_in")
		)
		(pad "41" smd roundrect
			(at 0 0 90)
			(size 4.7 2.7)
			(layers "F.Cu" "F.Mask")
			(roundrect_rratio 0.01851851852)
			(net 1 "GND")
			(pinfunction "GND")
			(pintype "power_in")
		)
		(pad "41" smd roundrect
			(at 0.05 -0.652 90)
			(size 1 0.8)
			(layers "F.Cu" "F.Mask" "F.Paste")
			(roundrect_rratio 0.05)
			(net 1 "GND")
			(pinfunction "GND")
			(pintype "power_in")
		)
		(pad "41" smd roundrect
			(at 0.05 0.748 90)
			(size 1 0.8)
			(layers "F.Cu" "F.Mask" "F.Paste")
			(roundrect_rratio 0.05)
			(net 1 "GND")
			(pinfunction "GND")
			(pintype "power_in")
		)
		(pad "41" smd roundrect
			(at 1.499 -0.652 90)
			(size 1 0.8)
			(layers "F.Cu" "F.Mask" "F.Paste")
			(roundrect_rratio 0.05)
			(net 1 "GND")
			(pinfunction "GND")
			(pintype "power_in")
		)
		(pad "41" smd roundrect
			(at 1.499 0.748 90)
			(size 1 0.8)
			(layers "F.Cu" "F.Mask" "F.Paste")
			(roundrect_rratio 0.05)
			(net 1 "GND")
			(pinfunction "GND")
			(pintype "power_in")
		)
	)
	(footprint "antmicro-footprints:C_0402_1005Metric"
		(layer "F.Cu")
		(at 139.5 59.5)
		(descr "Capacitor SMD 0402")
		(tags "capacitor SMD 0402")
		(property "Reference" "C75"
			(at -1.13 1.37 0)
			(layer "F.SilkS")
			(effects
				(font
					(size 0.7 0.7)
					(thickness 0.15)
				)
				(justify left bottom)
			)
		)
		(property "Value" "C_10u_0402"
			(at -1.022927 2.155213 0)
			(layer "F.Fab")
			(effects
				(font
					(size 0.7 0.7)
					(thickness 0.15)
				)
				(justify left bottom)
			)
		)
		(property "Datasheet" "https://www.yageo.com/en/Chart/Download/pdf/CC0402MRX5R5BB106"
			(at 0 0 0)
			(layer "F.Fab")
			(hide yes)
			(effects
				(font
					(size 1.27 1.27)
					(thickness 0.15)
				)
			)
		)
		(property "Description" "SMD Multilayer Ceramic Capacitor, 10 µF, 6.3 V, 0402 [1005 Metric], ± 20%, X5R, CC Series"
			(at 0 0 0)
			(layer "F.Fab")
			(hide yes)
			(effects
				(font
					(size 1.27 1.27)
					(thickness 0.15)
				)
			)
		)
		(property "MPN" "CC0402MRX5R5BB106"
			(at 0 0 0)
			(unlocked yes)
			(layer "F.Fab")
			(hide yes)
			(effects
				(font
					(size 1 1)
					(thickness 0.15)
				)
			)
		)
		(property "Manufacturer" "YAGEO"
			(at 0 0 0)
			(unlocked yes)
			(layer "F.Fab")
			(hide yes)
			(effects
				(font
					(size 1 1)
					(thickness 0.15)
				)
			)
		)
		(property "License" "Apache-2.0"
			(at 0 0 0)
			(unlocked yes)
			(layer "F.Fab")
			(hide yes)
			(effects
				(font
					(size 1 1)
					(thickness 0.15)
				)
			)
		)
		(property "Author" "Antmicro"
			(at 0 0 0)
			(unlocked yes)
			(layer "F.Fab")
			(hide yes)
			(effects
				(font
					(size 1 1)
					(thickness 0.15)
				)
			)
		)
		(property "Val" "10u"
			(at 0 0 0)
			(unlocked yes)
			(layer "F.Fab")
			(hide yes)
			(effects
				(font
					(size 1 1)
					(thickness 0.15)
				)
			)
		)
		(property "Voltage" ""
			(at 0 0 0)
			(unlocked yes)
			(layer "F.Fab")
			(hide yes)
			(effects
				(font
					(size 1 1)
					(thickness 0.15)
				)
			)
		)
		(property "Dielectric" ""
			(at 0 0 0)
			(unlocked yes)
			(layer "F.Fab")
			(hide yes)
			(effects
				(font
					(size 1 1)
					(thickness 0.15)
				)
			)
		)
		(sheetname "/Power/")
		(sheetfile "power.kicad_sch")
		(attr smd)
		(fp_poly
			(pts
				(xy -0.925 -0.47) (xy -0.925 0.47) (xy 0.925 0.47) (xy 0.925 -0.47)
			)
			(stroke
				(width 0.05)
				(type default)
			)
			(fill no)
			(layer "F.CrtYd")
		)
		(fp_line
			(start -0.494 -0.25)
			(end 0.504 -0.25)
			(stroke
				(width 0.15)
				(type solid)
			)
			(layer "F.Fab")
		)
		(fp_line
			(start -0.494 0.248)
			(end -0.494 -0.25)
			(stroke
				(width 0.15)
				(type solid)
			)
			(layer "F.Fab")
		)
		(fp_line
			(start 0.504 -0.25)
			(end 0.504 0.248)
			(stroke
				(width 0.15)
				(type solid)
			)
			(layer "F.Fab")
		)
		(fp_line
			(start 0.504 0.248)
			(end -0.494 0.248)
			(stroke
				(width 0.15)
				(type solid)
			)
			(layer "F.Fab")
		)
		(fp_text user "Author: Antmicro"
			(at -0.939 3.399 0)
			(layer "F.Fab")
			(effects
				(font
					(size 0.7 0.7)
					(thickness 0.15)
				)
				(justify left bottom)
			)
		)
		(fp_text user "${REFERENCE}"
			(at -0.939 4.599 0)
			(layer "F.Fab")
			(effects
				(font
					(size 0.7 0.7)
					(thickness 0.15)
				)
				(justify left bottom)
			)
		)
		(fp_text user "License: Apache-2.0"
			(at -0.939 5.799 0)
			(layer "F.Fab")
			(effects
				(font
					(size 0.7 0.7)
					(thickness 0.15)
				)
				(justify left bottom)
			)
		)
		(pad "1" smd roundrect
			(at -0.48 0)
			(size 0.59 0.64)
			(layers "F.Cu" "F.Mask" "F.Paste")
			(roundrect_rratio 0.25)
			(net 1 "GND")
			(pintype "passive")
		)
		(pad "2" smd roundrect
			(at 0.48 0)
			(size 0.59 0.64)
			(layers "F.Cu" "F.Mask" "F.Paste")
			(roundrect_rratio 0.25)
			(net 31 "/Power/3V3_LDO")
			(pintype "passive")
		)
	)
	(footprint "antmicro-footprints:R_0402_1005Metric"
		(layer "F.Cu")
		(at 188.476 124.92 -90)
		(descr "Resistor SMD 0402")
		(tags "resistor SMD 0402")
		(property "Reference" "R16"
			(at -1.02 1.376 90)
			(layer "F.SilkS")
			(effects
				(font
					(size 0.7 0.7)
					(thickness 0.15)
				)
				(justify right top)
			)
		)
		(property "Value" "R_12k_0402"
			(at -1.011843 1.772047 90)
			(layer "F.Fab")
			(effects
				(font
					(size 0.7 0.7)
					(thickness 0.15)
				)
				(justify right top)
			)
		)
		(property "Datasheet" "https://www.bourns.com/docs/product-datasheets/cr.pdf"
			(at 0 0 90)
			(layer "F.Fab")
			(hide yes)
			(effects
				(font
					(size 1.27 1.27)
					(thickness 0.15)
				)
			)
		)
		(property "Description" "SMD Chip Resistor, 12 kohm, ± 1%, 62.5 mW, 0402 [1005 Metric], Thick Film, General Purpose"
			(at 0 0 90)
			(layer "F.Fab")
			(hide yes)
			(effects
				(font
					(size 1.27 1.27)
					(thickness 0.15)
				)
			)
		)
		(property "MPN" "CR0402-FX-1202GLF"
			(at 0 0 270)
			(unlocked yes)
			(layer "F.Fab")
			(hide yes)
			(effects
				(font
					(size 1 1)
					(thickness 0.15)
				)
			)
		)
		(property "Manufacturer" "Bourns"
			(at 0 0 270)
			(unlocked yes)
			(layer "F.Fab")
			(hide yes)
			(effects
				(font
					(size 1 1)
					(thickness 0.15)
				)
			)
		)
		(property "License" "Apache-2.0"
			(at 0 0 270)
			(unlocked yes)
			(layer "F.Fab")
			(hide yes)
			(effects
				(font
					(size 1 1)
					(thickness 0.15)
				)
			)
		)
		(property "Author" "Antmicro"
			(at 0 0 270)
			(unlocked yes)
			(layer "F.Fab")
			(hide yes)
			(effects
				(font
					(size 1 1)
					(thickness 0.15)
				)
			)
		)
		(property "Val" "12k"
			(at 0 0 270)
			(unlocked yes)
			(layer "F.Fab")
			(hide yes)
			(effects
				(font
					(size 1 1)
					(thickness 0.15)
				)
			)
		)
		(property "Tolerance" "1%"
			(at 0 0 270)
			(unlocked yes)
			(layer "F.Fab")
			(hide yes)
			(effects
				(font
					(size 1 1)
					(thickness 0.15)
				)
			)
		)
		(property "Current" "1A"
			(at 0 0 270)
			(unlocked yes)
			(layer "F.Fab")
			(hide yes)
			(effects
				(font
					(size 1 1)
					(thickness 0.15)
				)
			)
		)
		(component_classes
			(class "DCDC_1V15")
		)
		(sheetname "/DCDC/")
		(sheetfile "dcdc.kicad_sch")
		(attr smd)
		(fp_rect
			(start -0.925 -0.47)
			(end 0.925 0.47)
			(stroke
				(width 0.05)
				(type default)
			)
			(fill no)
			(layer "F.CrtYd")
		)
		(fp_rect
			(start -0.5 -0.25)
			(end 0.5 0.25)
			(stroke
				(width 0.15)
				(type solid)
			)
			(fill no)
			(layer "F.Fab")
		)
		(fp_text user "${REFERENCE}"
			(at -0.95 3.168 90)
			(layer "F.Fab")
			(effects
				(font
					(size 0.7 0.7)
					(thickness 0.15)
				)
				(justify right top)
			)
		)
		(fp_text user "License: Apache-2.0"
			(at -0.95 5.169 90)
			(layer "F.Fab")
			(effects
				(font
					(size 0.7 0.7)
					(thickness 0.15)
				)
				(justify right top)
			)
		)
		(fp_text user "Author: Antmicro"
			(at -0.95 4.169 90)
			(layer "F.Fab")
			(effects
				(font
					(size 0.7 0.7)
					(thickness 0.15)
				)
				(justify right top)
			)
		)
		(pad "1" smd roundrect
			(at -0.48 0 270)
			(size 0.59 0.64)
			(layers "F.Cu" "F.Mask" "F.Paste")
			(roundrect_rratio 0.25)
			(net 1 "GND")
			(pintype "passive")
		)
		(pad "2" smd roundrect
			(at 0.48 0 270)
			(size 0.59 0.64)
			(layers "F.Cu" "F.Mask" "F.Paste")
			(roundrect_rratio 0.25)
			(net 1232 "/DCDC/1V15_FB")
			(pintype "passive")
		)
	)
	(footprint "antmicro-footprints:C_0402_1005Metric"
		(layer "F.Cu")
		(at 184.05 112.05 -90)
		(descr "Capacitor SMD 0402")
		(tags "capacitor SMD 0402")
		(property "Reference" "C55"
			(at -1.45 -0.55 90)
			(layer "F.SilkS")
			(effects
				(font
					(size 0.7 0.7)
					(thickness 0.15)
				)
				(justify right top)
			)
		)
		(property "Value" "C_4u7_25V_0402"
			(at -1.022927 2.155213 90)
			(layer "F.Fab")
			(effects
				(font
					(size 0.7 0.7)
					(thickness 0.15)
				)
				(justify right top)
			)
		)
		(property "Datasheet" "https://www.murata.com/products/productdetail?partno=GRM155C61E475ME15%23"
			(at 0 0 90)
			(layer "F.Fab")
			(hide yes)
			(effects
				(font
					(size 1.27 1.27)
					(thickness 0.15)
				)
			)
		)
		(property "Description" "SMD Multilayer Ceramic Capacitor"
			(at 0 0 90)
			(layer "F.Fab")
			(hide yes)
			(effects
				(font
					(size 1.27 1.27)
					(thickness 0.15)
				)
			)
		)
		(property "MPN" "GRM155C61E475ME15J"
			(at 0 0 270)
			(unlocked yes)
			(layer "F.Fab")
			(hide yes)
			(effects
				(font
					(size 1 1)
					(thickness 0.15)
				)
			)
		)
		(property "Manufacturer" "Murata"
			(at 0 0 270)
			(unlocked yes)
			(layer "F.Fab")
			(hide yes)
			(effects
				(font
					(size 1 1)
					(thickness 0.15)
				)
			)
		)
		(property "License" "Apache-2.0"
			(at 0 0 270)
			(unlocked yes)
			(layer "F.Fab")
			(hide yes)
			(effects
				(font
					(size 1 1)
					(thickness 0.15)
				)
			)
		)
		(property "Author" "Antmicro"
			(at 0 0 270)
			(unlocked yes)
			(layer "F.Fab")
			(hide yes)
			(effects
				(font
					(size 1 1)
					(thickness 0.15)
				)
			)
		)
		(property "Val" "4u7"
			(at 0 0 270)
			(unlocked yes)
			(layer "F.Fab")
			(hide yes)
			(effects
				(font
					(size 1 1)
					(thickness 0.15)
				)
			)
		)
		(property "Voltage" "25V"
			(at 0 0 270)
			(unlocked yes)
			(layer "F.Fab")
			(hide yes)
			(effects
				(font
					(size 1 1)
					(thickness 0.15)
				)
			)
		)
		(property "Dielectric" "X5S"
			(at 0 0 270)
			(unlocked yes)
			(layer "F.Fab")
			(hide yes)
			(effects
				(font
					(size 1 1)
					(thickness 0.15)
				)
			)
		)
		(sheetname "/DCDC/")
		(sheetfile "dcdc.kicad_sch")
		(attr smd)
		(fp_rect
			(start -0.925 -0.47)
			(end 0.925 0.47)
			(stroke
				(width 0.05)
				(type default)
			)
			(fill no)
			(layer "F.CrtYd")
		)
		(fp_line
			(start -0.494 0.248)
			(end -0.494 -0.25)
			(stroke
				(width 0.15)
				(type solid)
			)
			(layer "F.Fab")
		)
		(fp_line
			(start 0.504 0.248)
			(end -0.494 0.248)
			(stroke
				(width 0.15)
				(type solid)
			)
			(layer "F.Fab")
		)
		(fp_line
			(start -0.494 -0.25)
			(end 0.504 -0.25)
			(stroke
				(width 0.15)
				(type solid)
			)
			(layer "F.Fab")
		)
		(fp_line
			(start 0.504 -0.25)
			(end 0.504 0.248)
			(stroke
				(width 0.15)
				(type solid)
			)
			(layer "F.Fab")
		)
		(fp_text user "Author: Antmicro"
			(at -0.939 3.399 90)
			(layer "F.Fab")
			(effects
				(font
					(size 0.7 0.7)
					(thickness 0.15)
				)
				(justify right top)
			)
		)
		(fp_text user "${REFERENCE}"
			(at -0.939 4.599 90)
			(layer "F.Fab")
			(effects
				(font
					(size 0.7 0.7)
					(thickness 0.15)
				)
				(justify right top)
			)
		)
		(fp_text user "License: Apache-2.0"
			(at -0.939 5.799 90)
			(layer "F.Fab")
			(effects
				(font
					(size 0.7 0.7)
					(thickness 0.15)
				)
				(justify right top)
			)
		)
		(pad "1" smd roundrect
			(at -0.48 0 270)
			(size 0.59 0.64)
			(layers "F.Cu" "F.Mask" "F.Paste")
			(roundrect_rratio 0.25)
			(net 1 "GND")
			(pintype "passive")
		)
		(pad "2" smd roundrect
			(at 0.48 0 270)
			(size 0.59 0.64)
			(layers "F.Cu" "F.Mask" "F.Paste")
			(roundrect_rratio 0.25)
			(net 23 "/DCDC/5V_VDRV")
			(pintype "passive")
		)
	)
	(footprint "antmicro-footprints:C_0402_1005Metric"
		(layer "F.Cu")
		(at 205.6 83.6)
		(descr "Capacitor SMD 0402")
		(tags "capacitor SMD 0402")
		(property "Reference" "C138"
			(at 3.6 -0.4 180)
			(layer "F.SilkS")
			(effects
				(font
					(size 0.7 0.7)
					(thickness 0.15)
				)
				(justify right top)
			)
		)
		(property "Value" "C_4u7_25V_0402"
			(at -1.022927 2.155213 180)
			(layer "F.Fab")
			(effects
				(font
					(size 0.7 0.7)
					(thickness 0.15)
				)
				(justify right top)
			)
		)
		(property "Datasheet" "https://www.murata.com/products/productdetail?partno=GRM155C61E475ME15%23"
			(at 0 0 180)
			(layer "F.Fab")
			(hide yes)
			(effects
				(font
					(size 1.27 1.27)
					(thickness 0.15)
				)
			)
		)
		(property "Description" "SMD Multilayer Ceramic Capacitor"
			(at 0 0 180)
			(layer "F.Fab")
			(hide yes)
			(effects
				(font
					(size 1.27 1.27)
					(thickness 0.15)
				)
			)
		)
		(property "Manufacturer" "Murata"
			(at 0 0 0)
			(unlocked yes)
			(layer "F.Fab")
			(hide yes)
			(effects
				(font
					(size 1 1)
					(thickness 0.15)
				)
			)
		)
		(property "MPN" "GRM155C61E475ME15J"
			(at 0 0 0)
			(unlocked yes)
			(layer "F.Fab")
			(hide yes)
			(effects
				(font
					(size 1 1)
					(thickness 0.15)
				)
			)
		)
		(property "Val" "4u7"
			(at 0 0 0)
			(unlocked yes)
			(layer "F.Fab")
			(hide yes)
			(effects
				(font
					(size 1 1)
					(thickness 0.15)
				)
			)
		)
		(property "License" "Apache-2.0"
			(at 0 0 0)
			(unlocked yes)
			(layer "F.Fab")
			(hide yes)
			(effects
				(font
					(size 1 1)
					(thickness 0.15)
				)
			)
		)
		(property "Author" "Antmicro"
			(at 0 0 0)
			(unlocked yes)
			(layer "F.Fab")
			(hide yes)
			(effects
				(font
					(size 1 1)
					(thickness 0.15)
				)
			)
		)
		(property "Voltage" "25V"
			(at 0 0 0)
			(unlocked yes)
			(layer "F.Fab")
			(hide yes)
			(effects
				(font
					(size 1 1)
					(thickness 0.15)
				)
			)
		)
		(property "Dielectric" "X5S"
			(at 0 0 0)
			(unlocked yes)
			(layer "F.Fab")
			(hide yes)
			(effects
				(font
					(size 1 1)
					(thickness 0.15)
				)
			)
		)
		(sheetname "/USB DP Alt mode/")
		(sheetfile "usb_dp.kicad_sch")
		(attr smd)
		(fp_poly
			(pts
				(xy -0.925 -0.47) (xy -0.925 0.47) (xy 0.925 0.47) (xy 0.925 -0.47)
			)
			(stroke
				(width 0.05)
				(type default)
			)
			(fill no)
			(layer "F.CrtYd")
		)
		(fp_line
			(start -0.494 -0.25)
			(end 0.504 -0.25)
			(stroke
				(width 0.15)
				(type solid)
			)
			(layer "F.Fab")
		)
		(fp_line
			(start -0.494 0.248)
			(end -0.494 -0.25)
			(stroke
				(width 0.15)
				(type solid)
			)
			(layer "F.Fab")
		)
		(fp_line
			(start 0.504 -0.25)
			(end 0.504 0.248)
			(stroke
				(width 0.15)
				(type solid)
			)
			(layer "F.Fab")
		)
		(fp_line
			(start 0.504 0.248)
			(end -0.494 0.248)
			(stroke
				(width 0.15)
				(type solid)
			)
			(layer "F.Fab")
		)
		(fp_text user "License: Apache-2.0"
			(at -0.939 5.799 180)
			(layer "F.Fab")
			(effects
				(font
					(size 0.7 0.7)
					(thickness 0.15)
				)
				(justify right top)
			)
		)
		(fp_text user "Author: Antmicro"
			(at -0.939 3.399 180)
			(layer "F.Fab")
			(effects
				(font
					(size 0.7 0.7)
					(thickness 0.15)
				)
				(justify right top)
			)
		)
		(fp_text user "${REFERENCE}"
			(at -0.939 4.599 180)
			(layer "F.Fab")
			(effects
				(font
					(size 0.7 0.7)
					(thickness 0.15)
				)
				(justify right top)
			)
		)
		(pad "1" smd roundrect
			(at -0.48 0)
			(size 0.59 0.64)
			(layers "F.Cu" "F.Mask" "F.Paste")
			(roundrect_rratio 0.25)
			(net 522 "/Power/USBPD1_HV")
			(pintype "passive")
		)
		(pad "2" smd roundrect
			(at 0.48 0)
			(size 0.59 0.64)
			(layers "F.Cu" "F.Mask" "F.Paste")
			(roundrect_rratio 0.25)
			(net 1 "GND")
			(pintype "passive")
		)
	)
	(footprint "antmicro-footprints:USON-10_2.5x1mm_P0.5mm"
		(layer "F.Cu")
		(at 220.853 125.425 180)
		(descr "USON-10 2.5x1mm_ Pitch 0.5mm")
		(tags "USON-10 2.5x1mm Pitch 0.5mm")
		(property "Reference" "U17"
			(at -1.137 -2.405 90)
			(layer "F.SilkS")
			(effects
				(font
					(size 0.7 0.7)
					(thickness 0.15)
				)
				(justify right top)
			)
		)
		(property "Value" "TPD4E05U06QDQARQ1"
			(at 0.018 2.499 0)
			(layer "F.Fab")
			(effects
				(font
					(size 0.7 0.7)
					(thickness 0.15)
				)
				(justify right top)
			)
		)
		(property "Datasheet" "https://www.ti.com/lit/ds/symlink/tpd4e05u06-q1.pdf?HQS=dis-mous-null-mousermode-dsf-pf-null-wwe&ts=1663591265741&ref_url=https%253A%252F%252Fwww.mouser.com%252F"
			(at 0 0 0)
			(layer "F.Fab")
			(hide yes)
			(effects
				(font
					(size 1.27 1.27)
					(thickness 0.15)
				)
			)
		)
		(property "Description" "TVS diode array, 12 kV, USON-10, 5.5 V, 0.5 pF"
			(at 0 0 0)
			(layer "F.Fab")
			(hide yes)
			(effects
				(font
					(size 1.27 1.27)
					(thickness 0.15)
				)
			)
		)
		(property "Manufacturer" "Texas Instruments"
			(at 0 0 180)
			(unlocked yes)
			(layer "F.Fab")
			(hide yes)
			(effects
				(font
					(size 1 1)
					(thickness 0.15)
				)
			)
		)
		(property "MPN" "TPD4E05U06QDQARQ1"
			(at 0 0 180)
			(unlocked yes)
			(layer "F.Fab")
			(hide yes)
			(effects
				(font
					(size 1 1)
					(thickness 0.15)
				)
			)
		)
		(property "Author" "Antmicro"
			(at 0 0 180)
			(unlocked yes)
			(layer "F.Fab")
			(hide yes)
			(effects
				(font
					(size 1 1)
					(thickness 0.15)
				)
			)
		)
		(property "License" "Apache-2.0"
			(at 0 0 180)
			(unlocked yes)
			(layer "F.Fab")
			(hide yes)
			(effects
				(font
					(size 1 1)
					(thickness 0.15)
				)
			)
		)
		(sheetname "/USB Hub/")
		(sheetfile "usb_hub.kicad_sch")
		(attr smd)
		(fp_line
			(start 0.498 1.398)
			(end -0.5 1.398)
			(stroke
				(width 0.15)
				(type solid)
			)
			(layer "F.SilkS")
		)
		(fp_line
			(start 0.498 -1.401)
			(end -0.5 -1.401)
			(stroke
				(width 0.15)
				(type solid)
			)
			(layer "F.SilkS")
		)
		(fp_circle
			(center -0.68 -1.27)
			(end -0.63 -1.27)
			(stroke
				(width 0.15)
				(type solid)
			)
			(fill yes)
			(layer "F.SilkS")
		)
		(fp_rect
			(start -0.8 -1.5)
			(end 0.8 1.499)
			(stroke
				(width 0.05)
				(type solid)
			)
			(fill no)
			(layer "F.CrtYd")
		)
		(fp_line
			(start 0.498 -1.25)
			(end 0.498 1.249)
			(stroke
				(width 0.15)
				(type solid)
			)
			(layer "F.Fab")
		)
		(fp_line
			(start 0.498 -1.25)
			(end -0.25 -1.25)
			(stroke
				(width 0.15)
				(type solid)
			)
			(layer "F.Fab")
		)
		(fp_line
			(start -0.25 -1.25)
			(end -0.5 -1)
			(stroke
				(width 0.15)
				(type solid)
			)
			(layer "F.Fab")
		)
		(fp_line
			(start -0.5 1.249)
			(end 0.498 1.249)
			(stroke
				(width 0.15)
				(type solid)
			)
			(layer "F.Fab")
		)
		(fp_line
			(start -0.5 -1)
			(end -0.5 1.249)
			(stroke
				(width 0.15)
				(type solid)
			)
			(layer "F.Fab")
		)
		(fp_text user "Author: Antmicro"
			(at -0.802 5.7 0)
			(layer "F.Fab")
			(effects
				(font
					(size 0.7 0.7)
					(thickness 0.15)
				)
				(justify right top)
			)
		)
		(fp_text user "License: Apache-2.0"
			(at -0.802 6.9 0)
			(layer "F.Fab")
			(effects
				(font
					(size 0.7 0.7)
					(thickness 0.15)
				)
				(justify right top)
			)
		)
		(fp_text user "${REFERENCE}"
			(at -0.802 4.498 0)
			(layer "F.Fab")
			(effects
				(font
					(size 0.7 0.7)
					(thickness 0.15)
				)
				(justify right top)
			)
		)
		(pad "1" smd roundrect
			(at -0.387 -1 90)
			(size 0.25 0.55)
			(layers "F.Cu" "F.Mask" "F.Paste")
			(roundrect_rratio 0.25)
			(net 80 "/USB Hub/USBC4_CONN_TX2_P")
			(pintype "passive")
		)
		(pad "2" smd roundrect
			(at -0.387 -0.5 90)
			(size 0.25 0.55)
			(layers "F.Cu" "F.Mask" "F.Paste")
			(roundrect_rratio 0.25)
			(net 110 "/USB Hub/USBC4_CONN_TX2_N")
			(pintype "passive")
		)
		(pad "3" smd roundrect
			(at -0.387 0 90)
			(size 0.4 0.55)
			(layers "F.Cu" "F.Mask" "F.Paste")
			(roundrect_rratio 0.25)
			(net 1 "GND")
			(pintype "power_in")
		)
		(pad "4" smd roundrect
			(at -0.387 0.498 90)
			(size 0.25 0.55)
			(layers "F.Cu" "F.Mask" "F.Paste")
			(roundrect_rratio 0.25)
			(net 498 "/USB Hub/USBC4_RX_{2}+")
			(pintype "passive")
		)
		(pad "5" smd roundrect
			(at -0.387 0.998 90)
			(size 0.25 0.55)
			(layers "F.Cu" "F.Mask" "F.Paste")
			(roundrect_rratio 0.25)
			(net 500 "/USB Hub/USBC4_RX_{2}-")
			(pintype "passive")
		)
		(pad "6" smd roundrect
			(at 0.385 0.998 90)
			(size 0.25 0.55)
			(layers "F.Cu" "F.Mask" "F.Paste")
			(roundrect_rratio 0.25)
			(net 500 "/USB Hub/USBC4_RX_{2}-")
			(pintype "passive")
		)
		(pad "7" smd roundrect
			(at 0.385 0.498 90)
			(size 0.25 0.55)
			(layers "F.Cu" "F.Mask" "F.Paste")
			(roundrect_rratio 0.25)
			(net 498 "/USB Hub/USBC4_RX_{2}+")
			(pintype "passive")
		)
		(pad "8" smd roundrect
			(at 0.385 0 90)
			(size 0.4 0.55)
			(layers "F.Cu" "F.Mask" "F.Paste")
			(roundrect_rratio 0.25)
			(net 1 "GND")
			(pintype "passive")
		)
		(pad "9" smd roundrect
			(at 0.385 -0.5 90)
			(size 0.25 0.55)
			(layers "F.Cu" "F.Mask" "F.Paste")
			(roundrect_rratio 0.25)
			(net 110 "/USB Hub/USBC4_CONN_TX2_N")
			(pintype "passive")
		)
		(pad "10" smd roundrect
			(at 0.385 -1 90)
			(size 0.25 0.55)
			(layers "F.Cu" "F.Mask" "F.Paste")
			(roundrect_rratio 0.25)
			(net 80 "/USB Hub/USBC4_CONN_TX2_P")
			(pintype "passive")
		)
	)
	(footprint "antmicro-footprints:C_0402_1005Metric"
		(layer "F.Cu")
		(at 204.75 89.970856 180)
		(descr "Capacitor SMD 0402")
		(tags "capacitor SMD 0402")
		(property "Reference" "C318"
			(at 5.25 -0.429144 180)
			(layer "F.SilkS")
			(effects
				(font
					(size 0.7 0.7)
					(thickness 0.15)
				)
				(justify left bottom)
			)
		)
		(property "Value" "C_100n_0402"
			(at -1.022927 2.155213 180)
			(layer "F.Fab")
			(effects
				(font
					(size 0.7 0.7)
					(thickness 0.15)
				)
				(justify left bottom)
			)
		)
		(property "Datasheet" "https://www.murata.com/products/productdetail?partno=GRM155R61H104KE14%23"
			(at 0 0 180)
			(layer "F.Fab")
			(hide yes)
			(effects
				(font
					(size 1.27 1.27)
					(thickness 0.15)
				)
			)
		)
		(property "Description" "SMD Multilayer Ceramic Capacitor, 0.1 µF, 50 V, 0402 [1005 Metric], ± 10%, X5R, GRM Series"
			(at 0 0 180)
			(layer "F.Fab")
			(hide yes)
			(effects
				(font
					(size 1.27 1.27)
					(thickness 0.15)
				)
			)
		)
		(property "Manufacturer" "Murata"
			(at 0 0 180)
			(unlocked yes)
			(layer "F.Fab")
			(hide yes)
			(effects
				(font
					(size 1 1)
					(thickness 0.15)
				)
			)
		)
		(property "MPN" "GRM155R61H104KE14D"
			(at 0 0 180)
			(unlocked yes)
			(layer "F.Fab")
			(hide yes)
			(effects
				(font
					(size 1 1)
					(thickness 0.15)
				)
			)
		)
		(property "Val" "100n"
			(at 0 0 180)
			(unlocked yes)
			(layer "F.Fab")
			(hide yes)
			(effects
				(font
					(size 1 1)
					(thickness 0.15)
				)
			)
		)
		(property "License" "Apache-2.0"
			(at 0 0 180)
			(unlocked yes)
			(layer "F.Fab")
			(hide yes)
			(effects
				(font
					(size 1 1)
					(thickness 0.15)
				)
			)
		)
		(property "Author" "Antmicro"
			(at 0 0 180)
			(unlocked yes)
			(layer "F.Fab")
			(hide yes)
			(effects
				(font
					(size 1 1)
					(thickness 0.15)
				)
			)
		)
		(property "Voltage" "50V"
			(at 0 0 180)
			(unlocked yes)
			(layer "F.Fab")
			(hide yes)
			(effects
				(font
					(size 1 1)
					(thickness 0.15)
				)
			)
		)
		(property "Dielectric" "X5R"
			(at 0 0 180)
			(unlocked yes)
			(layer "F.Fab")
			(hide yes)
			(effects
				(font
					(size 1 1)
					(thickness 0.15)
				)
			)
		)
		(sheetname "/SoM_IO2/")
		(sheetfile "som_io2.kicad_sch")
		(attr smd)
		(fp_rect
			(start -0.925 -0.47)
			(end 0.925 0.47)
			(stroke
				(width 0.05)
				(type default)
			)
			(fill no)
			(layer "F.CrtYd")
		)
		(fp_line
			(start 0.504 0.248)
			(end -0.494 0.248)
			(stroke
				(width 0.15)
				(type solid)
			)
			(layer "F.Fab")
		)
		(fp_line
			(start 0.504 -0.25)
			(end 0.504 0.248)
			(stroke
				(width 0.15)
				(type solid)
			)
			(layer "F.Fab")
		)
		(fp_line
			(start -0.494 0.248)
			(end -0.494 -0.25)
			(stroke
				(width 0.15)
				(type solid)
			)
			(layer "F.Fab")
		)
		(fp_line
			(start -0.494 -0.25)
			(end 0.504 -0.25)
			(stroke
				(width 0.15)
				(type solid)
			)
			(layer "F.Fab")
		)
		(fp_text user "Author: Antmicro"
			(at -0.939 3.399 180)
			(layer "F.Fab")
			(effects
				(font
					(size 0.7 0.7)
					(thickness 0.15)
				)
				(justify left bottom)
			)
		)
		(fp_text user "License: Apache-2.0"
			(at -0.939 5.799 180)
			(layer "F.Fab")
			(effects
				(font
					(size 0.7 0.7)
					(thickness 0.15)
				)
				(justify left bottom)
			)
		)
		(fp_text user "${REFERENCE}"
			(at -0.939 4.599 180)
			(layer "F.Fab")
			(effects
				(font
					(size 0.7 0.7)
					(thickness 0.15)
				)
				(justify left bottom)
			)
		)
		(pad "1" smd roundrect
			(at -0.48 0 180)
			(size 0.59 0.64)
			(layers "F.Cu" "F.Mask" "F.Paste")
			(roundrect_rratio 0.25)
			(net 786 "/SoM_IO2/DP0.TX2+")
			(pintype "passive")
		)
		(pad "2" smd roundrect
			(at 0.48 0 180)
			(size 0.59 0.64)
			(layers "F.Cu" "F.Mask" "F.Paste")
			(roundrect_rratio 0.25)
			(net 615 "/SoM_IO2/DP0.TX2_C+")
			(pintype "passive")
		)
	)
	(footprint "antmicro-footprints:C_0402_1005Metric"
		(layer "F.Cu")
		(at 82.1 75.8 -90)
		(descr "Capacitor SMD 0402")
		(tags "capacitor SMD 0402")
		(property "Reference" "C343"
			(at 0.9 0.4 90)
			(layer "F.SilkS")
			(effects
				(font
					(size 0.7 0.7)
					(thickness 0.15)
				)
				(justify right top)
			)
		)
		(property "Value" "C_100n_0402"
			(at -1.022927 2.155213 90)
			(layer "F.Fab")
			(effects
				(font
					(size 0.7 0.7)
					(thickness 0.15)
				)
				(justify right top)
			)
		)
		(property "Datasheet" "https://www.murata.com/products/productdetail?partno=GRM155R61H104KE14%23"
			(at 0 0 90)
			(layer "F.Fab")
			(hide yes)
			(effects
				(font
					(size 1.27 1.27)
					(thickness 0.15)
				)
			)
		)
		(property "Description" "SMD Multilayer Ceramic Capacitor, 0.1 µF, 50 V, 0402 [1005 Metric], ± 10%, X5R, GRM Series"
			(at 0 0 90)
			(layer "F.Fab")
			(hide yes)
			(effects
				(font
					(size 1.27 1.27)
					(thickness 0.15)
				)
			)
		)
		(property "Manufacturer" "Murata"
			(at 0 0 270)
			(unlocked yes)
			(layer "F.Fab")
			(hide yes)
			(effects
				(font
					(size 1 1)
					(thickness 0.15)
				)
			)
		)
		(property "MPN" "GRM155R61H104KE14D"
			(at 0 0 270)
			(unlocked yes)
			(layer "F.Fab")
			(hide yes)
			(effects
				(font
					(size 1 1)
					(thickness 0.15)
				)
			)
		)
		(property "Val" "100n"
			(at 0 0 270)
			(unlocked yes)
			(layer "F.Fab")
			(hide yes)
			(effects
				(font
					(size 1 1)
					(thickness 0.15)
				)
			)
		)
		(property "License" "Apache-2.0"
			(at 0 0 270)
			(unlocked yes)
			(layer "F.Fab")
			(hide yes)
			(effects
				(font
					(size 1 1)
					(thickness 0.15)
				)
			)
		)
		(property "Author" "Antmicro"
			(at 0 0 270)
			(unlocked yes)
			(layer "F.Fab")
			(hide yes)
			(effects
				(font
					(size 1 1)
					(thickness 0.15)
				)
			)
		)
		(property "Voltage" "50V"
			(at 0 0 270)
			(unlocked yes)
			(layer "F.Fab")
			(hide yes)
			(effects
				(font
					(size 1 1)
					(thickness 0.15)
				)
			)
		)
		(property "Dielectric" "X5R"
			(at 0 0 270)
			(unlocked yes)
			(layer "F.Fab")
			(hide yes)
			(effects
				(font
					(size 1 1)
					(thickness 0.15)
				)
			)
		)
		(sheetname "/SoM_IO2/")
		(sheetfile "som_io2.kicad_sch")
		(attr smd)
		(fp_poly
			(pts
				(xy -0.925 -0.47) (xy 0.925 -0.47) (xy 0.925 0.47) (xy -0.925 0.47)
			)
			(stroke
				(width 0.05)
				(type default)
			)
			(fill no)
			(layer "F.CrtYd")
		)
		(fp_line
			(start -0.494 0.248)
			(end -0.494 -0.25)
			(stroke
				(width 0.15)
				(type solid)
			)
			(layer "F.Fab")
		)
		(fp_line
			(start 0.504 0.248)
			(end -0.494 0.248)
			(stroke
				(width 0.15)
				(type solid)
			)
			(layer "F.Fab")
		)
		(fp_line
			(start -0.494 -0.25)
			(end 0.504 -0.25)
			(stroke
				(width 0.15)
				(type solid)
			)
			(layer "F.Fab")
		)
		(fp_line
			(start 0.504 -0.25)
			(end 0.504 0.248)
			(stroke
				(width 0.15)
				(type solid)
			)
			(layer "F.Fab")
		)
		(fp_text user "Author: Antmicro"
			(at -0.939 3.399 90)
			(layer "F.Fab")
			(effects
				(font
					(size 0.7 0.7)
					(thickness 0.15)
				)
				(justify right top)
			)
		)
		(fp_text user "${REFERENCE}"
			(at -0.939 4.599 90)
			(layer "F.Fab")
			(effects
				(font
					(size 0.7 0.7)
					(thickness 0.15)
				)
				(justify right top)
			)
		)
		(fp_text user "License: Apache-2.0"
			(at -0.939 5.799 90)
			(layer "F.Fab")
			(effects
				(font
					(size 0.7 0.7)
					(thickness 0.15)
				)
				(justify right top)
			)
		)
		(pad "1" smd roundrect
			(at -0.48 0 270)
			(size 0.59 0.64)
			(layers "F.Cu" "F.Mask" "F.Paste")
			(roundrect_rratio 0.25)
			(net 1263 "/SoM_IO2/DP2.AUX_C-")
			(pintype "passive")
		)
		(pad "2" smd roundrect
			(at 0.48 0 270)
			(size 0.59 0.64)
			(layers "F.Cu" "F.Mask" "F.Paste")
			(roundrect_rratio 0.25)
			(net 656 "/Expansion connector/DP2.AUX-")
			(pintype "passive")
		)
	)
	(footprint "antmicro-footprints:C_0603_1608Metric_EIA"
		(layer "F.Cu")
		(at 193.9 122.7)
		(descr "Capacitor SMD 0603, IPC-7351 Density Level A")
		(tags "Capacitor 0603")
		(property "Reference" "C311"
			(at -0.5 -0.65 0)
			(layer "F.SilkS")
			(effects
				(font
					(size 0.7 0.7)
					(thickness 0.15)
				)
				(justify left bottom)
			)
		)
		(property "Value" "C_22u_16V_0603"
			(at -1.42757 1.770288 0)
			(layer "F.Fab")
			(effects
				(font
					(size 0.7 0.7)
					(thickness 0.15)
				)
				(justify left bottom)
			)
		)
		(property "Datasheet" "https://product.samsungsem.com/mlcc/CL10A226MO7JZN.do"
			(at 0 0 0)
			(layer "F.Fab")
			(hide yes)
			(effects
				(font
					(size 1.27 1.27)
					(thickness 0.15)
				)
			)
		)
		(property "Description" "SMD Multilayer Ceramic Capacitor"
			(at 0 0 0)
			(layer "F.Fab")
			(hide yes)
			(effects
				(font
					(size 1.27 1.27)
					(thickness 0.15)
				)
			)
		)
		(property "Manufacturer" "Samsung Electro-Mechanics"
			(at 0 0 0)
			(unlocked yes)
			(layer "F.Fab")
			(hide yes)
			(effects
				(font
					(size 1 1)
					(thickness 0.15)
				)
			)
		)
		(property "MPN" "CL10A226MO7JZNC"
			(at 0 0 0)
			(unlocked yes)
			(layer "F.Fab")
			(hide yes)
			(effects
				(font
					(size 1 1)
					(thickness 0.15)
				)
			)
		)
		(property "Val" "22u"
			(at 0 0 0)
			(unlocked yes)
			(layer "F.Fab")
			(hide yes)
			(effects
				(font
					(size 1 1)
					(thickness 0.15)
				)
			)
		)
		(property "License" "Apache-2.0"
			(at 0 0 0)
			(unlocked yes)
			(layer "F.Fab")
			(hide yes)
			(effects
				(font
					(size 1 1)
					(thickness 0.15)
				)
			)
		)
		(property "Author" "Antmicro"
			(at 0 0 0)
			(unlocked yes)
			(layer "F.Fab")
			(hide yes)
			(effects
				(font
					(size 1 1)
					(thickness 0.15)
				)
			)
		)
		(property "Voltage" "16V"
			(at 0 0 0)
			(unlocked yes)
			(layer "F.Fab")
			(hide yes)
			(effects
				(font
					(size 1 1)
					(thickness 0.15)
				)
			)
		)
		(property "Dielectric" ""
			(at 0 0 0)
			(unlocked yes)
			(layer "F.Fab")
			(hide yes)
			(effects
				(font
					(size 1 1)
					(thickness 0.15)
				)
			)
		)
		(sheetname "/USB Hub/")
		(sheetfile "usb_hub.kicad_sch")
		(attr smd)
		(fp_line
			(start -0.15 -0.55)
			(end 0.15 -0.55)
			(stroke
				(width 0.15)
				(type solid)
			)
			(layer "F.SilkS")
		)
		(fp_line
			(start -0.15 0.55)
			(end 0.15 0.55)
			(stroke
				(width 0.15)
				(type solid)
			)
			(layer "F.SilkS")
		)
		(fp_rect
			(start -1.25 -0.65)
			(end 1.25 0.65)
			(stroke
				(width 0.05)
				(type solid)
			)
			(fill no)
			(layer "F.CrtYd")
		)
		(fp_rect
			(start -0.8 -0.45)
			(end 0.8 0.45)
			(stroke
				(width 0.15)
				(type solid)
			)
			(fill no)
			(layer "F.Fab")
		)
		(fp_text user "License: Apache-2.0"
			(at -1.682 5.895 0)
			(layer "F.Fab")
			(effects
				(font
					(size 0.7 0.7)
					(thickness 0.15)
				)
				(justify left bottom)
			)
		)
		(fp_text user "Author: Antmicro"
			(at -1.682 4.894 0)
			(layer "F.Fab")
			(effects
				(font
					(size 0.7 0.7)
					(thickness 0.15)
				)
				(justify left bottom)
			)
		)
		(fp_text user "${REFERENCE}"
			(at -1.682 3.895 0)
			(layer "F.Fab")
			(effects
				(font
					(size 0.7 0.7)
					(thickness 0.15)
				)
				(justify left bottom)
			)
		)
		(pad "1" smd roundrect
			(at -0.7 0)
			(size 0.8 1.1)
			(layers "F.Cu" "F.Mask" "F.Paste")
			(roundrect_rratio 0.2)
			(net 1 "GND")
			(pintype "passive")
		)
		(pad "2" smd roundrect
			(at 0.7 0)
			(size 0.8 1.1)
			(layers "F.Cu" "F.Mask" "F.Paste")
			(roundrect_rratio 0.2)
			(net 282 "+1V15")
			(pintype "passive")
		)
	)
	(footprint "antmicro-footprints:R_0402_1005Metric"
		(layer "F.Cu")
		(at 147 110)
		(descr "Resistor SMD 0402")
		(tags "resistor SMD 0402")
		(property "Reference" "R228"
			(at -3.6 0.4 0)
			(layer "F.SilkS")
			(effects
				(font
					(size 0.7 0.7)
					(thickness 0.15)
				)
				(justify left bottom)
			)
		)
		(property "Value" "R_2k2_0402"
			(at -1.011843 1.772047 0)
			(layer "F.Fab")
			(effects
				(font
					(size 0.7 0.7)
					(thickness 0.15)
				)
				(justify left bottom)
			)
		)
		(property "Datasheet" "https://www.bourns.com/docs/product-datasheets/cr.pdf"
			(at 0 0 0)
			(layer "F.Fab")
			(hide yes)
			(effects
				(font
					(size 1.27 1.27)
					(thickness 0.15)
				)
			)
		)
		(property "Description" "SMD Chip Resistor, 2.2 kohm, ± 1%, 62.5 mW, 0402 [1005 Metric], Thick Film, General Purpose"
			(at 0 0 0)
			(layer "F.Fab")
			(hide yes)
			(effects
				(font
					(size 1.27 1.27)
					(thickness 0.15)
				)
			)
		)
		(property "MPN" "CR0402-FX-2201GLF"
			(at 0 0 0)
			(unlocked yes)
			(layer "F.Fab")
			(hide yes)
			(effects
				(font
					(size 1 1)
					(thickness 0.15)
				)
			)
		)
		(property "Manufacturer" "Bourns"
			(at 0 0 0)
			(unlocked yes)
			(layer "F.Fab")
			(hide yes)
			(effects
				(font
					(size 1 1)
					(thickness 0.15)
				)
			)
		)
		(property "License" "Apache-2.0"
			(at 0 0 0)
			(unlocked yes)
			(layer "F.Fab")
			(hide yes)
			(effects
				(font
					(size 1 1)
					(thickness 0.15)
				)
			)
		)
		(property "Author" "Antmicro"
			(at 0 0 0)
			(unlocked yes)
			(layer "F.Fab")
			(hide yes)
			(effects
				(font
					(size 1 1)
					(thickness 0.15)
				)
			)
		)
		(property "Val" "2k2"
			(at 0 0 0)
			(unlocked yes)
			(layer "F.Fab")
			(hide yes)
			(effects
				(font
					(size 1 1)
					(thickness 0.15)
				)
			)
		)
		(property "Tolerance" "1%"
			(at 0 0 0)
			(unlocked yes)
			(layer "F.Fab")
			(hide yes)
			(effects
				(font
					(size 1 1)
					(thickness 0.15)
				)
			)
		)
		(sheetname "/SoM_IO/")
		(sheetfile "som_io.kicad_sch")
		(attr smd exclude_from_pos_files exclude_from_bom dnp)
		(fp_rect
			(start -0.925 -0.47)
			(end 0.925 0.47)
			(stroke
				(width 0.05)
				(type default)
			)
			(fill no)
			(layer "F.CrtYd")
		)
		(fp_rect
			(start -0.5 -0.25)
			(end 0.5 0.25)
			(stroke
				(width 0.15)
				(type solid)
			)
			(fill no)
			(layer "F.Fab")
		)
		(fp_text user "${REFERENCE}"
			(at -0.95 3.168 0)
			(layer "F.Fab")
			(effects
				(font
					(size 0.7 0.7)
					(thickness 0.15)
				)
				(justify left bottom)
			)
		)
		(fp_text user "Author: Antmicro"
			(at -0.95 4.169 0)
			(layer "F.Fab")
			(effects
				(font
					(size 0.7 0.7)
					(thickness 0.15)
				)
				(justify left bottom)
			)
		)
		(fp_text user "License: Apache-2.0"
			(at -0.95 5.169 0)
			(layer "F.Fab")
			(effects
				(font
					(size 0.7 0.7)
					(thickness 0.15)
				)
				(justify left bottom)
			)
		)
		(pad "1" smd roundrect
			(at -0.48 0)
			(size 0.59 0.64)
			(layers "F.Cu" "F.Mask" "F.Paste")
			(roundrect_rratio 0.25)
			(net 11 "+1V8")
			(pintype "passive")
		)
		(pad "2" smd roundrect
			(at 0.48 0)
			(size 0.59 0.64)
			(layers "F.Cu" "F.Mask" "F.Paste")
			(roundrect_rratio 0.25)
			(net 139 "/SoM_IO/I2C2_SCL_1V8")
			(pintype "passive")
		)
	)
	(footprint "antmicro-footprints:C_0402_1005Metric"
		(layer "F.Cu")
		(at 91.1 97.3)
		(descr "Capacitor SMD 0402")
		(tags "capacitor SMD 0402")
		(property "Reference" "C349"
			(at 1.1 0.500001 0)
			(layer "F.SilkS")
			(effects
				(font
					(size 0.7 0.7)
					(thickness 0.15)
				)
				(justify left bottom)
			)
		)
		(property "Value" "C_100n_0402"
			(at -1.022927 2.155213 0)
			(layer "F.Fab")
			(effects
				(font
					(size 0.7 0.7)
					(thickness 0.15)
				)
				(justify left bottom)
			)
		)
		(property "Datasheet" "https://www.murata.com/products/productdetail?partno=GRM155R61H104KE14%23"
			(at 0 0 0)
			(layer "F.Fab")
			(hide yes)
			(effects
				(font
					(size 1.27 1.27)
					(thickness 0.15)
				)
			)
		)
		(property "Description" "SMD Multilayer Ceramic Capacitor, 0.1 µF, 50 V, 0402 [1005 Metric], ± 10%, X5R, GRM Series"
			(at 0 0 0)
			(layer "F.Fab")
			(hide yes)
			(effects
				(font
					(size 1.27 1.27)
					(thickness 0.15)
				)
			)
		)
		(property "Manufacturer" "Murata"
			(at 0 0 0)
			(unlocked yes)
			(layer "F.Fab")
			(hide yes)
			(effects
				(font
					(size 1 1)
					(thickness 0.15)
				)
			)
		)
		(property "MPN" "GRM155R61H104KE14D"
			(at 0 0 0)
			(unlocked yes)
			(layer "F.Fab")
			(hide yes)
			(effects
				(font
					(size 1 1)
					(thickness 0.15)
				)
			)
		)
		(property "Val" "100n"
			(at 0 0 0)
			(unlocked yes)
			(layer "F.Fab")
			(hide yes)
			(effects
				(font
					(size 1 1)
					(thickness 0.15)
				)
			)
		)
		(property "License" "Apache-2.0"
			(at 0 0 0)
			(unlocked yes)
			(layer "F.Fab")
			(hide yes)
			(effects
				(font
					(size 1 1)
					(thickness 0.15)
				)
			)
		)
		(property "Author" "Antmicro"
			(at 0 0 0)
			(unlocked yes)
			(layer "F.Fab")
			(hide yes)
			(effects
				(font
					(size 1 1)
					(thickness 0.15)
				)
			)
		)
		(property "Voltage" "50V"
			(at 0 0 0)
			(unlocked yes)
			(layer "F.Fab")
			(hide yes)
			(effects
				(font
					(size 1 1)
					(thickness 0.15)
				)
			)
		)
		(property "Dielectric" "X5R"
			(at 0 0 0)
			(unlocked yes)
			(layer "F.Fab")
			(hide yes)
			(effects
				(font
					(size 1 1)
					(thickness 0.15)
				)
			)
		)
		(sheetname "/SoM_IO2/")
		(sheetfile "som_io2.kicad_sch")
		(attr smd)
		(fp_rect
			(start -0.925 -0.47)
			(end 0.925 0.47)
			(stroke
				(width 0.05)
				(type default)
			)
			(fill no)
			(layer "F.CrtYd")
		)
		(fp_line
			(start -0.494 -0.25)
			(end 0.504 -0.25)
			(stroke
				(width 0.15)
				(type solid)
			)
			(layer "F.Fab")
		)
		(fp_line
			(start -0.494 0.248)
			(end -0.494 -0.25)
			(stroke
				(width 0.15)
				(type solid)
			)
			(layer "F.Fab")
		)
		(fp_line
			(start 0.504 -0.25)
			(end 0.504 0.248)
			(stroke
				(width 0.15)
				(type solid)
			)
			(layer "F.Fab")
		)
		(fp_line
			(start 0.504 0.248)
			(end -0.494 0.248)
			(stroke
				(width 0.15)
				(type solid)
			)
			(layer "F.Fab")
		)
		(fp_text user "Author: Antmicro"
			(at -0.939 3.399 0)
			(layer "F.Fab")
			(effects
				(font
					(size 0.7 0.7)
					(thickness 0.15)
				)
				(justify left bottom)
			)
		)
		(fp_text user "${REFERENCE}"
			(at -0.939 4.599 0)
			(layer "F.Fab")
			(effects
				(font
					(size 0.7 0.7)
					(thickness 0.15)
				)
				(justify left bottom)
			)
		)
		(fp_text user "License: Apache-2.0"
			(at -0.939 5.799 0)
			(layer "F.Fab")
			(effects
				(font
					(size 0.7 0.7)
					(thickness 0.15)
				)
				(justify left bottom)
			)
		)
		(pad "1" smd roundrect
			(at -0.48 0)
			(size 0.59 0.64)
			(layers "F.Cu" "F.Mask" "F.Paste")
			(roundrect_rratio 0.25)
			(net 675 "/Expansion connector/DP3.TX1-")
			(pintype "passive")
		)
		(pad "2" smd roundrect
			(at 0.48 0)
			(size 0.59 0.64)
			(layers "F.Cu" "F.Mask" "F.Paste")
			(roundrect_rratio 0.25)
			(net 1269 "/SoM_IO2/DP3.TX1_C-")
			(pintype "passive")
		)
	)
	(footprint "antmicro-footprints:QFN-2L_1.6x1x0.55mm"
		(layer "F.Cu")
		(at 160.6 93.8 90)
		(property "Reference" "D7"
			(at 0 -0.799999 90)
			(layer "F.SilkS")
			(effects
				(font
					(size 0.7 0.7)
					(thickness 0.15)
				)
				(justify left bottom)
			)
		)
		(property "Value" "ESDA25P35-1U1M"
			(at 0 1.700001 90)
			(layer "F.Fab")
			(effects
				(font
					(size 0.7 0.7)
					(thickness 0.15)
				)
				(justify left bottom)
			)
		)
		(property "Datasheet" "https://www.st.com/resource/en/datasheet/esda25p35-1u1m.pdf"
			(at 0 0 90)
			(layer "F.Fab")
			(hide yes)
			(effects
				(font
					(size 1.27 1.27)
					(thickness 0.15)
				)
			)
		)
		(property "Description" "Unidirectional TVS, 30 kV, QFN-2L, 22 V, 195 pF"
			(at 0 0 90)
			(layer "F.Fab")
			(hide yes)
			(effects
				(font
					(size 1.27 1.27)
					(thickness 0.15)
				)
			)
		)
		(property "Manufacturer" "STMicroelectronics"
			(at 0 0 90)
			(unlocked yes)
			(layer "F.Fab")
			(hide yes)
			(effects
				(font
					(size 1 1)
					(thickness 0.15)
				)
			)
		)
		(property "MPN" "ESDA25P35-1U1M"
			(at 0 0 90)
			(unlocked yes)
			(layer "F.Fab")
			(hide yes)
			(effects
				(font
					(size 1 1)
					(thickness 0.15)
				)
			)
		)
		(property "Author" "Antmicro"
			(at 0 0 90)
			(unlocked yes)
			(layer "F.Fab")
			(hide yes)
			(effects
				(font
					(size 1 1)
					(thickness 0.15)
				)
			)
		)
		(property "License" "Apache-2.0"
			(at 0 0 90)
			(unlocked yes)
			(layer "F.Fab")
			(hide yes)
			(effects
				(font
					(size 1 1)
					(thickness 0.15)
				)
			)
		)
		(component_classes
			(class "DCDC_SOM")
		)
		(sheetname "/DCDC/")
		(sheetfile "dcdc.kicad_sch")
		(attr smd)
		(fp_line
			(start 0.230001 -0.45)
			(end -0.230001 -0.45)
			(stroke
				(width 0.15)
				(type solid)
			)
			(layer "F.SilkS")
		)
		(fp_line
			(start -1.2 -0.4)
			(end -1.2 0.4)
			(stroke
				(width 0.15)
				(type solid)
			)
			(layer "F.SilkS")
		)
		(fp_line
			(start 0.230001 0.45)
			(end -0.230001 0.45)
			(stroke
				(width 0.15)
				(type solid)
			)
			(layer "F.SilkS")
		)
		(fp_poly
			(pts
				(xy 1.25 0.65) (xy 1.25 -0.65) (xy -1.25 -0.65) (xy -1.25 0.65)
			)
			(stroke
				(width 0.05)
				(type solid)
			)
			(fill no)
			(layer "F.CrtYd")
		)
		(fp_line
			(start 0.201 -0.202)
			(end -0.101 0)
			(stroke
				(width 0.15)
				(type solid)
			)
			(layer "F.Fab")
		)
		(fp_line
			(start -0.199 -0.202)
			(end -0.199 0.1)
			(stroke
				(width 0.15)
				(type solid)
			)
			(layer "F.Fab")
		)
		(fp_line
			(start 0.599 0)
			(end 0.200999 0)
			(stroke
				(width 0.15)
				(type solid)
			)
			(layer "F.Fab")
		)
		(fp_line
			(start 0.200999 0)
			(end 0.201 -0.202)
			(stroke
				(width 0.15)
				(type solid)
			)
			(layer "F.Fab")
		)
		(fp_line
			(start -0.101 0)
			(end 0.201 0.2)
			(stroke
				(width 0.15)
				(type solid)
			)
			(layer "F.Fab")
		)
		(fp_line
			(start -0.199 0)
			(end -0.597 0)
			(stroke
				(width 0.15)
				(type solid)
			)
			(layer "F.Fab")
		)
		(fp_line
			(start 0.201 0.2)
			(end 0.200999 0)
			(stroke
				(width 0.15)
				(type solid)
			)
			(layer "F.Fab")
		)
		(fp_line
			(start -0.199 0.2)
			(end -0.199 0.1)
			(stroke
				(width 0.15)
				(type solid)
			)
			(layer "F.Fab")
		)
		(fp_poly
			(pts
				(xy 0.848 0.4) (xy 0.848 -0.401999) (xy -0.85 -0.402) (xy -0.85 0.4)
			)
			(stroke
				(width 0.15)
				(type solid)
			)
			(fill no)
			(layer "F.Fab")
		)
		(fp_text user "License: Apache-2.0"
			(at -1.31 5.769 90)
			(layer "F.Fab")
			(effects
				(font
					(size 0.7 0.7)
					(thickness 0.15)
				)
				(justify left bottom)
			)
		)
		(fp_text user "${REFERENCE}"
			(at -1.309999 3.769 90)
			(layer "F.Fab")
			(effects
				(font
					(size 0.7 0.7)
					(thickness 0.15)
				)
				(justify left bottom)
			)
		)
		(fp_text user "Author: Antmicro"
			(at -1.31 4.769 90)
			(layer "F.Fab")
			(effects
				(font
					(size 0.7 0.7)
					(thickness 0.15)
				)
				(justify left bottom)
			)
		)
		(pad "1" smd roundrect
			(at -0.7 0 270)
			(size 0.8 1)
			(layers "F.Cu" "F.Mask" "F.Paste")
			(roundrect_rratio 0.2)
			(net 12 "SYS_VIN_HV")
			(pinfunction "C")
			(pintype "passive")
		)
		(pad "2" smd roundrect
			(at 0.7 0 270)
			(size 0.8 1)
			(layers "F.Cu" "F.Mask" "F.Paste")
			(roundrect_rratio 0.2)
			(net 1 "GND")
			(pinfunction "A")
			(pintype "passive")
		)
	)
	(footprint "antmicro-footprints:C_0603_1608Metric_EIA"
		(layer "F.Cu")
		(at 188.25 127.3 -90)
		(descr "Capacitor SMD 0603, IPC-7351 Density Level A")
		(tags "Capacitor 0603")
		(property "Reference" "C35"
			(at 1.1 0.45 90)
			(layer "F.SilkS")
			(effects
				(font
					(size 0.7 0.7)
					(thickness 0.15)
				)
				(justify right top)
			)
		)
		(property "Value" "C_22u_16V_0603"
			(at -1.42757 1.770288 90)
			(layer "F.Fab")
			(effects
				(font
					(size 0.7 0.7)
					(thickness 0.15)
				)
				(justify right top)
			)
		)
		(property "Datasheet" "https://product.samsungsem.com/mlcc/CL10A226MO7JZN.do"
			(at 0 0 90)
			(layer "F.Fab")
			(hide yes)
			(effects
				(font
					(size 1.27 1.27)
					(thickness 0.15)
				)
			)
		)
		(property "Description" "SMD Multilayer Ceramic Capacitor"
			(at 0 0 90)
			(layer "F.Fab")
			(hide yes)
			(effects
				(font
					(size 1.27 1.27)
					(thickness 0.15)
				)
			)
		)
		(property "MPN" "CL10A226MO7JZNC"
			(at 0 0 270)
			(unlocked yes)
			(layer "F.Fab")
			(hide yes)
			(effects
				(font
					(size 1 1)
					(thickness 0.15)
				)
			)
		)
		(property "Manufacturer" "Samsung Electro-Mechanics"
			(at 0 0 270)
			(unlocked yes)
			(layer "F.Fab")
			(hide yes)
			(effects
				(font
					(size 1 1)
					(thickness 0.15)
				)
			)
		)
		(property "License" "Apache-2.0"
			(at 0 0 270)
			(unlocked yes)
			(layer "F.Fab")
			(hide yes)
			(effects
				(font
					(size 1 1)
					(thickness 0.15)
				)
			)
		)
		(property "Author" "Antmicro"
			(at 0 0 270)
			(unlocked yes)
			(layer "F.Fab")
			(hide yes)
			(effects
				(font
					(size 1 1)
					(thickness 0.15)
				)
			)
		)
		(property "Val" "22u"
			(at 0 0 270)
			(unlocked yes)
			(layer "F.Fab")
			(hide yes)
			(effects
				(font
					(size 1 1)
					(thickness 0.15)
				)
			)
		)
		(property "Voltage" "16V"
			(at 0 0 270)
			(unlocked yes)
			(layer "F.Fab")
			(hide yes)
			(effects
				(font
					(size 1 1)
					(thickness 0.15)
				)
			)
		)
		(property "Dielectric" ""
			(at 0 0 270)
			(unlocked yes)
			(layer "F.Fab")
			(hide yes)
			(effects
				(font
					(size 1 1)
					(thickness 0.15)
				)
			)
		)
		(property "Public" "False"
			(at 0 0 270)
			(unlocked yes)
			(layer "F.Fab")
			(hide yes)
			(effects
				(font
					(size 1 1)
					(thickness 0.15)
				)
			)
		)
		(component_classes
			(class "DCDC_1V15")
		)
		(sheetname "/DCDC/")
		(sheetfile "dcdc.kicad_sch")
		(attr smd)
		(fp_line
			(start -0.15 0.55)
			(end 0.15 0.55)
			(stroke
				(width 0.15)
				(type solid)
			)
			(layer "F.SilkS")
		)
		(fp_line
			(start -0.15 -0.55)
			(end 0.15 -0.55)
			(stroke
				(width 0.15)
				(type solid)
			)
			(layer "F.SilkS")
		)
		(fp_rect
			(start -1.25 -0.65)
			(end 1.25 0.65)
			(stroke
				(width 0.05)
				(type solid)
			)
			(fill no)
			(layer "F.CrtYd")
		)
		(fp_rect
			(start -0.8 -0.45)
			(end 0.8 0.45)
			(stroke
				(width 0.15)
				(type solid)
			)
			(fill no)
			(layer "F.Fab")
		)
		(fp_text user "${REFERENCE}"
			(at -1.682 3.895 90)
			(layer "F.Fab")
			(effects
				(font
					(size 0.7 0.7)
					(thickness 0.15)
				)
				(justify right top)
			)
		)
		(fp_text user "License: Apache-2.0"
			(at -1.682 5.895 90)
			(layer "F.Fab")
			(effects
				(font
					(size 0.7 0.7)
					(thickness 0.15)
				)
				(justify right top)
			)
		)
		(fp_text user "Author: Antmicro"
			(at -1.682 4.894 90)
			(layer "F.Fab")
			(effects
				(font
					(size 0.7 0.7)
					(thickness 0.15)
				)
				(justify right top)
			)
		)
		(pad "1" smd roundrect
			(at -0.7 0 270)
			(size 0.8 1.1)
			(layers "F.Cu" "F.Mask" "F.Paste")
			(roundrect_rratio 0.2)
			(net 1 "GND")
			(pintype "passive")
		)
		(pad "2" smd roundrect
			(at 0.7 0 270)
			(size 0.8 1.1)
			(layers "F.Cu" "F.Mask" "F.Paste")
			(roundrect_rratio 0.2)
			(net 5 "+5V")
			(pintype "passive")
		)
	)
	(footprint "antmicro-footprints:R_0402_1005Metric"
		(layer "F.Cu")
		(at 147 111)
		(descr "Resistor SMD 0402")
		(tags "resistor SMD 0402")
		(property "Reference" "R352"
			(at -3.6 0.4 0)
			(layer "F.SilkS")
			(effects
				(font
					(size 0.7 0.7)
					(thickness 0.15)
				)
				(justify left bottom)
			)
		)
		(property "Value" "R_2k2_0402"
			(at -1.011843 1.772047 0)
			(layer "F.Fab")
			(effects
				(font
					(size 0.7 0.7)
					(thickness 0.15)
				)
				(justify left bottom)
			)
		)
		(property "Datasheet" "https://www.bourns.com/docs/product-datasheets/cr.pdf"
			(at 0 0 0)
			(layer "F.Fab")
			(hide yes)
			(effects
				(font
					(size 1.27 1.27)
					(thickness 0.15)
				)
			)
		)
		(property "Description" "SMD Chip Resistor, 2.2 kohm, ± 1%, 62.5 mW, 0402 [1005 Metric], Thick Film, General Purpose"
			(at 0 0 0)
			(layer "F.Fab")
			(hide yes)
			(effects
				(font
					(size 1.27 1.27)
					(thickness 0.15)
				)
			)
		)
		(property "MPN" "CR0402-FX-2201GLF"
			(at 0 0 0)
			(unlocked yes)
			(layer "F.Fab")
			(hide yes)
			(effects
				(font
					(size 1 1)
					(thickness 0.15)
				)
			)
		)
		(property "Manufacturer" "Bourns"
			(at 0 0 0)
			(unlocked yes)
			(layer "F.Fab")
			(hide yes)
			(effects
				(font
					(size 1 1)
					(thickness 0.15)
				)
			)
		)
		(property "License" "Apache-2.0"
			(at 0 0 0)
			(unlocked yes)
			(layer "F.Fab")
			(hide yes)
			(effects
				(font
					(size 1 1)
					(thickness 0.15)
				)
			)
		)
		(property "Author" "Antmicro"
			(at 0 0 0)
			(unlocked yes)
			(layer "F.Fab")
			(hide yes)
			(effects
				(font
					(size 1 1)
					(thickness 0.15)
				)
			)
		)
		(property "Val" "2k2"
			(at 0 0 0)
			(unlocked yes)
			(layer "F.Fab")
			(hide yes)
			(effects
				(font
					(size 1 1)
					(thickness 0.15)
				)
			)
		)
		(property "Tolerance" "1%"
			(at 0 0 0)
			(unlocked yes)
			(layer "F.Fab")
			(hide yes)
			(effects
				(font
					(size 1 1)
					(thickness 0.15)
				)
			)
		)
		(sheetname "/SoM_IO/")
		(sheetfile "som_io.kicad_sch")
		(attr smd exclude_from_pos_files exclude_from_bom dnp)
		(fp_rect
			(start -0.925 -0.47)
			(end 0.925 0.47)
			(stroke
				(width 0.05)
				(type default)
			)
			(fill no)
			(layer "F.CrtYd")
		)
		(fp_rect
			(start -0.5 -0.25)
			(end 0.5 0.25)
			(stroke
				(width 0.15)
				(type solid)
			)
			(fill no)
			(layer "F.Fab")
		)
		(fp_text user "Author: Antmicro"
			(at -0.95 4.169 0)
			(layer "F.Fab")
			(effects
				(font
					(size 0.7 0.7)
					(thickness 0.15)
				)
				(justify left bottom)
			)
		)
		(fp_text user "License: Apache-2.0"
			(at -0.95 5.169 0)
			(layer "F.Fab")
			(effects
				(font
					(size 0.7 0.7)
					(thickness 0.15)
				)
				(justify left bottom)
			)
		)
		(fp_text user "${REFERENCE}"
			(at -0.95 3.168 0)
			(layer "F.Fab")
			(effects
				(font
					(size 0.7 0.7)
					(thickness 0.15)
				)
				(justify left bottom)
			)
		)
		(pad "1" smd roundrect
			(at -0.48 0)
			(size 0.59 0.64)
			(layers "F.Cu" "F.Mask" "F.Paste")
			(roundrect_rratio 0.25)
			(net 11 "+1V8")
			(pintype "passive")
		)
		(pad "2" smd roundrect
			(at 0.48 0)
			(size 0.59 0.64)
			(layers "F.Cu" "F.Mask" "F.Paste")
			(roundrect_rratio 0.25)
			(net 167 "/SoM_IO/I2C2_SDA_1V8")
			(pintype "passive")
		)
	)
	(footprint "antmicro-footprints:R_0402_1005Metric"
		(layer "F.Cu")
		(at 88 57.5 180)
		(descr "Resistor SMD 0402")
		(tags "resistor SMD 0402")
		(property "Reference" "R301"
			(at 16.35 -8.65 0)
			(layer "F.SilkS")
			(effects
				(font
					(size 0.7 0.7)
					(thickness 0.15)
				)
				(justify right top)
			)
		)
		(property "Value" "R_0R_0402"
			(at -1.011843 1.772047 0)
			(layer "F.Fab")
			(effects
				(font
					(size 0.7 0.7)
					(thickness 0.15)
				)
				(justify right top)
			)
		)
		(property "Datasheet" "https://industrial.panasonic.com/cdbs/www-data/pdf/RDA0000/AOA0000C301.pdf"
			(at 0 0 0)
			(layer "F.Fab")
			(hide yes)
			(effects
				(font
					(size 1.27 1.27)
					(thickness 0.15)
				)
			)
		)
		(property "Description" "SMD Chip Resistor, Jumper, 0 ohm, 100 mW, 0402 [1005 Metric], Thick Film, General Purpose"
			(at 0 0 0)
			(layer "F.Fab")
			(hide yes)
			(effects
				(font
					(size 1.27 1.27)
					(thickness 0.15)
				)
			)
		)
		(property "MPN" "ERJ2GE0R00X"
			(at 0 0 180)
			(unlocked yes)
			(layer "F.Fab")
			(hide yes)
			(effects
				(font
					(size 1 1)
					(thickness 0.15)
				)
			)
		)
		(property "Manufacturer" "Panasonic"
			(at 0 0 180)
			(unlocked yes)
			(layer "F.Fab")
			(hide yes)
			(effects
				(font
					(size 1 1)
					(thickness 0.15)
				)
			)
		)
		(property "License" "Apache-2.0"
			(at 0 0 180)
			(unlocked yes)
			(layer "F.Fab")
			(hide yes)
			(effects
				(font
					(size 1 1)
					(thickness 0.15)
				)
			)
		)
		(property "Author" "Antmicro"
			(at 0 0 180)
			(unlocked yes)
			(layer "F.Fab")
			(hide yes)
			(effects
				(font
					(size 1 1)
					(thickness 0.15)
				)
			)
		)
		(property "Val" "0R"
			(at 0 0 180)
			(unlocked yes)
			(layer "F.Fab")
			(hide yes)
			(effects
				(font
					(size 1 1)
					(thickness 0.15)
				)
			)
		)
		(property "Tolerance" "~"
			(at 0 0 180)
			(unlocked yes)
			(layer "F.Fab")
			(hide yes)
			(effects
				(font
					(size 1 1)
					(thickness 0.15)
				)
			)
		)
		(property "Current" "1A"
			(at 0 0 180)
			(unlocked yes)
			(layer "F.Fab")
			(hide yes)
			(effects
				(font
					(size 1 1)
					(thickness 0.15)
				)
			)
		)
		(sheetname "/SoM_Power/")
		(sheetfile "som_power.kicad_sch")
		(attr smd)
		(fp_rect
			(start -0.925 -0.47)
			(end 0.925 0.47)
			(stroke
				(width 0.05)
				(type default)
			)
			(fill no)
			(layer "F.CrtYd")
		)
		(fp_rect
			(start -0.5 -0.25)
			(end 0.5 0.25)
			(stroke
				(width 0.15)
				(type solid)
			)
			(fill no)
			(layer "F.Fab")
		)
		(fp_text user "${REFERENCE}"
			(at -0.95 3.168 0)
			(layer "F.Fab")
			(effects
				(font
					(size 0.7 0.7)
					(thickness 0.15)
				)
				(justify right top)
			)
		)
		(fp_text user "License: Apache-2.0"
			(at -0.95 5.169 0)
			(layer "F.Fab")
			(effects
				(font
					(size 0.7 0.7)
					(thickness 0.15)
				)
				(justify right top)
			)
		)
		(fp_text user "Author: Antmicro"
			(at -0.95 4.169 0)
			(layer "F.Fab")
			(effects
				(font
					(size 0.7 0.7)
					(thickness 0.15)
				)
				(justify right top)
			)
		)
		(pad "1" smd roundrect
			(at -0.48 0 180)
			(size 0.59 0.64)
			(layers "F.Cu" "F.Mask" "F.Paste")
			(roundrect_rratio 0.25)
			(net 1033 "Net-(U70-OUT)")
			(pintype "passive")
		)
		(pad "2" smd roundrect
			(at 0.48 0 180)
			(size 0.59 0.64)
			(layers "F.Cu" "F.Mask" "F.Paste")
			(roundrect_rratio 0.25)
			(net 1382 "Net-(R300-Pad2)")
			(pintype "passive")
		)
	)
	(footprint "antmicro-footprints:TP_SMD_0.75mm"
		(layer "F.Cu")
		(at 79.4 76.8 180)
		(property "Reference" "TP73"
			(at -0.49 -3.34 270)
			(layer "F.SilkS")
			(effects
				(font
					(size 0.7 0.7)
					(thickness 0.15)
				)
				(justify left bottom)
			)
		)
		(property "Value" "TP_0.75mm_SMD"
			(at 0 1.2 180)
			(layer "F.Fab")
			(effects
				(font
					(size 0.7 0.7)
					(thickness 0.15)
				)
				(justify left bottom)
			)
		)
		(property "Description" "SMT test point"
			(at 0 0 180)
			(layer "F.Fab")
			(hide yes)
			(effects
				(font
					(size 1.27 1.27)
					(thickness 0.15)
				)
			)
		)
		(property "MPN" ""
			(at 0 0 180)
			(unlocked yes)
			(layer "F.Fab")
			(hide yes)
			(effects
				(font
					(size 1 1)
					(thickness 0.15)
				)
			)
		)
		(property "Manufacturer" ""
			(at 0 0 180)
			(unlocked yes)
			(layer "F.Fab")
			(hide yes)
			(effects
				(font
					(size 1 1)
					(thickness 0.15)
				)
			)
		)
		(property "Author" "Antmicro"
			(at 0 0 180)
			(unlocked yes)
			(layer "F.Fab")
			(hide yes)
			(effects
				(font
					(size 1 1)
					(thickness 0.15)
				)
			)
		)
		(property "License" "Apache-2.0"
			(at 0 0 180)
			(unlocked yes)
			(layer "F.Fab")
			(hide yes)
			(effects
				(font
					(size 1 1)
					(thickness 0.15)
				)
			)
		)
		(sheetname "/Expansion connector/")
		(sheetfile "expansion_connector.kicad_sch")
		(attr exclude_from_pos_files exclude_from_bom)
		(fp_circle
			(center 0 0)
			(end 0.475 0)
			(stroke
				(width 0.05)
				(type default)
			)
			(fill no)
			(layer "F.CrtYd")
		)
		(fp_text user "Author: Antmicro"
			(at -0.4 3.901 180)
			(layer "F.Fab")
			(effects
				(font
					(size 0.7 0.7)
					(thickness 0.15)
				)
				(justify left bottom)
			)
		)
		(fp_text user "${REFERENCE}"
			(at -0.4 2.7 180)
			(layer "F.Fab")
			(effects
				(font
					(size 0.7 0.7)
					(thickness 0.15)
				)
				(justify left bottom)
			)
		)
		(fp_text user "License: Apache-2.0"
			(at -0.4 5.101 180)
			(layer "F.Fab")
			(effects
				(font
					(size 0.7 0.7)
					(thickness 0.15)
				)
				(justify left bottom)
			)
		)
		(pad "1" smd circle
			(at 0 0 180)
			(size 0.75 0.75)
			(layers "F.Cu" "F.Mask")
			(net 659 "Net-(J18-PadB01)")
			(pinfunction "1")
			(pintype "passive")
		)
	)
	(footprint "antmicro-footprints:R_0402_1005Metric"
		(layer "F.Cu")
		(at 182.764468 87.835 90)
		(descr "Resistor SMD 0402")
		(tags "resistor SMD 0402")
		(property "Reference" "R69"
			(at -0.84 2.38 90)
			(layer "F.SilkS")
			(effects
				(font
					(size 0.7 0.7)
					(thickness 0.15)
				)
				(justify left bottom)
			)
		)
		(property "Value" "R_255k_0402"
			(at -1.011843 1.772047 90)
			(layer "F.Fab")
			(effects
				(font
					(size 0.7 0.7)
					(thickness 0.15)
				)
				(justify left bottom)
			)
		)
		(property "Datasheet" "https://www.bourns.com/docs/product-datasheets/cr.pdf"
			(at 0 0 90)
			(layer "F.Fab")
			(hide yes)
			(effects
				(font
					(size 1.27 1.27)
					(thickness 0.15)
				)
			)
		)
		(property "Description" "SMD Chip Resistor, 255 kohm, ± 1%, 100 mW, 0402 [1005 Metric], Thick Film, Precision"
			(at 0 0 90)
			(layer "F.Fab")
			(hide yes)
			(effects
				(font
					(size 1.27 1.27)
					(thickness 0.15)
				)
			)
		)
		(property "MPN" "CR0402-FX-2553GLF"
			(at 0 0 90)
			(unlocked yes)
			(layer "F.Fab")
			(hide yes)
			(effects
				(font
					(size 1 1)
					(thickness 0.15)
				)
			)
		)
		(property "Manufacturer" "Bourns"
			(at 0 0 90)
			(unlocked yes)
			(layer "F.Fab")
			(hide yes)
			(effects
				(font
					(size 1 1)
					(thickness 0.15)
				)
			)
		)
		(property "License" "Apache-2.0"
			(at 0 0 90)
			(unlocked yes)
			(layer "F.Fab")
			(hide yes)
			(effects
				(font
					(size 1 1)
					(thickness 0.15)
				)
			)
		)
		(property "Author" "Antmicro"
			(at 0 0 90)
			(unlocked yes)
			(layer "F.Fab")
			(hide yes)
			(effects
				(font
					(size 1 1)
					(thickness 0.15)
				)
			)
		)
		(property "Val" "255k"
			(at 0 0 90)
			(unlocked yes)
			(layer "F.Fab")
			(hide yes)
			(effects
				(font
					(size 1 1)
					(thickness 0.15)
				)
			)
		)
		(property "Tolerance" "1%"
			(at 0 0 90)
			(unlocked yes)
			(layer "F.Fab")
			(hide yes)
			(effects
				(font
					(size 1 1)
					(thickness 0.15)
				)
			)
		)
		(component_classes
			(class "DCDC_SOM")
		)
		(sheetname "/DCDC/")
		(sheetfile "dcdc.kicad_sch")
		(attr smd)
		(fp_rect
			(start -0.925 -0.47)
			(end 0.925 0.47)
			(stroke
				(width 0.05)
				(type default)
			)
			(fill no)
			(layer "F.CrtYd")
		)
		(fp_rect
			(start -0.5 -0.25)
			(end 0.5 0.25)
			(stroke
				(width 0.15)
				(type solid)
			)
			(fill no)
			(layer "F.Fab")
		)
		(fp_text user "${REFERENCE}"
			(at -0.95 3.168 90)
			(layer "F.Fab")
			(effects
				(font
					(size 0.7 0.7)
					(thickness 0.15)
				)
				(justify left bottom)
			)
		)
		(fp_text user "Author: Antmicro"
			(at -0.95 4.169 90)
			(layer "F.Fab")
			(effects
				(font
					(size 0.7 0.7)
					(thickness 0.15)
				)
				(justify left bottom)
			)
		)
		(fp_text user "License: Apache-2.0"
			(at -0.95 5.169 90)
			(layer "F.Fab")
			(effects
				(font
					(size 0.7 0.7)
					(thickness 0.15)
				)
				(justify left bottom)
			)
		)
		(pad "1" smd roundrect
			(at -0.48 0 90)
			(size 0.59 0.64)
			(layers "F.Cu" "F.Mask" "F.Paste")
			(roundrect_rratio 0.25)
			(net 1219 "/DCDC/16V_FB")
			(pintype "passive")
		)
		(pad "2" smd roundrect
			(at 0.48 0 90)
			(size 0.59 0.64)
			(layers "F.Cu" "F.Mask" "F.Paste")
			(roundrect_rratio 0.25)
			(net 903 "/DCDC/16V_OUT")
			(pintype "passive")
		)
	)
	(footprint "antmicro-footprints:C_0805_2012Metric"
		(layer "F.Cu")
		(at 174.49 146.32 -90)
		(descr "Capacitor SMD 0805")
		(tags "capacitor SMD 0805")
		(property "Reference" "C307"
			(at 1.89 0.13 90)
			(layer "F.SilkS")
			(effects
				(font
					(size 0.7 0.7)
					(thickness 0.15)
				)
				(justify right top)
			)
		)
		(property "Value" "C_22u_25V_0805"
			(at -2.055717 1.963152 90)
			(layer "F.Fab")
			(effects
				(font
					(size 0.7 0.7)
					(thickness 0.15)
				)
				(justify right top)
			)
		)
		(property "Datasheet" "https://product.samsungsem.com/mlcc/CL21A226MAYNNN.do"
			(at 0 0 90)
			(layer "F.Fab")
			(hide yes)
			(effects
				(font
					(size 1.27 1.27)
					(thickness 0.15)
				)
			)
		)
		(property "Description" "SMT Multilayer Ceramic Capacitor, 22uF, +/-20%, 25V, X5R, 0805 [2012 Metric]"
			(at 0 0 90)
			(layer "F.Fab")
			(hide yes)
			(effects
				(font
					(size 1.27 1.27)
					(thickness 0.15)
				)
			)
		)
		(property "Manufacturer" "Samsung Electro-Mechanics"
			(at 0 0 270)
			(unlocked yes)
			(layer "F.Fab")
			(hide yes)
			(effects
				(font
					(size 1 1)
					(thickness 0.15)
				)
			)
		)
		(property "MPN" "CL21A226MAYNNNE"
			(at 0 0 270)
			(unlocked yes)
			(layer "F.Fab")
			(hide yes)
			(effects
				(font
					(size 1 1)
					(thickness 0.15)
				)
			)
		)
		(property "Val" "22u"
			(at 0 0 270)
			(unlocked yes)
			(layer "F.Fab")
			(hide yes)
			(effects
				(font
					(size 1 1)
					(thickness 0.15)
				)
			)
		)
		(property "License" "Apache-2.0"
			(at 0 0 270)
			(unlocked yes)
			(layer "F.Fab")
			(hide yes)
			(effects
				(font
					(size 1 1)
					(thickness 0.15)
				)
			)
		)
		(property "Author" "Antmicro"
			(at 0 0 270)
			(unlocked yes)
			(layer "F.Fab")
			(hide yes)
			(effects
				(font
					(size 1 1)
					(thickness 0.15)
				)
			)
		)
		(property "Voltage" "25V"
			(at 0 0 270)
			(unlocked yes)
			(layer "F.Fab")
			(hide yes)
			(effects
				(font
					(size 1 1)
					(thickness 0.15)
				)
			)
		)
		(property "Dielectric" "X5R"
			(at 0 0 270)
			(unlocked yes)
			(layer "F.Fab")
			(hide yes)
			(effects
				(font
					(size 1 1)
					(thickness 0.15)
				)
			)
		)
		(property "Public" "False"
			(at 0 0 270)
			(unlocked yes)
			(layer "F.Fab")
			(hide yes)
			(effects
				(font
					(size 1 1)
					(thickness 0.15)
				)
			)
		)
		(sheetname "/DCDC/")
		(sheetfile "dcdc.kicad_sch")
		(attr smd)
		(fp_line
			(start -0.3 0.7)
			(end 0.3 0.7)
			(stroke
				(width 0.15)
				(type solid)
			)
			(layer "F.SilkS")
		)
		(fp_line
			(start -0.3 -0.7)
			(end 0.3 -0.7)
			(stroke
				(width 0.15)
				(type solid)
			)
			(layer "F.SilkS")
		)
		(fp_rect
			(start 1.95 -0.9)
			(end -1.95 0.9)
			(stroke
				(width 0.05)
				(type default)
			)
			(fill no)
			(layer "F.CrtYd")
		)
		(fp_rect
			(start -0.95 -0.675)
			(end 0.95 0.675)
			(stroke
				(width 0.15)
				(type solid)
			)
			(fill no)
			(layer "F.Fab")
		)
		(fp_text user "${REFERENCE}"
			(at -1.9 3.947 90)
			(layer "F.Fab")
			(effects
				(font
					(size 0.7 0.7)
					(thickness 0.15)
				)
				(justify right top)
			)
		)
		(fp_text user "Author: Antmicro"
			(at -1.9 5.947 90)
			(layer "F.Fab")
			(effects
				(font
					(size 0.7 0.7)
					(thickness 0.15)
				)
				(justify right top)
			)
		)
		(fp_text user "License: Apache-2.0"
			(at -1.9 4.947 90)
			(layer "F.Fab")
			(effects
				(font
					(size 0.7 0.7)
					(thickness 0.15)
				)
				(justify right top)
			)
		)
		(pad "1" smd roundrect
			(at -1.1 0 270)
			(size 1.2 1.3)
			(layers "F.Cu" "F.Mask" "F.Paste")
			(roundrect_rratio 0.25)
			(net 1 "GND")
			(pintype "passive")
		)
		(pad "2" smd roundrect
			(at 1.1 0 270)
			(size 1.2 1.3)
			(layers "F.Cu" "F.Mask" "F.Paste")
			(roundrect_rratio 0.25)
			(net 880 "/DCDC/12V_OUT")
			(pintype "passive")
		)
	)
	(footprint "antmicro-footprints:C_0402_1005Metric"
		(layer "F.Cu")
		(at 89.12 90.45)
		(descr "Capacitor SMD 0402")
		(tags "capacitor SMD 0402")
		(property "Reference" "C338"
			(at -3.82 0.45 0)
			(layer "F.SilkS")
			(effects
				(font
					(size 0.7 0.7)
					(thickness 0.15)
				)
				(justify left bottom)
			)
		)
		(property "Value" "C_100n_0402"
			(at -1.022927 2.155213 0)
			(layer "F.Fab")
			(effects
				(font
					(size 0.7 0.7)
					(thickness 0.15)
				)
				(justify left bottom)
			)
		)
		(property "Datasheet" "https://www.murata.com/products/productdetail?partno=GRM155R61H104KE14%23"
			(at 0 0 0)
			(layer "F.Fab")
			(hide yes)
			(effects
				(font
					(size 1.27 1.27)
					(thickness 0.15)
				)
			)
		)
		(property "Description" "SMD Multilayer Ceramic Capacitor, 0.1 µF, 50 V, 0402 [1005 Metric], ± 10%, X5R, GRM Series"
			(at 0 0 0)
			(layer "F.Fab")
			(hide yes)
			(effects
				(font
					(size 1.27 1.27)
					(thickness 0.15)
				)
			)
		)
		(property "Manufacturer" "Murata"
			(at 0 0 0)
			(unlocked yes)
			(layer "F.Fab")
			(hide yes)
			(effects
				(font
					(size 1 1)
					(thickness 0.15)
				)
			)
		)
		(property "MPN" "GRM155R61H104KE14D"
			(at 0 0 0)
			(unlocked yes)
			(layer "F.Fab")
			(hide yes)
			(effects
				(font
					(size 1 1)
					(thickness 0.15)
				)
			)
		)
		(property "Val" "100n"
			(at 0 0 0)
			(unlocked yes)
			(layer "F.Fab")
			(hide yes)
			(effects
				(font
					(size 1 1)
					(thickness 0.15)
				)
			)
		)
		(property "License" "Apache-2.0"
			(at 0 0 0)
			(unlocked yes)
			(layer "F.Fab")
			(hide yes)
			(effects
				(font
					(size 1 1)
					(thickness 0.15)
				)
			)
		)
		(property "Author" "Antmicro"
			(at 0 0 0)
			(unlocked yes)
			(layer "F.Fab")
			(hide yes)
			(effects
				(font
					(size 1 1)
					(thickness 0.15)
				)
			)
		)
		(property "Voltage" "50V"
			(at 0 0 0)
			(unlocked yes)
			(layer "F.Fab")
			(hide yes)
			(effects
				(font
					(size 1 1)
					(thickness 0.15)
				)
			)
		)
		(property "Dielectric" "X5R"
			(at 0 0 0)
			(unlocked yes)
			(layer "F.Fab")
			(hide yes)
			(effects
				(font
					(size 1 1)
					(thickness 0.15)
				)
			)
		)
		(sheetname "/SoM_IO2/")
		(sheetfile "som_io2.kicad_sch")
		(attr smd)
		(fp_rect
			(start -0.925 -0.47)
			(end 0.925 0.47)
			(stroke
				(width 0.05)
				(type default)
			)
			(fill no)
			(layer "F.CrtYd")
		)
		(fp_line
			(start -0.494 -0.25)
			(end 0.504 -0.25)
			(stroke
				(width 0.15)
				(type solid)
			)
			(layer "F.Fab")
		)
		(fp_line
			(start -0.494 0.248)
			(end -0.494 -0.25)
			(stroke
				(width 0.15)
				(type solid)
			)
			(layer "F.Fab")
		)
		(fp_line
			(start 0.504 -0.25)
			(end 0.504 0.248)
			(stroke
				(width 0.15)
				(type solid)
			)
			(layer "F.Fab")
		)
		(fp_line
			(start 0.504 0.248)
			(end -0.494 0.248)
			(stroke
				(width 0.15)
				(type solid)
			)
			(layer "F.Fab")
		)
		(fp_text user "License: Apache-2.0"
			(at -0.939 5.799 0)
			(layer "F.Fab")
			(effects
				(font
					(size 0.7 0.7)
					(thickness 0.15)
				)
				(justify left bottom)
			)
		)
		(fp_text user "Author: Antmicro"
			(at -0.939 3.399 0)
			(layer "F.Fab")
			(effects
				(font
					(size 0.7 0.7)
					(thickness 0.15)
				)
				(justify left bottom)
			)
		)
		(fp_text user "${REFERENCE}"
			(at -0.939 4.599 0)
			(layer "F.Fab")
			(effects
				(font
					(size 0.7 0.7)
					(thickness 0.15)
				)
				(justify left bottom)
			)
		)
		(pad "1" smd roundrect
			(at -0.48 0)
			(size 0.59 0.64)
			(layers "F.Cu" "F.Mask" "F.Paste")
			(roundrect_rratio 0.25)
			(net 737 "/Expansion connector/DP2.TX0-")
			(pintype "passive")
		)
		(pad "2" smd roundrect
			(at 0.48 0)
			(size 0.59 0.64)
			(layers "F.Cu" "F.Mask" "F.Paste")
			(roundrect_rratio 0.25)
			(net 1258 "/SoM_IO2/DP2.TX0_C-")
			(pintype "passive")
		)
	)
	(footprint "antmicro-footprints:C_0402_1005Metric"
		(layer "F.Cu")
		(at 218.8 132.825 180)
		(descr "Capacitor SMD 0402")
		(tags "capacitor SMD 0402")
		(property "Reference" "C81"
			(at -0.9 2.425 0)
			(layer "F.SilkS")
			(effects
				(font
					(size 0.7 0.7)
					(thickness 0.15)
				)
				(justify right top)
			)
		)
		(property "Value" "C_100n_0402"
			(at -1.022927 2.155213 0)
			(layer "F.Fab")
			(effects
				(font
					(size 0.7 0.7)
					(thickness 0.15)
				)
				(justify right top)
			)
		)
		(property "Datasheet" "https://www.murata.com/products/productdetail?partno=GRM155R61H104KE14%23"
			(at 0 0 0)
			(layer "F.Fab")
			(hide yes)
			(effects
				(font
					(size 1.27 1.27)
					(thickness 0.15)
				)
			)
		)
		(property "Description" "SMD Multilayer Ceramic Capacitor, 0.1 µF, 50 V, 0402 [1005 Metric], ± 10%, X5R, GRM Series"
			(at 0 0 0)
			(layer "F.Fab")
			(hide yes)
			(effects
				(font
					(size 1.27 1.27)
					(thickness 0.15)
				)
			)
		)
		(property "Manufacturer" "Murata"
			(at 0 0 180)
			(unlocked yes)
			(layer "F.Fab")
			(hide yes)
			(effects
				(font
					(size 1 1)
					(thickness 0.15)
				)
			)
		)
		(property "MPN" "GRM155R61H104KE14D"
			(at 0 0 180)
			(unlocked yes)
			(layer "F.Fab")
			(hide yes)
			(effects
				(font
					(size 1 1)
					(thickness 0.15)
				)
			)
		)
		(property "Val" "100n"
			(at 0 0 180)
			(unlocked yes)
			(layer "F.Fab")
			(hide yes)
			(effects
				(font
					(size 1 1)
					(thickness 0.15)
				)
			)
		)
		(property "License" "Apache-2.0"
			(at 0 0 180)
			(unlocked yes)
			(layer "F.Fab")
			(hide yes)
			(effects
				(font
					(size 1 1)
					(thickness 0.15)
				)
			)
		)
		(property "Author" "Antmicro"
			(at 0 0 180)
			(unlocked yes)
			(layer "F.Fab")
			(hide yes)
			(effects
				(font
					(size 1 1)
					(thickness 0.15)
				)
			)
		)
		(property "Voltage" "50V"
			(at 0 0 180)
			(unlocked yes)
			(layer "F.Fab")
			(hide yes)
			(effects
				(font
					(size 1 1)
					(thickness 0.15)
				)
			)
		)
		(property "Dielectric" "X5R"
			(at 0 0 180)
			(unlocked yes)
			(layer "F.Fab")
			(hide yes)
			(effects
				(font
					(size 1 1)
					(thickness 0.15)
				)
			)
		)
		(sheetname "/USB Hub/")
		(sheetfile "usb_hub.kicad_sch")
		(attr smd)
		(fp_rect
			(start -0.925 -0.47)
			(end 0.925 0.47)
			(stroke
				(width 0.05)
				(type default)
			)
			(fill no)
			(layer "F.CrtYd")
		)
		(fp_line
			(start 0.504 0.248)
			(end -0.494 0.248)
			(stroke
				(width 0.15)
				(type solid)
			)
			(layer "F.Fab")
		)
		(fp_line
			(start 0.504 -0.25)
			(end 0.504 0.248)
			(stroke
				(width 0.15)
				(type solid)
			)
			(layer "F.Fab")
		)
		(fp_line
			(start -0.494 0.248)
			(end -0.494 -0.25)
			(stroke
				(width 0.15)
				(type solid)
			)
			(layer "F.Fab")
		)
		(fp_line
			(start -0.494 -0.25)
			(end 0.504 -0.25)
			(stroke
				(width 0.15)
				(type solid)
			)
			(layer "F.Fab")
		)
		(fp_text user "${REFERENCE}"
			(at -0.939 4.599 0)
			(layer "F.Fab")
			(effects
				(font
					(size 0.7 0.7)
					(thickness 0.15)
				)
				(justify right top)
			)
		)
		(fp_text user "License: Apache-2.0"
			(at -0.939 5.799 0)
			(layer "F.Fab")
			(effects
				(font
					(size 0.7 0.7)
					(thickness 0.15)
				)
				(justify right top)
			)
		)
		(fp_text user "Author: Antmicro"
			(at -0.939 3.399 0)
			(layer "F.Fab")
			(effects
				(font
					(size 0.7 0.7)
					(thickness 0.15)
				)
				(justify right top)
			)
		)
		(pad "1" smd roundrect
			(at -0.48 0 180)
			(size 0.59 0.64)
			(layers "F.Cu" "F.Mask" "F.Paste")
			(roundrect_rratio 0.25)
			(net 78 "/USB Hub/USBC4_CONN_TX1_P")
			(pintype "passive")
		)
		(pad "2" smd roundrect
			(at 0.48 0 180)
			(size 0.59 0.64)
			(layers "F.Cu" "F.Mask" "F.Paste")
			(roundrect_rratio 0.25)
			(net 40 "/USB Hub/USBC4_TX_{1}+")
			(pintype "passive")
		)
	)
	(footprint "antmicro-footprints:R_0402_1005Metric"
		(layer "F.Cu")
		(at 136 106.93)
		(descr "Resistor SMD 0402")
		(tags "resistor SMD 0402")
		(property "Reference" "R344"
			(at -1.4 -0.53 0)
			(layer "F.SilkS")
			(effects
				(font
					(size 0.7 0.7)
					(thickness 0.15)
				)
				(justify left bottom)
			)
		)
		(property "Value" "R_0R_0402"
			(at -1.011843 1.772046 0)
			(layer "F.Fab")
			(effects
				(font
					(size 0.7 0.7)
					(thickness 0.15)
				)
				(justify left bottom)
			)
		)
		(property "Datasheet" "https://industrial.panasonic.com/cdbs/www-data/pdf/RDA0000/AOA0000C301.pdf"
			(at 0 0 0)
			(layer "F.Fab")
			(hide yes)
			(effects
				(font
					(size 1.27 1.27)
					(thickness 0.15)
				)
			)
		)
		(property "Description" "SMD Chip Resistor, Jumper, 0 ohm, 100 mW, 0402 [1005 Metric], Thick Film, General Purpose"
			(at 0 0 0)
			(layer "F.Fab")
			(hide yes)
			(effects
				(font
					(size 1.27 1.27)
					(thickness 0.15)
				)
			)
		)
		(property "Manufacturer" "Panasonic"
			(at 0 0 0)
			(unlocked yes)
			(layer "F.Fab")
			(hide yes)
			(effects
				(font
					(size 1 1)
					(thickness 0.15)
				)
			)
		)
		(property "MPN" "ERJ2GE0R00X"
			(at 0 0 0)
			(unlocked yes)
			(layer "F.Fab")
			(hide yes)
			(effects
				(font
					(size 1 1)
					(thickness 0.15)
				)
			)
		)
		(property "Val" "0R"
			(at 0 0 0)
			(unlocked yes)
			(layer "F.Fab")
			(hide yes)
			(effects
				(font
					(size 1 1)
					(thickness 0.15)
				)
			)
		)
		(property "License" "Apache-2.0"
			(at 0 0 0)
			(unlocked yes)
			(layer "F.Fab")
			(hide yes)
			(effects
				(font
					(size 1 1)
					(thickness 0.15)
				)
			)
		)
		(property "Author" "Antmicro"
			(at 0 0 0)
			(unlocked yes)
			(layer "F.Fab")
			(hide yes)
			(effects
				(font
					(size 1 1)
					(thickness 0.15)
				)
			)
		)
		(property "Tolerance" "~"
			(at 0 0 0)
			(unlocked yes)
			(layer "F.Fab")
			(hide yes)
			(effects
				(font
					(size 1 1)
					(thickness 0.15)
				)
			)
		)
		(property "Current" "1A"
			(at 0 0 0)
			(unlocked yes)
			(layer "F.Fab")
			(hide yes)
			(effects
				(font
					(size 1 1)
					(thickness 0.15)
				)
			)
		)
		(sheetname "/Peripherals/")
		(sheetfile "peripherals.kicad_sch")
		(attr smd)
		(fp_poly
			(pts
				(xy -0.925 -0.47) (xy -0.925 0.47) (xy 0.925 0.47) (xy 0.925 -0.47)
			)
			(stroke
				(width 0.05)
				(type default)
			)
			(fill no)
			(layer "F.CrtYd")
		)
		(fp_poly
			(pts
				(xy -0.5 -0.25) (xy -0.5 0.25) (xy 0.5 0.25) (xy 0.5 -0.25)
			)
			(stroke
				(width 0.15)
				(type solid)
			)
			(fill no)
			(layer "F.Fab")
		)
		(fp_text user "Author: Antmicro"
			(at -0.95 4.169 0)
			(layer "F.Fab")
			(effects
				(font
					(size 0.7 0.7)
					(thickness 0.15)
				)
				(justify left bottom)
			)
		)
		(fp_text user "License: Apache-2.0"
			(at -0.949999 5.169 0)
			(layer "F.Fab")
			(effects
				(font
					(size 0.7 0.7)
					(thickness 0.15)
				)
				(justify left bottom)
			)
		)
		(fp_text user "${REFERENCE}"
			(at -0.95 3.168 0)
			(layer "F.Fab")
			(effects
				(font
					(size 0.7 0.7)
					(thickness 0.15)
				)
				(justify left bottom)
			)
		)
		(pad "1" smd roundrect
			(at -0.48 0)
			(size 0.59 0.64)
			(layers "F.Cu" "F.Mask" "F.Paste")
			(roundrect_rratio 0.25)
			(net 2 "+3V3")
			(pintype "passive")
		)
		(pad "2" smd roundrect
			(at 0.48 0)
			(size 0.59 0.64)
			(layers "F.Cu" "F.Mask" "F.Paste")
			(roundrect_rratio 0.25)
			(net 1310 "Net-(U71-~{RESET})")
			(pintype "passive")
		)
	)
	(footprint "antmicro-footprints:C_0805_2012Metric"
		(layer "F.Cu")
		(at 174.365 126.92 90)
		(descr "Capacitor SMD 0805")
		(tags "capacitor SMD 0805")
		(property "Reference" "C43"
			(at 1.52 -5.665 90)
			(layer "F.SilkS")
			(effects
				(font
					(size 0.7 0.7)
					(thickness 0.15)
				)
				(justify left bottom)
			)
		)
		(property "Value" "C_22u_25V_0805"
			(at -2.055717 1.963152 90)
			(layer "F.Fab")
			(effects
				(font
					(size 0.7 0.7)
					(thickness 0.15)
				)
				(justify left bottom)
			)
		)
		(property "Datasheet" "https://product.samsungsem.com/mlcc/CL21A226MAYNNN.do"
			(at 0 0 90)
			(layer "F.Fab")
			(hide yes)
			(effects
				(font
					(size 1.27 1.27)
					(thickness 0.15)
				)
			)
		)
		(property "Description" "SMT Multilayer Ceramic Capacitor, 22uF, +/-20%, 25V, X5R, 0805 [2012 Metric]"
			(at 0 0 90)
			(layer "F.Fab")
			(hide yes)
			(effects
				(font
					(size 1.27 1.27)
					(thickness 0.15)
				)
			)
		)
		(property "MPN" "CL21A226MAYNNNE"
			(at 0 0 90)
			(unlocked yes)
			(layer "F.Fab")
			(hide yes)
			(effects
				(font
					(size 1 1)
					(thickness 0.15)
				)
			)
		)
		(property "Manufacturer" "Samsung Electro-Mechanics"
			(at 0 0 90)
			(unlocked yes)
			(layer "F.Fab")
			(hide yes)
			(effects
				(font
					(size 1 1)
					(thickness 0.15)
				)
			)
		)
		(property "License" "Apache-2.0"
			(at 0 0 90)
			(unlocked yes)
			(layer "F.Fab")
			(hide yes)
			(effects
				(font
					(size 1 1)
					(thickness 0.15)
				)
			)
		)
		(property "Author" "Antmicro"
			(at 0 0 90)
			(unlocked yes)
			(layer "F.Fab")
			(hide yes)
			(effects
				(font
					(size 1 1)
					(thickness 0.15)
				)
			)
		)
		(property "Val" "22u"
			(at 0 0 90)
			(unlocked yes)
			(layer "F.Fab")
			(hide yes)
			(effects
				(font
					(size 1 1)
					(thickness 0.15)
				)
			)
		)
		(property "Voltage" "25V"
			(at 0 0 90)
			(unlocked yes)
			(layer "F.Fab")
			(hide yes)
			(effects
				(font
					(size 1 1)
					(thickness 0.15)
				)
			)
		)
		(property "Dielectric" "X5R"
			(at 0 0 90)
			(unlocked yes)
			(layer "F.Fab")
			(hide yes)
			(effects
				(font
					(size 1 1)
					(thickness 0.15)
				)
			)
		)
		(property "Public" "False"
			(at 0 0 90)
			(unlocked yes)
			(layer "F.Fab")
			(hide yes)
			(effects
				(font
					(size 1 1)
					(thickness 0.15)
				)
			)
		)
		(sheetname "/DCDC/")
		(sheetfile "dcdc.kicad_sch")
		(attr smd)
		(fp_line
			(start -0.3 -0.7)
			(end 0.3 -0.7)
			(stroke
				(width 0.15)
				(type solid)
			)
			(layer "F.SilkS")
		)
		(fp_line
			(start -0.3 0.7)
			(end 0.3 0.7)
			(stroke
				(width 0.15)
				(type solid)
			)
			(layer "F.SilkS")
		)
		(fp_rect
			(start 1.95 -0.9)
			(end -1.95 0.9)
			(stroke
				(width 0.05)
				(type default)
			)
			(fill no)
			(layer "F.CrtYd")
		)
		(fp_rect
			(start -0.95 -0.675)
			(end 0.95 0.675)
			(stroke
				(width 0.15)
				(type solid)
			)
			(fill no)
			(layer "F.Fab")
		)
		(fp_text user "License: Apache-2.0"
			(at -1.9 4.947 90)
			(layer "F.Fab")
			(effects
				(font
					(size 0.7 0.7)
					(thickness 0.15)
				)
				(justify left bottom)
			)
		)
		(fp_text user "Author: Antmicro"
			(at -1.9 5.947 90)
			(layer "F.Fab")
			(effects
				(font
					(size 0.7 0.7)
					(thickness 0.15)
				)
				(justify left bottom)
			)
		)
		(fp_text user "${REFERENCE}"
			(at -1.9 3.947 90)
			(layer "F.Fab")
			(effects
				(font
					(size 0.7 0.7)
					(thickness 0.15)
				)
				(justify left bottom)
			)
		)
		(pad "1" smd roundrect
			(at -1.1 0 90)
			(size 1.2 1.3)
			(layers "F.Cu" "F.Mask" "F.Paste")
			(roundrect_rratio 0.25)
			(net 1 "GND")
			(pintype "passive")
		)
		(pad "2" smd roundrect
			(at 1.1 0 90)
			(size 1.2 1.3)
			(layers "F.Cu" "F.Mask" "F.Paste")
			(roundrect_rratio 0.25)
			(net 13 "VCC")
			(pintype "passive")
		)
	)
	(footprint "antmicro-footprints:MLP44-24L_4x4x0.75mm"
		(layer "F.Cu")
		(at 181 143)
		(property "Reference" "U8"
			(at -2.7 2.8 90)
			(layer "F.SilkS")
			(effects
				(font
					(size 0.7 0.7)
					(thickness 0.15)
				)
				(justify left bottom)
			)
		)
		(property "Value" "SIC437AED-T1-GE3"
			(at -2.7 3.6 0)
			(layer "F.Fab")
			(effects
				(font
					(size 0.7 0.7)
					(thickness 0.15)
				)
				(justify left bottom)
			)
		)
		(property "Datasheet" "https://www.vishay.com/docs/75921/sic437.pdf"
			(at 0 0 0)
			(layer "F.Fab")
			(hide yes)
			(effects
				(font
					(size 1.27 1.27)
					(thickness 0.15)
				)
			)
		)
		(property "Description" "DC/DC Buck Step Down Regulator Adjustable, 4.5-28V In, 0.6V to 20V/12A Out, 1MHz, PowerPAK MLP44-24"
			(at 0 0 0)
			(layer "F.Fab")
			(hide yes)
			(effects
				(font
					(size 1.27 1.27)
					(thickness 0.15)
				)
			)
		)
		(property "Manufacturer" "Vishay"
			(at 0 0 180)
			(unlocked yes)
			(layer "F.Fab")
			(hide yes)
			(effects
				(font
					(size 1 1)
					(thickness 0.15)
				)
			)
		)
		(property "MPN" "SIC437AED-T1-GE3"
			(at 0 0 180)
			(unlocked yes)
			(layer "F.Fab")
			(hide yes)
			(effects
				(font
					(size 1 1)
					(thickness 0.15)
				)
			)
		)
		(property "Author" "Antmicro"
			(at 0 0 180)
			(unlocked yes)
			(layer "F.Fab")
			(hide yes)
			(effects
				(font
					(size 1 1)
					(thickness 0.15)
				)
			)
		)
		(property "License" "Apache-2.0"
			(at 0 0 180)
			(unlocked yes)
			(layer "F.Fab")
			(hide yes)
			(effects
				(font
					(size 1 1)
					(thickness 0.15)
				)
			)
		)
		(sheetname "/DCDC/")
		(sheetfile "dcdc.kicad_sch")
		(attr smd)
		(net_tie_pad_groups "1,2,26" "3,4,27" "5,6,7,8,9")
		(fp_line
			(start -2.11 -1.38)
			(end -2.11 -2.1)
			(stroke
				(width 0.15)
				(type solid)
			)
			(layer "F.SilkS")
		)
		(fp_line
			(start -2.11 2.11)
			(end -2.11 1.39)
			(stroke
				(width 0.15)
				(type solid)
			)
			(layer "F.SilkS")
		)
		(fp_line
			(start -1.89 -2.1)
			(end -2.11 -2.1)
			(stroke
				(width 0.15)
				(type solid)
			)
			(layer "F.SilkS")
		)
		(fp_line
			(start -1.89 2.11)
			(end -2.11 2.11)
			(stroke
				(width 0.15)
				(type solid)
			)
			(layer "F.SilkS")
		)
		(fp_line
			(start 1.44 2.11)
			(end 2.11 2.11)
			(stroke
				(width 0.15)
				(type solid)
			)
			(layer "F.SilkS")
		)
		(fp_line
			(start 1.89 -2.11)
			(end 2.11 -2.11)
			(stroke
				(width 0.15)
				(type solid)
			)
			(layer "F.SilkS")
		)
		(fp_line
			(start 2.11 -2.11)
			(end 2.11 -1.69)
			(stroke
				(width 0.15)
				(type solid)
			)
			(layer "F.SilkS")
		)
		(fp_line
			(start 2.11 2.11)
			(end 2.11 1.84)
			(stroke
				(width 0.15)
				(type solid)
			)
			(layer "F.SilkS")
		)
		(fp_circle
			(center -2.25 -1.15)
			(end -2.2 -1.15)
			(stroke
				(width 0.15)
				(type solid)
			)
			(fill yes)
			(layer "F.SilkS")
		)
		(fp_line
			(start -2.55 -2.55)
			(end 2.55 -2.55)
			(stroke
				(width 0.05)
				(type solid)
			)
			(layer "F.CrtYd")
		)
		(fp_line
			(start -2.55 2.55)
			(end -2.55 -2.55)
			(stroke
				(width 0.05)
				(type solid)
			)
			(layer "F.CrtYd")
		)
		(fp_line
			(start 2.55 -2.55)
			(end 2.55 2.55)
			(stroke
				(width 0.05)
				(type solid)
			)
			(layer "F.CrtYd")
		)
		(fp_line
			(start 2.55 2.55)
			(end -2.55 2.55)
			(stroke
				(width 0.05)
				(type solid)
			)
			(layer "F.CrtYd")
		)
		(fp_line
			(start -2 -1)
			(end -2 2)
			(stroke
				(width 0.15)
				(type solid)
			)
			(layer "F.Fab")
		)
		(fp_line
			(start -2 2)
			(end 2 2)
			(stroke
				(width 0.15)
				(type solid)
			)
			(layer "F.Fab")
		)
		(fp_line
			(start -1 -2)
			(end -2 -1)
			(stroke
				(width 0.15)
				(type solid)
			)
			(layer "F.Fab")
		)
		(fp_line
			(start 2 -2)
			(end -1 -2)
			(stroke
				(width 0.15)
				(type solid)
			)
			(layer "F.Fab")
		)
		(fp_line
			(start 2 2)
			(end 2 -2)
			(stroke
				(width 0.15)
				(type solid)
			)
			(layer "F.Fab")
		)
		(fp_text user "License: Apache-2.0"
			(at -2.7 5.6 0)
			(layer "F.Fab")
			(effects
				(font
					(size 0.7 0.7)
					(thickness 0.15)
				)
				(justify left bottom)
			)
		)
		(fp_text user "${REFERENCE}"
			(at -2.7 6.8 0)
			(layer "F.Fab")
			(effects
				(font
					(size 0.7 0.7)
					(thickness 0.15)
				)
				(justify left bottom)
			)
		)
		(fp_text user "Author: Antmicro"
			(at -2.7 8 0)
			(layer "F.Fab")
			(effects
				(font
					(size 0.7 0.7)
					(thickness 0.15)
				)
				(justify left bottom)
			)
		)
		(pad "1" smd roundrect
			(at -1.94 -0.825 90)
			(size 0.3 0.725)
			(layers "F.Cu" "F.Mask" "F.Paste")
			(roundrect_rratio 0.25)
			(net 13 "VCC")
			(pinfunction "V_{IN}")
			(pintype "power_in")
		)
		(pad "2" smd roundrect
			(at -1.94 -0.375 90)
			(size 0.3 0.725)
			(layers "F.Cu" "F.Mask" "F.Paste")
			(roundrect_rratio 0.25)
			(net 13 "VCC")
			(pinfunction "V_{IN}")
			(pintype "passive")
		)
		(pad "3" smd roundrect
			(at -1.94 0.525 90)
			(size 0.3 0.725)
			(layers "F.Cu" "F.Mask" "F.Paste")
			(roundrect_rratio 0.25)
			(net 1 "GND")
			(pinfunction "P_{GND}")
			(pintype "passive")
		)
		(pad "4" smd roundrect
			(at -1.94 0.975 90)
			(size 0.3 0.725)
			(layers "F.Cu" "F.Mask" "F.Paste")
			(roundrect_rratio 0.25)
			(net 1 "GND")
			(pinfunction "P_{GND}")
			(pintype "passive")
		)
		(pad "5" smd custom
			(at -1.475 1.94)
			(size 0.3 0.3)
			(layers "F.Cu" "F.Mask" "F.Paste")
			(net 1186 "/DCDC/12V_SW")
			(pinfunction "SW")
			(pintype "passive")
			(options
				(clearance outline)
				(anchor circle)
			)
			(primitives
				(gr_poly
					(pts
						(xy -0.15 -0.2875) (xy -0.144291 -0.316201) (xy -0.128033 -0.340533) (xy -0.103701 -0.356791)
						(xy -0.075 -0.3625) (xy 0.075 -0.3625) (xy 0.103701 -0.356791) (xy 0.128033 -0.340533) (xy 0.144291 -0.316201)
						(xy 0.15 -0.2875) (xy 0.15 0.2875) (xy 0.144291 0.316201) (xy 0.128033 0.340533) (xy 0.103701 0.356791)
						(xy 0.075 0.3625) (xy -0.075 0.3625) (xy -0.103701 0.356791) (xy -0.128033 0.340533) (xy -0.144291 0.316201)
						(xy -0.15 0.2875)
					)
					(width 0)
					(fill yes)
				)
				(gr_poly
					(pts
						(xy -0.15 -0.3625) (xy 2.2 -0.3625) (xy 2.2 -0.0875) (xy -0.15 -0.0875)
					)
					(width 0)
					(fill yes)
				)
			)
		)
		(pad "6" smd roundrect
			(at -1.025 1.94)
			(size 0.3 0.725)
			(layers "F.Cu" "F.Mask" "F.Paste")
			(roundrect_rratio 0.25)
			(net 1186 "/DCDC/12V_SW")
			(pinfunction "SW")
			(pintype "passive")
		)
		(pad "7" smd roundrect
			(at -0.575 1.94)
			(size 0.3 0.725)
			(layers "F.Cu" "F.Mask" "F.Paste")
			(roundrect_rratio 0.25)
			(net 1186 "/DCDC/12V_SW")
			(pinfunction "SW")
			(pintype "passive")
		)
		(pad "8" smd roundrect
			(at 0.125 1.94)
			(size 0.3 0.725)
			(layers "F.Cu" "F.Mask" "F.Paste")
			(roundrect_rratio 0.25)
			(net 1186 "/DCDC/12V_SW")
			(pinfunction "SW")
			(pintype "passive")
		)
		(pad "9" smd roundrect
			(at 0.575 1.94)
			(size 0.3 0.725)
			(layers "F.Cu" "F.Mask" "F.Paste")
			(roundrect_rratio 0.25)
			(net 1186 "/DCDC/12V_SW")
			(pinfunction "SW")
			(pintype "passive")
		)
		(pad "10" smd roundrect
			(at 1.025 1.935)
			(size 0.3 0.725)
			(layers "F.Cu" "F.Mask" "F.Paste")
			(roundrect_rratio 0.25)
			(net 1169 "unconnected-(U8-GL-Pad10)")
			(pinfunction "GL")
			(pintype "passive+no_connect")
		)
		(pad "11" smd roundrect
			(at 1.94 1.425 90)
			(size 0.3 0.725)
			(layers "F.Cu" "F.Mask" "F.Paste")
			(roundrect_rratio 0.25)
			(net 1170 "unconnected-(U8-GL-Pad10)_1")
			(pinfunction "GL")
			(pintype "passive+no_connect")
		)
		(pad "12" smd roundrect
			(at 1.94 0.975 90)
			(size 0.3 0.725)
			(layers "F.Cu" "F.Mask" "F.Paste")
			(roundrect_rratio 0.25)
			(net 578 "/DCDC/12V_VDRV")
			(pinfunction "V_{DRV}")
			(pintype "passive")
		)
		(pad "13" smd roundrect
			(at 1.94 0.525 90)
			(size 0.3 0.725)
			(layers "F.Cu" "F.Mask" "F.Paste")
			(roundrect_rratio 0.25)
			(net 1 "GND")
			(pinfunction "P_{GND}")
			(pintype "power_in")
		)
		(pad "14" smd roundrect
			(at 1.94 0.075 90)
			(size 0.3 0.725)
			(layers "F.Cu" "F.Mask" "F.Paste")
			(roundrect_rratio 0.25)
			(net 1172 "unconnected-(U8-P_{GOOD}-Pad14)")
			(pinfunction "P_{GOOD}")
			(pintype "output+no_connect")
		)
		(pad "15" smd roundrect
			(at 1.94 -0.375 90)
			(size 0.3 0.725)
			(layers "F.Cu" "F.Mask" "F.Paste")
			(roundrect_rratio 0.25)
			(net 20 "/DCDC/12V_VDD")
			(pinfunction "V_{DD}")
			(pintype "passive")
		)
		(pad "16" smd roundrect
			(at 1.94 -0.825 90)
			(size 0.3 0.725)
			(layers "F.Cu" "F.Mask" "F.Paste")
			(roundrect_rratio 0.25)
			(net 1 "GND")
			(pinfunction "A_{GND}")
			(pintype "power_in")
		)
		(pad "17" smd roundrect
			(at 1.94 -1.275 90)
			(size 0.3 0.725)
			(layers "F.Cu" "F.Mask" "F.Paste")
			(roundrect_rratio 0.25)
			(net 1206 "/DCDC/12V_FB")
			(pinfunction "FB")
			(pintype "passive")
		)
		(pad "18" smd roundrect
			(at 1.475 -1.94)
			(size 0.3 0.725)
			(layers "F.Cu" "F.Mask" "F.Paste")
			(roundrect_rratio 0.25)
			(net 880 "/DCDC/12V_OUT")
			(pinfunction "V_{OUT}")
			(pintype "passive")
		)
		(pad "19" smd roundrect
			(at 1.025 -1.94)
			(size 0.3 0.725)
			(layers "F.Cu" "F.Mask" "F.Paste")
			(roundrect_rratio 0.25)
			(net 1293 "/DCDC/CARRIER_PWR_ON")
			(pinfunction "EN")
			(pintype "input")
		)
		(pad "20" smd roundrect
			(at 0.575 -1.94)
			(size 0.3 0.725)
			(layers "F.Cu" "F.Mask" "F.Paste")
			(roundrect_rratio 0.25)
			(net 1205 "/DCDC/12V_MODE2")
			(pinfunction "MODE2")
			(pintype "input")
		)
		(pad "21" smd roundrect
			(at 0.125 -1.94)
			(size 0.3 0.725)
			(layers "F.Cu" "F.Mask" "F.Paste")
			(roundrect_rratio 0.25)
			(net 1204 "/DCDC/12V_MODE1")
			(pinfunction "MODE1")
			(pintype "input")
		)
		(pad "22" smd roundrect
			(at -0.575 -1.94)
			(size 0.3 0.725)
			(layers "F.Cu" "F.Mask" "F.Paste")
			(roundrect_rratio 0.25)
			(net 13 "VCC")
			(pinfunction "V_{IN}")
			(pintype "passive")
		)
		(pad "23" smd roundrect
			(at -1.025 -1.94)
			(size 0.3 0.725)
			(layers "F.Cu" "F.Mask" "F.Paste")
			(roundrect_rratio 0.25)
			(net 585 "/DCDC/12V_BOOT")
			(pinfunction "BOOT")
			(pintype "passive")
		)
		(pad "24" smd roundrect
			(at -1.475 -1.94)
			(size 0.3 0.725)
			(layers "F.Cu" "F.Mask" "F.Paste")
			(roundrect_rratio 0.25)
			(net 879 "/DCDC/12V_PHASE")
			(pinfunction "PHASE")
			(pintype "passive")
		)
		(pad "25" smd rect
			(at 0.49 -0.75 180)
			(size 1.575 1.05)
			(layers "F.Cu" "F.Mask" "F.Paste")
			(net 1 "GND")
			(pinfunction "A_{GND}")
			(pintype "passive")
		)
		(pad "26" smd rect
			(at -1.175 -0.75 180)
			(size 1.15 1.05)
			(layers "F.Cu" "F.Mask" "F.Paste")
			(net 13 "VCC")
			(pinfunction "V_{IN}")
			(pintype "passive")
		)
		(pad "27" smd custom
			(at -0.75 0.775)
			(size 1 1)
			(layers "F.Cu" "F.Mask" "F.Paste")
			(net 1 "GND")
			(pinfunction "P_{GND}")
			(pintype "passive")
			(options
				(clearance outline)
				(anchor rect)
			)
			(primitives
				(gr_poly
					(pts
						(xy -1 0.5) (xy -1 -0.7) (xy 1.825 -0.7) (xy 1.825 -0.245) (xy 1.175 -0.245) (xy 1.175 0.5)
					)
					(width 0)
					(fill yes)
				)
			)
		)
		(pad "28" smd rect
			(at 0.985 0.99 180)
			(size 0.58 0.38)
			(layers "F.Cu" "F.Mask" "F.Paste")
			(net 1171 "unconnected-(U8-GL-Pad10)_2")
			(pinfunction "GL")
			(pintype "passive+no_connect")
		)
	)
	(footprint "antmicro-footprints:C_0805_2012Metric"
		(layer "F.Cu")
		(at 170.725 126.92 90)
		(descr "Capacitor SMD 0805")
		(tags "capacitor SMD 0805")
		(property "Reference" "C268"
			(at 1.52 -4.025 90)
			(layer "F.SilkS")
			(effects
				(font
					(size 0.7 0.7)
					(thickness 0.15)
				)
				(justify left bottom)
			)
		)
		(property "Value" "C_22u_25V_0805"
			(at -2.055717 1.963152 90)
			(layer "F.Fab")
			(effects
				(font
					(size 0.7 0.7)
					(thickness 0.15)
				)
				(justify left bottom)
			)
		)
		(property "Datasheet" "https://product.samsungsem.com/mlcc/CL21A226MAYNNN.do"
			(at 0 0 90)
			(layer "F.Fab")
			(hide yes)
			(effects
				(font
					(size 1.27 1.27)
					(thickness 0.15)
				)
			)
		)
		(property "Description" "SMT Multilayer Ceramic Capacitor, 22uF, +/-20%, 25V, X5R, 0805 [2012 Metric]"
			(at 0 0 90)
			(layer "F.Fab")
			(hide yes)
			(effects
				(font
					(size 1.27 1.27)
					(thickness 0.15)
				)
			)
		)
		(property "MPN" "CL21A226MAYNNNE"
			(at 0 0 90)
			(unlocked yes)
			(layer "F.Fab")
			(hide yes)
			(effects
				(font
					(size 1 1)
					(thickness 0.15)
				)
			)
		)
		(property "Manufacturer" "Samsung Electro-Mechanics"
			(at 0 0 90)
			(unlocked yes)
			(layer "F.Fab")
			(hide yes)
			(effects
				(font
					(size 1 1)
					(thickness 0.15)
				)
			)
		)
		(property "License" "Apache-2.0"
			(at 0 0 90)
			(unlocked yes)
			(layer "F.Fab")
			(hide yes)
			(effects
				(font
					(size 1 1)
					(thickness 0.15)
				)
			)
		)
		(property "Author" "Antmicro"
			(at 0 0 90)
			(unlocked yes)
			(layer "F.Fab")
			(hide yes)
			(effects
				(font
					(size 1 1)
					(thickness 0.15)
				)
			)
		)
		(property "Val" "22u"
			(at 0 0 90)
			(unlocked yes)
			(layer "F.Fab")
			(hide yes)
			(effects
				(font
					(size 1 1)
					(thickness 0.15)
				)
			)
		)
		(property "Voltage" "25V"
			(at 0 0 90)
			(unlocked yes)
			(layer "F.Fab")
			(hide yes)
			(effects
				(font
					(size 1 1)
					(thickness 0.15)
				)
			)
		)
		(property "Dielectric" "X5R"
			(at 0 0 90)
			(unlocked yes)
			(layer "F.Fab")
			(hide yes)
			(effects
				(font
					(size 1 1)
					(thickness 0.15)
				)
			)
		)
		(property "Public" "False"
			(at 0 0 90)
			(unlocked yes)
			(layer "F.Fab")
			(hide yes)
			(effects
				(font
					(size 1 1)
					(thickness 0.15)
				)
			)
		)
		(sheetname "/DCDC/")
		(sheetfile "dcdc.kicad_sch")
		(attr smd)
		(fp_line
			(start -0.3 -0.7)
			(end 0.3 -0.7)
			(stroke
				(width 0.15)
				(type solid)
			)
			(layer "F.SilkS")
		)
		(fp_line
			(start -0.3 0.7)
			(end 0.3 0.7)
			(stroke
				(width 0.15)
				(type solid)
			)
			(layer "F.SilkS")
		)
		(fp_rect
			(start 1.95 -0.9)
			(end -1.95 0.9)
			(stroke
				(width 0.05)
				(type default)
			)
			(fill no)
			(layer "F.CrtYd")
		)
		(fp_rect
			(start -0.95 -0.675)
			(end 0.95 0.675)
			(stroke
				(width 0.15)
				(type solid)
			)
			(fill no)
			(layer "F.Fab")
		)
		(fp_text user "Author: Antmicro"
			(at -1.9 5.947 90)
			(layer "F.Fab")
			(effects
				(font
					(size 0.7 0.7)
					(thickness 0.15)
				)
				(justify left bottom)
			)
		)
		(fp_text user "${REFERENCE}"
			(at -1.9 3.947 90)
			(layer "F.Fab")
			(effects
				(font
					(size 0.7 0.7)
					(thickness 0.15)
				)
				(justify left bottom)
			)
		)
		(fp_text user "License: Apache-2.0"
			(at -1.9 4.947 90)
			(layer "F.Fab")
			(effects
				(font
					(size 0.7 0.7)
					(thickness 0.15)
				)
				(justify left bottom)
			)
		)
		(pad "1" smd roundrect
			(at -1.1 0 90)
			(size 1.2 1.3)
			(layers "F.Cu" "F.Mask" "F.Paste")
			(roundrect_rratio 0.25)
			(net 1 "GND")
			(pintype "passive")
		)
		(pad "2" smd roundrect
			(at 1.1 0 90)
			(size 1.2 1.3)
			(layers "F.Cu" "F.Mask" "F.Paste")
			(roundrect_rratio 0.25)
			(net 13 "VCC")
			(pintype "passive")
		)
	)
	(footprint "antmicro-footprints:C_0603_1608Metric_EIA"
		(layer "F.Cu")
		(at 177.65 130.18 -90)
		(descr "Capacitor SMD 0603, IPC-7351 Density Level A")
		(tags "Capacitor 0603")
		(property "Reference" "C70"
			(at -2.18 9.35 90)
			(layer "F.SilkS")
			(effects
				(font
					(size 0.7 0.7)
					(thickness 0.15)
				)
				(justify left bottom)
			)
		)
		(property "Value" "C_22u_16V_0603"
			(at -1.42757 1.770288 90)
			(layer "F.Fab")
			(effects
				(font
					(size 0.7 0.7)
					(thickness 0.15)
				)
				(justify right top)
			)
		)
		(property "Datasheet" "https://product.samsungsem.com/mlcc/CL10A226MO7JZN.do"
			(at 0 0 90)
			(layer "F.Fab")
			(hide yes)
			(effects
				(font
					(size 1.27 1.27)
					(thickness 0.15)
				)
			)
		)
		(property "Description" "SMD Multilayer Ceramic Capacitor"
			(at 0 0 90)
			(layer "F.Fab")
			(hide yes)
			(effects
				(font
					(size 1.27 1.27)
					(thickness 0.15)
				)
			)
		)
		(property "Manufacturer" "Samsung Electro-Mechanics"
			(at 0 0 270)
			(unlocked yes)
			(layer "F.Fab")
			(hide yes)
			(effects
				(font
					(size 1 1)
					(thickness 0.15)
				)
			)
		)
		(property "MPN" "CL10A226MO7JZNC"
			(at 0 0 270)
			(unlocked yes)
			(layer "F.Fab")
			(hide yes)
			(effects
				(font
					(size 1 1)
					(thickness 0.15)
				)
			)
		)
		(property "Val" "22u"
			(at 0 0 270)
			(unlocked yes)
			(layer "F.Fab")
			(hide yes)
			(effects
				(font
					(size 1 1)
					(thickness 0.15)
				)
			)
		)
		(property "License" "Apache-2.0"
			(at 0 0 270)
			(unlocked yes)
			(layer "F.Fab")
			(hide yes)
			(effects
				(font
					(size 1 1)
					(thickness 0.15)
				)
			)
		)
		(property "Author" "Antmicro"
			(at 0 0 270)
			(unlocked yes)
			(layer "F.Fab")
			(hide yes)
			(effects
				(font
					(size 1 1)
					(thickness 0.15)
				)
			)
		)
		(property "Voltage" "16V"
			(at 0 0 270)
			(unlocked yes)
			(layer "F.Fab")
			(hide yes)
			(effects
				(font
					(size 1 1)
					(thickness 0.15)
				)
			)
		)
		(property "Dielectric" ""
			(at 0 0 270)
			(unlocked yes)
			(layer "F.Fab")
			(hide yes)
			(effects
				(font
					(size 1 1)
					(thickness 0.15)
				)
			)
		)
		(sheetname "/DCDC/")
		(sheetfile "dcdc.kicad_sch")
		(attr smd)
		(fp_line
			(start -0.15 0.55)
			(end 0.15 0.55)
			(stroke
				(width 0.15)
				(type solid)
			)
			(layer "F.SilkS")
		)
		(fp_line
			(start -0.15 -0.55)
			(end 0.15 -0.55)
			(stroke
				(width 0.15)
				(type solid)
			)
			(layer "F.SilkS")
		)
		(fp_rect
			(start -1.25 -0.65)
			(end 1.25 0.65)
			(stroke
				(width 0.05)
				(type solid)
			)
			(fill no)
			(layer "F.CrtYd")
		)
		(fp_rect
			(start -0.8 -0.45)
			(end 0.8 0.45)
			(stroke
				(width 0.15)
				(type solid)
			)
			(fill no)
			(layer "F.Fab")
		)
		(fp_text user "${REFERENCE}"
			(at -1.682 3.895 90)
			(layer "F.Fab")
			(effects
				(font
					(size 0.7 0.7)
					(thickness 0.15)
				)
				(justify right top)
			)
		)
		(fp_text user "Author: Antmicro"
			(at -1.682 4.894 90)
			(layer "F.Fab")
			(effects
				(font
					(size 0.7 0.7)
					(thickness 0.15)
				)
				(justify right top)
			)
		)
		(fp_text user "License: Apache-2.0"
			(at -1.682 5.895 90)
			(layer "F.Fab")
			(effects
				(font
					(size 0.7 0.7)
					(thickness 0.15)
				)
				(justify right top)
			)
		)
		(pad "1" smd roundrect
			(at -0.7 0 270)
			(size 0.8 1.1)
			(layers "F.Cu" "F.Mask" "F.Paste")
			(roundrect_rratio 0.2)
			(net 1 "GND")
			(pintype "passive")
		)
		(pad "2" smd roundrect
			(at 0.7 0 270)
			(size 0.8 1.1)
			(layers "F.Cu" "F.Mask" "F.Paste")
			(roundrect_rratio 0.2)
			(net 567 "/DCDC/3V3_OUT")
			(pintype "passive")
		)
	)
	(footprint "antmicro-footprints:R_0402_1005Metric"
		(layer "F.Cu")
		(at 156.6 120.4 180)
		(descr "Resistor SMD 0402")
		(tags "resistor SMD 0402")
		(property "Reference" "R357"
			(at -3.6 0.4 0)
			(layer "F.SilkS")
			(effects
				(font
					(size 0.7 0.7)
					(thickness 0.15)
				)
				(justify right top)
			)
		)
		(property "Value" "R_2k2_0402"
			(at -1.011843 1.772047 0)
			(layer "F.Fab")
			(effects
				(font
					(size 0.7 0.7)
					(thickness 0.15)
				)
				(justify right top)
			)
		)
		(property "Datasheet" "https://www.bourns.com/docs/product-datasheets/cr.pdf"
			(at 0 0 0)
			(layer "F.Fab")
			(hide yes)
			(effects
				(font
					(size 1.27 1.27)
					(thickness 0.15)
				)
			)
		)
		(property "Description" "SMD Chip Resistor, 2.2 kohm, ± 1%, 62.5 mW, 0402 [1005 Metric], Thick Film, General Purpose"
			(at 0 0 0)
			(layer "F.Fab")
			(hide yes)
			(effects
				(font
					(size 1.27 1.27)
					(thickness 0.15)
				)
			)
		)
		(property "MPN" "CR0402-FX-2201GLF"
			(at 0 0 180)
			(unlocked yes)
			(layer "F.Fab")
			(hide yes)
			(effects
				(font
					(size 1 1)
					(thickness 0.15)
				)
			)
		)
		(property "Manufacturer" "Bourns"
			(at 0 0 180)
			(unlocked yes)
			(layer "F.Fab")
			(hide yes)
			(effects
				(font
					(size 1 1)
					(thickness 0.15)
				)
			)
		)
		(property "License" "Apache-2.0"
			(at 0 0 180)
			(unlocked yes)
			(layer "F.Fab")
			(hide yes)
			(effects
				(font
					(size 1 1)
					(thickness 0.15)
				)
			)
		)
		(property "Author" "Antmicro"
			(at 0 0 180)
			(unlocked yes)
			(layer "F.Fab")
			(hide yes)
			(effects
				(font
					(size 1 1)
					(thickness 0.15)
				)
			)
		)
		(property "Val" "2k2"
			(at 0 0 180)
			(unlocked yes)
			(layer "F.Fab")
			(hide yes)
			(effects
				(font
					(size 1 1)
					(thickness 0.15)
				)
			)
		)
		(property "Tolerance" "1%"
			(at 0 0 180)
			(unlocked yes)
			(layer "F.Fab")
			(hide yes)
			(effects
				(font
					(size 1 1)
					(thickness 0.15)
				)
			)
		)
		(sheetname "/SoM_IO/")
		(sheetfile "som_io.kicad_sch")
		(attr smd exclude_from_pos_files exclude_from_bom dnp)
		(fp_rect
			(start -0.925 -0.47)
			(end 0.925 0.47)
			(stroke
				(width 0.05)
				(type default)
			)
			(fill no)
			(layer "F.CrtYd")
		)
		(fp_rect
			(start -0.5 -0.25)
			(end 0.5 0.25)
			(stroke
				(width 0.15)
				(type solid)
			)
			(fill no)
			(layer "F.Fab")
		)
		(fp_text user "License: Apache-2.0"
			(at -0.95 5.169 0)
			(layer "F.Fab")
			(effects
				(font
					(size 0.7 0.7)
					(thickness 0.15)
				)
				(justify right top)
			)
		)
		(fp_text user "Author: Antmicro"
			(at -0.95 4.169 0)
			(layer "F.Fab")
			(effects
				(font
					(size 0.7 0.7)
					(thickness 0.15)
				)
				(justify right top)
			)
		)
		(fp_text user "${REFERENCE}"
			(at -0.95 3.168 0)
			(layer "F.Fab")
			(effects
				(font
					(size 0.7 0.7)
					(thickness 0.15)
				)
				(justify right top)
			)
		)
		(pad "1" smd roundrect
			(at -0.48 0 180)
			(size 0.59 0.64)
			(layers "F.Cu" "F.Mask" "F.Paste")
			(roundrect_rratio 0.25)
			(net 11 "+1V8")
			(pintype "passive")
		)
		(pad "2" smd roundrect
			(at 0.48 0 180)
			(size 0.59 0.64)
			(layers "F.Cu" "F.Mask" "F.Paste")
			(roundrect_rratio 0.25)
			(net 317 "/SoM_IO/I2C0_SCL_1V8")
			(pintype "passive")
		)
	)
	(footprint "antmicro-footprints:C_0805_2012Metric"
		(layer "F.Cu")
		(at 170.57 110.366 90)
		(descr "Capacitor SMD 0805")
		(tags "capacitor SMD 0805")
		(property "Reference" "C271"
			(at 1.69 0.49 90)
			(layer "F.SilkS")
			(effects
				(font
					(size 0.7 0.7)
					(thickness 0.15)
				)
				(justify left bottom)
			)
		)
		(property "Value" "C_22u_25V_0805"
			(at -2.055717 1.963152 90)
			(layer "F.Fab")
			(effects
				(font
					(size 0.7 0.7)
					(thickness 0.15)
				)
				(justify left bottom)
			)
		)
		(property "Datasheet" "https://product.samsungsem.com/mlcc/CL21A226MAYNNN.do"
			(at 0 0 90)
			(layer "F.Fab")
			(hide yes)
			(effects
				(font
					(size 1.27 1.27)
					(thickness 0.15)
				)
			)
		)
		(property "Description" "SMT Multilayer Ceramic Capacitor, 22uF, +/-20%, 25V, X5R, 0805 [2012 Metric]"
			(at 0 0 90)
			(layer "F.Fab")
			(hide yes)
			(effects
				(font
					(size 1.27 1.27)
					(thickness 0.15)
				)
			)
		)
		(property "MPN" "CL21A226MAYNNNE"
			(at 0 0 90)
			(unlocked yes)
			(layer "F.Fab")
			(hide yes)
			(effects
				(font
					(size 1 1)
					(thickness 0.15)
				)
			)
		)
		(property "Manufacturer" "Samsung Electro-Mechanics"
			(at 0 0 90)
			(unlocked yes)
			(layer "F.Fab")
			(hide yes)
			(effects
				(font
					(size 1 1)
					(thickness 0.15)
				)
			)
		)
		(property "License" "Apache-2.0"
			(at 0 0 90)
			(unlocked yes)
			(layer "F.Fab")
			(hide yes)
			(effects
				(font
					(size 1 1)
					(thickness 0.15)
				)
			)
		)
		(property "Author" "Antmicro"
			(at 0 0 90)
			(unlocked yes)
			(layer "F.Fab")
			(hide yes)
			(effects
				(font
					(size 1 1)
					(thickness 0.15)
				)
			)
		)
		(property "Val" "22u"
			(at 0 0 90)
			(unlocked yes)
			(layer "F.Fab")
			(hide yes)
			(effects
				(font
					(size 1 1)
					(thickness 0.15)
				)
			)
		)
		(property "Voltage" "25V"
			(at 0 0 90)
			(unlocked yes)
			(layer "F.Fab")
			(hide yes)
			(effects
				(font
					(size 1 1)
					(thickness 0.15)
				)
			)
		)
		(property "Dielectric" "X5R"
			(at 0 0 90)
			(unlocked yes)
			(layer "F.Fab")
			(hide yes)
			(effects
				(font
					(size 1 1)
					(thickness 0.15)
				)
			)
		)
		(property "Public" "False"
			(at 0 0 90)
			(unlocked yes)
			(layer "F.Fab")
			(hide yes)
			(effects
				(font
					(size 1 1)
					(thickness 0.15)
				)
			)
		)
		(sheetname "/DCDC/")
		(sheetfile "dcdc.kicad_sch")
		(attr smd)
		(fp_line
			(start -0.3 -0.7)
			(end 0.3 -0.7)
			(stroke
				(width 0.15)
				(type solid)
			)
			(layer "F.SilkS")
		)
		(fp_line
			(start -0.3 0.7)
			(end 0.3 0.7)
			(stroke
				(width 0.15)
				(type solid)
			)
			(layer "F.SilkS")
		)
		(fp_rect
			(start 1.95 -0.9)
			(end -1.95 0.9)
			(stroke
				(width 0.05)
				(type default)
			)
			(fill no)
			(layer "F.CrtYd")
		)
		(fp_rect
			(start -0.95 -0.675)
			(end 0.95 0.675)
			(stroke
				(width 0.15)
				(type solid)
			)
			(fill no)
			(layer "F.Fab")
		)
		(fp_text user "License: Apache-2.0"
			(at -1.9 4.947 90)
			(layer "F.Fab")
			(effects
				(font
					(size 0.7 0.7)
					(thickness 0.15)
				)
				(justify left bottom)
			)
		)
		(fp_text user "${REFERENCE}"
			(at -1.9 3.947 90)
			(layer "F.Fab")
			(effects
				(font
					(size 0.7 0.7)
					(thickness 0.15)
				)
				(justify left bottom)
			)
		)
		(fp_text user "Author: Antmicro"
			(at -1.9 5.947 90)
			(layer "F.Fab")
			(effects
				(font
					(size 0.7 0.7)
					(thickness 0.15)
				)
				(justify left bottom)
			)
		)
		(pad "1" smd roundrect
			(at -1.1 0 90)
			(size 1.2 1.3)
			(layers "F.Cu" "F.Mask" "F.Paste")
			(roundrect_rratio 0.25)
			(net 1 "GND")
			(pintype "passive")
		)
		(pad "2" smd roundrect
			(at 1.1 0 90)
			(size 1.2 1.3)
			(layers "F.Cu" "F.Mask" "F.Paste")
			(roundrect_rratio 0.25)
			(net 13 "VCC")
			(pintype "passive")
		)
	)
	(footprint "antmicro-footprints:C_0402_1005Metric"
		(layer "F.Cu")
		(at 151.499998 96.000001)
		(descr "Capacitor SMD 0402")
		(tags "capacitor SMD 0402")
		(property "Reference" "C354"
			(at -1.899998 -0.600001 0)
			(layer "F.SilkS")
			(effects
				(font
					(size 0.7 0.7)
					(thickness 0.15)
				)
				(justify left bottom)
			)
		)
		(property "Value" "C_100n_0402"
			(at -1.022927 2.155213 0)
			(layer "F.Fab")
			(effects
				(font
					(size 0.7 0.7)
					(thickness 0.15)
				)
				(justify left bottom)
			)
		)
		(property "Datasheet" "https://www.murata.com/products/productdetail?partno=GRM155R61H104KE14%23"
			(at 0 0 0)
			(layer "F.Fab")
			(hide yes)
			(effects
				(font
					(size 1.27 1.27)
					(thickness 0.15)
				)
			)
		)
		(property "Description" "SMD Multilayer Ceramic Capacitor, 0.1 µF, 50 V, 0402 [1005 Metric], ± 10%, X5R, GRM Series"
			(at 0 0 0)
			(layer "F.Fab")
			(hide yes)
			(effects
				(font
					(size 1.27 1.27)
					(thickness 0.15)
				)
			)
		)
		(property "Manufacturer" "Murata"
			(at 0 0 0)
			(unlocked yes)
			(layer "F.Fab")
			(hide yes)
			(effects
				(font
					(size 1 1)
					(thickness 0.15)
				)
			)
		)
		(property "MPN" "GRM155R61H104KE14D"
			(at 0 0 0)
			(unlocked yes)
			(layer "F.Fab")
			(hide yes)
			(effects
				(font
					(size 1 1)
					(thickness 0.15)
				)
			)
		)
		(property "Val" "100n"
			(at 0 0 0)
			(unlocked yes)
			(layer "F.Fab")
			(hide yes)
			(effects
				(font
					(size 1 1)
					(thickness 0.15)
				)
			)
		)
		(property "License" "Apache-2.0"
			(at 0 0 0)
			(unlocked yes)
			(layer "F.Fab")
			(hide yes)
			(effects
				(font
					(size 1 1)
					(thickness 0.15)
				)
			)
		)
		(property "Author" "Antmicro"
			(at 0 0 0)
			(unlocked yes)
			(layer "F.Fab")
			(hide yes)
			(effects
				(font
					(size 1 1)
					(thickness 0.15)
				)
			)
		)
		(property "Voltage" "50V"
			(at 0 0 0)
			(unlocked yes)
			(layer "F.Fab")
			(hide yes)
			(effects
				(font
					(size 1 1)
					(thickness 0.15)
				)
			)
		)
		(property "Dielectric" "X5R"
			(at 0 0 0)
			(unlocked yes)
			(layer "F.Fab")
			(hide yes)
			(effects
				(font
					(size 1 1)
					(thickness 0.15)
				)
			)
		)
		(sheetname "/SoM_IO/")
		(sheetfile "som_io.kicad_sch")
		(attr smd)
		(fp_poly
			(pts
				(xy -0.925 -0.47) (xy 0.925 -0.47) (xy 0.925 0.47) (xy -0.925 0.47)
			)
			(stroke
				(width 0.05)
				(type default)
			)
			(fill no)
			(layer "F.CrtYd")
		)
		(fp_line
			(start -0.494 -0.25)
			(end 0.504 -0.25)
			(stroke
				(width 0.15)
				(type solid)
			)
			(layer "F.Fab")
		)
		(fp_line
			(start -0.494 0.248)
			(end -0.494 -0.25)
			(stroke
				(width 0.15)
				(type solid)
			)
			(layer "F.Fab")
		)
		(fp_line
			(start 0.504 -0.25)
			(end 0.504 0.248)
			(stroke
				(width 0.15)
				(type solid)
			)
			(layer "F.Fab")
		)
		(fp_line
			(start 0.504 0.248)
			(end -0.494 0.248)
			(stroke
				(width 0.15)
				(type solid)
			)
			(layer "F.Fab")
		)
		(fp_text user "Author: Antmicro"
			(at -0.939 3.399 0)
			(layer "F.Fab")
			(effects
				(font
					(size 0.7 0.7)
					(thickness 0.15)
				)
				(justify left bottom)
			)
		)
		(fp_text user "${REFERENCE}"
			(at -0.939 4.599 0)
			(layer "F.Fab")
			(effects
				(font
					(size 0.7 0.7)
					(thickness 0.15)
				)
				(justify left bottom)
			)
		)
		(fp_text user "License: Apache-2.0"
			(at -0.939 5.799 0)
			(layer "F.Fab")
			(effects
				(font
					(size 0.7 0.7)
					(thickness 0.15)
				)
				(justify left bottom)
			)
		)
		(pad "1" smd roundrect
			(at -0.48 0)
			(size 0.59 0.64)
			(layers "F.Cu" "F.Mask" "F.Paste")
			(roundrect_rratio 0.25)
			(net 1 "GND")
			(pintype "passive")
		)
		(pad "2" smd roundrect
			(at 0.48 0)
			(size 0.59 0.64)
			(layers "F.Cu" "F.Mask" "F.Paste")
			(roundrect_rratio 0.25)
			(net 11 "+1V8")
			(pintype "passive")
		)
	)
	(footprint "antmicro-footprints:R_0402_1005Metric"
		(layer "F.Cu")
		(at 94 62.5)
		(descr "Resistor SMD 0402")
		(tags "resistor SMD 0402")
		(property "Reference" "R14"
			(at 6.9 1.5 0)
			(layer "F.SilkS")
			(effects
				(font
					(size 0.7 0.7)
					(thickness 0.15)
				)
				(justify left bottom)
			)
		)
		(property "Value" "R_10k_0402"
			(at -1.011843 1.772046 0)
			(layer "F.Fab")
			(effects
				(font
					(size 0.7 0.7)
					(thickness 0.15)
				)
				(justify left bottom)
			)
		)
		(property "Datasheet" "https://www.bourns.com/docs/product-datasheets/cr.pdf"
			(at 0 0 0)
			(layer "F.Fab")
			(hide yes)
			(effects
				(font
					(size 1.27 1.27)
					(thickness 0.15)
				)
			)
		)
		(property "Description" "SMD Chip Resistor, 10 kohm, ± 1%, 62.5 mW, 0402 [1005 Metric], Thick Film, General Purpose"
			(at 0 0 0)
			(layer "F.Fab")
			(hide yes)
			(effects
				(font
					(size 1.27 1.27)
					(thickness 0.15)
				)
			)
		)
		(property "MPN" "CR0402-FX-1002GLF"
			(at 0 0 0)
			(unlocked yes)
			(layer "F.Fab")
			(hide yes)
			(effects
				(font
					(size 1 1)
					(thickness 0.15)
				)
			)
		)
		(property "Manufacturer" "Bourns"
			(at 0 0 0)
			(unlocked yes)
			(layer "F.Fab")
			(hide yes)
			(effects
				(font
					(size 1 1)
					(thickness 0.15)
				)
			)
		)
		(property "License" "Apache-2.0"
			(at 0 0 0)
			(unlocked yes)
			(layer "F.Fab")
			(hide yes)
			(effects
				(font
					(size 1 1)
					(thickness 0.15)
				)
			)
		)
		(property "Author" "Antmicro"
			(at 0 0 0)
			(unlocked yes)
			(layer "F.Fab")
			(hide yes)
			(effects
				(font
					(size 1 1)
					(thickness 0.15)
				)
			)
		)
		(property "Val" "10k"
			(at 0 0 0)
			(unlocked yes)
			(layer "F.Fab")
			(hide yes)
			(effects
				(font
					(size 1 1)
					(thickness 0.15)
				)
			)
		)
		(property "Tolerance" "1%"
			(at 0 0 0)
			(unlocked yes)
			(layer "F.Fab")
			(hide yes)
			(effects
				(font
					(size 1 1)
					(thickness 0.15)
				)
			)
		)
		(sheetname "/SoM_Power/")
		(sheetfile "som_power.kicad_sch")
		(attr smd)
		(fp_poly
			(pts
				(xy -0.925 -0.47) (xy -0.925 0.47) (xy 0.925 0.47) (xy 0.925 -0.47)
			)
			(stroke
				(width 0.05)
				(type default)
			)
			(fill no)
			(layer "F.CrtYd")
		)
		(fp_poly
			(pts
				(xy -0.5 -0.25) (xy -0.5 0.25) (xy 0.5 0.25) (xy 0.5 -0.25)
			)
			(stroke
				(width 0.15)
				(type solid)
			)
			(fill no)
			(layer "F.Fab")
		)
		(fp_text user "Author: Antmicro"
			(at -0.95 4.169 0)
			(layer "F.Fab")
			(effects
				(font
					(size 0.7 0.7)
					(thickness 0.15)
				)
				(justify left bottom)
			)
		)
		(fp_text user "License: Apache-2.0"
			(at -0.949999 5.169 0)
			(layer "F.Fab")
			(effects
				(font
					(size 0.7 0.7)
					(thickness 0.15)
				)
				(justify left bottom)
			)
		)
		(fp_text user "${REFERENCE}"
			(at -0.95 3.168 0)
			(layer "F.Fab")
			(effects
				(font
					(size 0.7 0.7)
					(thickness 0.15)
				)
				(justify left bottom)
			)
		)
		(pad "1" smd roundrect
			(at -0.48 0)
			(size 0.59 0.64)
			(layers "F.Cu" "F.Mask" "F.Paste")
			(roundrect_rratio 0.25)
			(net 1287 "/SoM_Power/MODULE_POWER_ON")
			(pintype "passive")
		)
		(pad "2" smd roundrect
			(at 0.48 0)
			(size 0.59 0.64)
			(layers "F.Cu" "F.Mask" "F.Paste")
			(roundrect_rratio 0.25)
			(net 4 "+3V3_AON")
			(pintype "passive")
		)
	)
	(footprint "antmicro-footprints:LED_0603_1608Metric_G"
		(layer "F.Cu")
		(at 190.676 140.1 180)
		(descr "LED SMD 0603 Green")
		(tags "LED SMD 0603 Green")
		(property "Reference" "D14"
			(at -0.95 1.6 0)
			(layer "F.SilkS")
			(effects
				(font
					(size 0.7 0.7)
					(thickness 0.15)
				)
				(justify right top)
			)
		)
		(property "Value" "LED_G_0603_LTST-C190GKT"
			(at -0.001 1.599 0)
			(layer "F.Fab")
			(effects
				(font
					(size 0.7 0.7)
					(thickness 0.15)
				)
				(justify right top)
			)
		)
		(property "Datasheet" "https://media.digikey.com/pdf/Data%20Sheets/Lite-On%20PDFs/LTST-C190GKT.pdf"
			(at 0 0 0)
			(layer "F.Fab")
			(hide yes)
			(effects
				(font
					(size 1.27 1.27)
					(thickness 0.15)
				)
			)
		)
		(property "Description" "LED, Green, SMD, 0603, 20 mA, 2.1 V, 569 nm"
			(at 0 0 0)
			(layer "F.Fab")
			(hide yes)
			(effects
				(font
					(size 1.27 1.27)
					(thickness 0.15)
				)
			)
		)
		(property "MPN" "LTST-C190GKT"
			(at 0 0 180)
			(unlocked yes)
			(layer "F.Fab")
			(hide yes)
			(effects
				(font
					(size 1 1)
					(thickness 0.15)
				)
			)
		)
		(property "Manufacturer" "Lite-On"
			(at 0 0 180)
			(unlocked yes)
			(layer "F.Fab")
			(hide yes)
			(effects
				(font
					(size 1 1)
					(thickness 0.15)
				)
			)
		)
		(property "Author" "Antmicro"
			(at 0 0 180)
			(unlocked yes)
			(layer "F.Fab")
			(hide yes)
			(effects
				(font
					(size 1 1)
					(thickness 0.15)
				)
			)
		)
		(property "License" "Apache-2.0"
			(at 0 0 180)
			(unlocked yes)
			(layer "F.Fab")
			(hide yes)
			(effects
				(font
					(size 1 1)
					(thickness 0.15)
				)
			)
		)
		(property "Color" "Green"
			(at 0 0 180)
			(unlocked yes)
			(layer "F.Fab")
			(hide yes)
			(effects
				(font
					(size 1 1)
					(thickness 0.15)
				)
			)
		)
		(sheetname "/SFP/")
		(sheetfile "sfp.kicad_sch")
		(attr smd)
		(fp_line
			(start 0.22 0.35)
			(end -0.22 0.35)
			(stroke
				(width 0.15)
				(type solid)
			)
			(layer "F.SilkS")
		)
		(fp_line
			(start 0.22 -0.35)
			(end -0.22 -0.35)
			(stroke
				(width 0.15)
				(type solid)
			)
			(layer "F.SilkS")
		)
		(fp_line
			(start 0.105328 0.201008)
			(end 0.105329 -0.198992)
			(stroke
				(width 0.1)
				(type solid)
			)
			(layer "F.SilkS")
		)
		(fp_line
			(start 0.105328 0.201008)
			(end -0.094672 0.001008)
			(stroke
				(width 0.1)
				(type solid)
			)
			(layer "F.SilkS")
		)
		(fp_line
			(start 0.105328 0.001008)
			(end 0.240001 0.001)
			(stroke
				(width 0.1)
				(type solid)
			)
			(layer "F.SilkS")
		)
		(fp_line
			(start -0.094672 0.201008)
			(end -0.094672 -0.198992)
			(stroke
				(width 0.1)
				(type solid)
			)
			(layer "F.SilkS")
		)
		(fp_line
			(start -0.094672 0.001008)
			(end 0.105329 -0.198992)
			(stroke
				(width 0.1)
				(type solid)
			)
			(layer "F.SilkS")
		)
		(fp_line
			(start -0.094672 0.001008)
			(end -0.24 0.001008)
			(stroke
				(width 0.1)
				(type solid)
			)
			(layer "F.SilkS")
		)
		(fp_line
			(start -1.18 -0.319)
			(end -1.18 0.321)
			(stroke
				(width 0.15)
				(type solid)
			)
			(layer "F.SilkS")
		)
		(fp_poly
			(pts
				(xy 1.25 0.65) (xy -1.25 0.65) (xy -1.25 -0.65) (xy 1.25 -0.65)
			)
			(stroke
				(width 0.05)
				(type solid)
			)
			(fill no)
			(layer "F.CrtYd")
		)
		(fp_line
			(start 0.599 0)
			(end 0.200999 0)
			(stroke
				(width 0.15)
				(type solid)
			)
			(layer "F.Fab")
		)
		(fp_line
			(start 0.201 0.2)
			(end 0.200999 0)
			(stroke
				(width 0.15)
				(type solid)
			)
			(layer "F.Fab")
		)
		(fp_line
			(start 0.201 -0.202)
			(end -0.101 0)
			(stroke
				(width 0.15)
				(type solid)
			)
			(layer "F.Fab")
		)
		(fp_line
			(start 0.200999 0)
			(end 0.201 -0.202)
			(stroke
				(width 0.15)
				(type solid)
			)
			(layer "F.Fab")
		)
		(fp_line
			(start -0.101 0)
			(end 0.201 0.2)
			(stroke
				(width 0.15)
				(type solid)
			)
			(layer "F.Fab")
		)
		(fp_line
			(start -0.199 0.2)
			(end -0.199 0.1)
			(stroke
				(width 0.15)
				(type solid)
			)
			(layer "F.Fab")
		)
		(fp_line
			(start -0.199 0)
			(end -0.597 0)
			(stroke
				(width 0.15)
				(type solid)
			)
			(layer "F.Fab")
		)
		(fp_line
			(start -0.199 -0.202)
			(end -0.199 0.1)
			(stroke
				(width 0.15)
				(type solid)
			)
			(layer "F.Fab")
		)
		(fp_poly
			(pts
				(xy 0.848 0.4) (xy -0.85 0.4) (xy -0.85 -0.402) (xy 0.848 -0.401999)
			)
			(stroke
				(width 0.15)
				(type solid)
			)
			(fill no)
			(layer "F.Fab")
		)
		(fp_text user "Author: Antmicro"
			(at -1.4224 4.799 0)
			(layer "F.Fab")
			(effects
				(font
					(size 0.7 0.7)
					(thickness 0.15)
				)
				(justify right top)
			)
		)
		(fp_text user "${REFERENCE}"
			(at -1.4224 5.999 0)
			(layer "F.Fab")
			(effects
				(font
					(size 0.7 0.7)
					(thickness 0.15)
				)
				(justify right top)
			)
		)
		(fp_text user "License: Apache-2.0"
			(at -1.4224 3.599 0)
			(layer "F.Fab")
			(effects
				(font
					(size 0.7 0.7)
					(thickness 0.15)
				)
				(justify right top)
			)
		)
		(pad "1" smd roundrect
			(at -0.7 0)
			(size 0.8 1)
			(layers "F.Cu" "F.Mask" "F.Paste")
			(roundrect_rratio 0.2)
			(net 530 "Net-(D14-C)")
			(pinfunction "C")
			(pintype "passive")
		)
		(pad "2" smd roundrect
			(at 0.7 0)
			(size 0.8 1)
			(layers "F.Cu" "F.Mask" "F.Paste")
			(roundrect_rratio 0.2)
			(net 2 "+3V3")
			(pinfunction "A")
			(pintype "passive")
		)
	)
	(footprint "antmicro-footprints:C_0402_1005Metric"
		(layer "F.Cu")
		(at 203.1 117.9 -90)
		(descr "Capacitor SMD 0402")
		(tags "capacitor SMD 0402")
		(property "Reference" "C94"
			(at -3 0.4 90)
			(layer "F.SilkS")
			(effects
				(font
					(size 0.7 0.7)
					(thickness 0.15)
				)
				(justify right top)
			)
		)
		(property "Value" "C_100n_0402"
			(at -1.022927 2.155213 90)
			(layer "F.Fab")
			(effects
				(font
					(size 0.7 0.7)
					(thickness 0.15)
				)
				(justify right top)
			)
		)
		(property "Datasheet" "https://www.murata.com/products/productdetail?partno=GRM155R61H104KE14%23"
			(at 0 0 90)
			(layer "F.Fab")
			(hide yes)
			(effects
				(font
					(size 1.27 1.27)
					(thickness 0.15)
				)
			)
		)
		(property "Description" "SMD Multilayer Ceramic Capacitor, 0.1 µF, 50 V, 0402 [1005 Metric], ± 10%, X5R, GRM Series"
			(at 0 0 90)
			(layer "F.Fab")
			(hide yes)
			(effects
				(font
					(size 1.27 1.27)
					(thickness 0.15)
				)
			)
		)
		(property "MPN" "GRM155R61H104KE14D"
			(at 0 0 270)
			(unlocked yes)
			(layer "F.Fab")
			(hide yes)
			(effects
				(font
					(size 1 1)
					(thickness 0.15)
				)
			)
		)
		(property "Val" "100n"
			(at 0 0 270)
			(unlocked yes)
			(layer "F.Fab")
			(hide yes)
			(effects
				(font
					(size 1 1)
					(thickness 0.15)
				)
			)
		)
		(property "Voltage" "50V"
			(at 0 0 270)
			(unlocked yes)
			(layer "F.Fab")
			(hide yes)
			(effects
				(font
					(size 1 1)
					(thickness 0.15)
				)
			)
		)
		(property "Dielectric" "X5R"
			(at 0 0 270)
			(unlocked yes)
			(layer "F.Fab")
			(hide yes)
			(effects
				(font
					(size 1 1)
					(thickness 0.15)
				)
			)
		)
		(property "Manufacturer" "Murata"
			(at 0 0 270)
			(unlocked yes)
			(layer "F.Fab")
			(hide yes)
			(effects
				(font
					(size 1 1)
					(thickness 0.15)
				)
			)
		)
		(property "License" "Apache-2.0"
			(at 0 0 270)
			(unlocked yes)
			(layer "F.Fab")
			(hide yes)
			(effects
				(font
					(size 1 1)
					(thickness 0.15)
				)
			)
		)
		(property "Author" "Antmicro"
			(at 0 0 270)
			(unlocked yes)
			(layer "F.Fab")
			(hide yes)
			(effects
				(font
					(size 1 1)
					(thickness 0.15)
				)
			)
		)
		(sheetname "/USB Hub/")
		(sheetfile "usb_hub.kicad_sch")
		(attr smd)
		(fp_poly
			(pts
				(xy -0.925 -0.47) (xy 0.925 -0.47) (xy 0.925 0.47) (xy -0.925 0.47)
			)
			(stroke
				(width 0.05)
				(type default)
			)
			(fill no)
			(layer "F.CrtYd")
		)
		(fp_line
			(start -0.494 0.248)
			(end -0.494 -0.25)
			(stroke
				(width 0.15)
				(type solid)
			)
			(layer "F.Fab")
		)
		(fp_line
			(start 0.504 0.248)
			(end -0.494 0.248)
			(stroke
				(width 0.15)
				(type solid)
			)
			(layer "F.Fab")
		)
		(fp_line
			(start -0.494 -0.25)
			(end 0.504 -0.25)
			(stroke
				(width 0.15)
				(type solid)
			)
			(layer "F.Fab")
		)
		(fp_line
			(start 0.504 -0.25)
			(end 0.504 0.248)
			(stroke
				(width 0.15)
				(type solid)
			)
			(layer "F.Fab")
		)
		(fp_text user "${REFERENCE}"
			(at -0.939 4.599 90)
			(layer "F.Fab")
			(effects
				(font
					(size 0.7 0.7)
					(thickness 0.15)
				)
				(justify right top)
			)
		)
		(fp_text user "License: Apache-2.0"
			(at -0.939 5.799 90)
			(layer "F.Fab")
			(effects
				(font
					(size 0.7 0.7)
					(thickness 0.15)
				)
				(justify right top)
			)
		)
		(fp_text user "Author: Antmicro"
			(at -0.939 3.399 90)
			(layer "F.Fab")
			(effects
				(font
					(size 0.7 0.7)
					(thickness 0.15)
				)
				(justify right top)
			)
		)
		(pad "1" smd roundrect
			(at -0.48 0 270)
			(size 0.59 0.64)
			(layers "F.Cu" "F.Mask" "F.Paste")
			(roundrect_rratio 0.25)
			(net 1 "GND")
			(pintype "passive")
		)
		(pad "2" smd roundrect
			(at 0.48 0 270)
			(size 0.59 0.64)
			(layers "F.Cu" "F.Mask" "F.Paste")
			(roundrect_rratio 0.25)
			(net 2 "+3V3")
			(pintype "passive")
		)
	)
	(footprint "antmicro-footprints:R_0402_1005Metric"
		(layer "F.Cu")
		(at 147.8 118.2)
		(descr "Resistor SMD 0402")
		(tags "resistor SMD 0402")
		(property "Reference" "R362"
			(at -3.7 0.5 0)
			(layer "F.SilkS")
			(effects
				(font
					(size 0.7 0.7)
					(thickness 0.15)
				)
				(justify left bottom)
			)
		)
		(property "Value" "R_2k2_0402"
			(at -1.011843 1.772047 0)
			(layer "F.Fab")
			(effects
				(font
					(size 0.7 0.7)
					(thickness 0.15)
				)
				(justify left bottom)
			)
		)
		(property "Datasheet" "https://www.bourns.com/docs/product-datasheets/cr.pdf"
			(at 0 0 0)
			(layer "F.Fab")
			(hide yes)
			(effects
				(font
					(size 1.27 1.27)
					(thickness 0.15)
				)
			)
		)
		(property "Description" "SMD Chip Resistor, 2.2 kohm, ± 1%, 62.5 mW, 0402 [1005 Metric], Thick Film, General Purpose"
			(at 0 0 0)
			(layer "F.Fab")
			(hide yes)
			(effects
				(font
					(size 1.27 1.27)
					(thickness 0.15)
				)
			)
		)
		(property "MPN" "CR0402-FX-2201GLF"
			(at 0 0 0)
			(unlocked yes)
			(layer "F.Fab")
			(hide yes)
			(effects
				(font
					(size 1 1)
					(thickness 0.15)
				)
			)
		)
		(property "Manufacturer" "Bourns"
			(at 0 0 0)
			(unlocked yes)
			(layer "F.Fab")
			(hide yes)
			(effects
				(font
					(size 1 1)
					(thickness 0.15)
				)
			)
		)
		(property "License" "Apache-2.0"
			(at 0 0 0)
			(unlocked yes)
			(layer "F.Fab")
			(hide yes)
			(effects
				(font
					(size 1 1)
					(thickness 0.15)
				)
			)
		)
		(property "Author" "Antmicro"
			(at 0 0 0)
			(unlocked yes)
			(layer "F.Fab")
			(hide yes)
			(effects
				(font
					(size 1 1)
					(thickness 0.15)
				)
			)
		)
		(property "Val" "2k2"
			(at 0 0 0)
			(unlocked yes)
			(layer "F.Fab")
			(hide yes)
			(effects
				(font
					(size 1 1)
					(thickness 0.15)
				)
			)
		)
		(property "Tolerance" "1%"
			(at 0 0 0)
			(unlocked yes)
			(layer "F.Fab")
			(hide yes)
			(effects
				(font
					(size 1 1)
					(thickness 0.15)
				)
			)
		)
		(sheetname "/SoM_IO/")
		(sheetfile "som_io.kicad_sch")
		(attr smd)
		(fp_rect
			(start -0.925 -0.47)
			(end 0.925 0.47)
			(stroke
				(width 0.05)
				(type default)
			)
			(fill no)
			(layer "F.CrtYd")
		)
		(fp_rect
			(start -0.5 -0.25)
			(end 0.5 0.25)
			(stroke
				(width 0.15)
				(type solid)
			)
			(fill no)
			(layer "F.Fab")
		)
		(fp_text user "${REFERENCE}"
			(at -0.95 3.168 0)
			(layer "F.Fab")
			(effects
				(font
					(size 0.7 0.7)
					(thickness 0.15)
				)
				(justify left bottom)
			)
		)
		(fp_text user "License: Apache-2.0"
			(at -0.95 5.169 0)
			(layer "F.Fab")
			(effects
				(font
					(size 0.7 0.7)
					(thickness 0.15)
				)
				(justify left bottom)
			)
		)
		(fp_text user "Author: Antmicro"
			(at -0.95 4.169 0)
			(layer "F.Fab")
			(effects
				(font
					(size 0.7 0.7)
					(thickness 0.15)
				)
				(justify left bottom)
			)
		)
		(pad "1" smd roundrect
			(at -0.48 0)
			(size 0.59 0.64)
			(layers "F.Cu" "F.Mask" "F.Paste")
			(roundrect_rratio 0.25)
			(net 2 "+3V3")
			(pintype "passive")
		)
		(pad "2" smd roundrect
			(at 0.48 0)
			(size 0.59 0.64)
			(layers "F.Cu" "F.Mask" "F.Paste")
			(roundrect_rratio 0.25)
			(net 999 "/SFP/I2C_{SFP}.SDA")
			(pintype "passive")
		)
	)
	(footprint "antmicro-footprints:SOT-523"
		(layer "F.Cu")
		(at 143.26 133.44 -90)
		(property "Reference" "Q38"
			(at -1.14 7.06 90)
			(layer "F.SilkS")
			(effects
				(font
					(size 0.7 0.7)
					(thickness 0.15)
				)
				(justify right top)
			)
		)
		(property "Value" "DMG1012T-7"
			(at 0.1 1.824 90)
			(layer "F.Fab")
			(effects
				(font
					(size 0.7 0.7)
					(thickness 0.15)
				)
				(justify right top)
			)
		)
		(property "Datasheet" "https://www.diodes.com/assets/Datasheets/ds31783.pdf"
			(at 0 0 90)
			(layer "F.Fab")
			(hide yes)
			(effects
				(font
					(size 1.27 1.27)
					(thickness 0.15)
				)
			)
		)
		(property "Description" "Power MOSFET, N Channel, 20 V, 630 mA, 0.3 ohm, SOT-523, Surface Mount"
			(at 0 0 90)
			(layer "F.Fab")
			(hide yes)
			(effects
				(font
					(size 1.27 1.27)
					(thickness 0.15)
				)
			)
		)
		(property "MPN" "DMG1012T-7"
			(at 0 0 270)
			(unlocked yes)
			(layer "F.Fab")
			(hide yes)
			(effects
				(font
					(size 1 1)
					(thickness 0.15)
				)
			)
		)
		(property "Manufacturer" "Diodes Incorporated"
			(at 0 0 270)
			(unlocked yes)
			(layer "F.Fab")
			(hide yes)
			(effects
				(font
					(size 1 1)
					(thickness 0.15)
				)
			)
		)
		(property "Author" "Antmicro"
			(at 0 0 270)
			(unlocked yes)
			(layer "F.Fab")
			(hide yes)
			(effects
				(font
					(size 1 1)
					(thickness 0.15)
				)
			)
		)
		(property "License" "Apache-2.0"
			(at 0 0 270)
			(unlocked yes)
			(layer "F.Fab")
			(hide yes)
			(effects
				(font
					(size 1 1)
					(thickness 0.15)
				)
			)
		)
		(sheetname "/SoM_Power/")
		(sheetfile "som_power.kicad_sch")
		(attr smd)
		(fp_line
			(start -0.927 -0.051)
			(end -0.927 -0.351)
			(stroke
				(width 0.15)
				(type solid)
			)
			(layer "F.SilkS")
		)
		(fp_line
			(start -0.927 -0.351)
			(end -0.725 -0.551)
			(stroke
				(width 0.15)
				(type solid)
			)
			(layer "F.SilkS")
		)
		(fp_line
			(start -0.725 -0.551)
			(end -0.277 -0.551)
			(stroke
				(width 0.15)
				(type solid)
			)
			(layer "F.SilkS")
		)
		(fp_line
			(start -0.277 -0.551)
			(end -0.277 -0.75)
			(stroke
				(width 0.15)
				(type solid)
			)
			(layer "F.SilkS")
		)
		(fp_circle
			(center -0.9652 0.9652)
			(end -0.9152 0.9652)
			(stroke
				(width 0.15)
				(type solid)
			)
			(fill yes)
			(layer "F.SilkS")
		)
		(fp_line
			(start -1.12 1.15)
			(end 1.1 1.15)
			(stroke
				(width 0.05)
				(type solid)
			)
			(layer "F.CrtYd")
		)
		(fp_line
			(start -1.12 -1.16)
			(end -1.12 1.15)
			(stroke
				(width 0.05)
				(type solid)
			)
			(layer "F.CrtYd")
		)
		(fp_line
			(start -1.12 -1.16)
			(end 1.1 -1.16)
			(stroke
				(width 0.05)
				(type solid)
			)
			(layer "F.CrtYd")
		)
		(fp_line
			(start 1.1 -1.16)
			(end 1.1 1.15)
			(stroke
				(width 0.05)
				(type solid)
			)
			(layer "F.CrtYd")
		)
		(fp_line
			(start 0.8 0.424)
			(end -0.802 0.424)
			(stroke
				(width 0.15)
				(type solid)
			)
			(layer "F.Fab")
		)
		(fp_line
			(start -0.802 -0.276)
			(end -0.802 0.424)
			(stroke
				(width 0.15)
				(type solid)
			)
			(layer "F.Fab")
		)
		(fp_line
			(start -0.652 -0.425)
			(end -0.802 -0.276)
			(stroke
				(width 0.15)
				(type solid)
			)
			(layer "F.Fab")
		)
		(fp_line
			(start 0.8 -0.425)
			(end 0.8 0.424)
			(stroke
				(width 0.15)
				(type solid)
			)
			(layer "F.Fab")
		)
		(fp_line
			(start 0.8 -0.425)
			(end -0.652 -0.425)
			(stroke
				(width 0.15)
				(type solid)
			)
			(layer "F.Fab")
		)
		(fp_circle
			(center -0.9652 0.9652)
			(end -0.9144 0.9652)
			(stroke
				(width 0.15)
				(type solid)
			)
			(fill no)
			(layer "F.Fab")
		)
		(fp_text user "License: Apache-2.0"
			(at -1.12 5.024 90)
			(layer "F.Fab")
			(effects
				(font
					(size 0.7 0.7)
					(thickness 0.15)
				)
				(justify right top)
			)
		)
		(fp_text user "Author: Antmicro"
			(at -1.12 6.224 90)
			(layer "F.Fab")
			(effects
				(font
					(size 0.7 0.7)
					(thickness 0.15)
				)
				(justify right top)
			)
		)
		(fp_text user "${REFERENCE}"
			(at -1.12 3.824 90)
			(layer "F.Fab")
			(effects
				(font
					(size 0.7 0.7)
					(thickness 0.15)
				)
				(justify right top)
			)
		)
		(pad "1" smd rect
			(at -0.5 0.65 270)
			(size 0.4 0.51)
			(layers "F.Cu" "F.Mask" "F.Paste")
			(net 883 "Net-(Q10-G)")
			(pinfunction "G")
			(pintype "input")
		)
		(pad "2" smd rect
			(at 0.498 0.65 270)
			(size 0.4 0.51)
			(layers "F.Cu" "F.Mask" "F.Paste")
			(net 1 "GND")
			(pinfunction "S")
			(pintype "passive")
		)
		(pad "3" smd rect
			(at 0 -0.652 270)
			(size 0.4 0.51)
			(layers "F.Cu" "F.Mask" "F.Paste")
			(net 1303 "Net-(Q38-D)")
			(pinfunction "D")
			(pintype "passive")
		)
	)
	(footprint "antmicro-footprints:XDFN-2_1x0.60mm"
		(layer "F.Cu")
		(at 203.248 55.497999 -90)
		(property "Reference" "D46"
			(at 1.002001 0.498 90)
			(layer "F.SilkS")
			(effects
				(font
					(size 0.7 0.7)
					(thickness 0.15)
				)
				(justify left bottom)
			)
		)
		(property "Value" "TPD1E0B04_XDFN-2"
			(at 0 1.5 90)
			(layer "F.Fab")
			(effects
				(font
					(size 0.7 0.7)
					(thickness 0.15)
				)
				(justify right top)
			)
		)
		(property "Datasheet" "https://www.ti.com/general/docs/suppproductinfo.tsp?distId=26&gotoUrl=https://www.ti.com/lit/gpn/tpd1e0b04"
			(at 0 0 90)
			(layer "F.Fab")
			(hide yes)
			(effects
				(font
					(size 1.27 1.27)
					(thickness 0.15)
				)
			)
		)
		(property "Description" "Bidirectional TVS, 8 kV,  XDFN-2, 3.6 V, 0.18 pF"
			(at 0 0 90)
			(layer "F.Fab")
			(hide yes)
			(effects
				(font
					(size 1.27 1.27)
					(thickness 0.15)
				)
			)
		)
		(property "MPN" "TPD1E0B04DPYR"
			(at 0 0 90)
			(layer "F.Fab")
			(hide yes)
			(effects
				(font
					(size 1.27 1.27)
					(thickness 0.15)
				)
			)
		)
		(property "Manufacturer" "Texas Instruments"
			(at 0 0 90)
			(layer "F.Fab")
			(hide yes)
			(effects
				(font
					(size 1.27 1.27)
					(thickness 0.15)
				)
			)
		)
		(property "Author" "Antmicro"
			(at 0 0 270)
			(unlocked yes)
			(layer "F.Fab")
			(hide yes)
			(effects
				(font
					(size 1 1)
					(thickness 0.15)
				)
			)
		)
		(property "License" "Apache-2.0"
			(at 0 0 270)
			(unlocked yes)
			(layer "F.Fab")
			(hide yes)
			(effects
				(font
					(size 1 1)
					(thickness 0.15)
				)
			)
		)
		(sheetname "/SoM_Power/")
		(sheetfile "som_power.kicad_sch")
		(attr smd)
		(fp_poly
			(pts
				(xy -0.725 -0.475) (xy 0.725 -0.475) (xy 0.725 0.475) (xy -0.725 0.475)
			)
			(stroke
				(width 0.05)
				(type solid)
			)
			(fill no)
			(layer "F.CrtYd")
		)
		(fp_poly
			(pts
				(xy -0.55 -0.35) (xy 0.55 -0.35) (xy 0.55 0.35) (xy -0.55 0.35)
			)
			(stroke
				(width 0.15)
				(type solid)
			)
			(fill no)
			(layer "F.Fab")
		)
		(fp_text user "License: Apache-2.0"
			(at -0.799999 5.6 90)
			(layer "F.Fab")
			(effects
				(font
					(size 0.7 0.7)
					(thickness 0.15)
				)
				(justify right top)
			)
		)
		(fp_text user "${REFERENCE}"
			(at -0.8 3.2 90)
			(layer "F.Fab")
			(effects
				(font
					(size 0.7 0.7)
					(thickness 0.15)
				)
				(justify right top)
			)
		)
		(fp_text user "Author: Antmicro"
			(at -0.8 4.4 90)
			(layer "F.Fab")
			(effects
				(font
					(size 0.7 0.7)
					(thickness 0.15)
				)
				(justify right top)
			)
		)
		(pad "1" smd roundrect
			(at -0.350999 0 270)
			(size 0.3 0.5)
			(layers "F.Cu" "F.Mask" "F.Paste")
			(roundrect_rratio 0.25)
			(net 1 "GND")
			(pinfunction "C")
			(pintype "passive")
		)
		(pad "2" smd roundrect
			(at 0.349 0 270)
			(size 0.3 0.5)
			(layers "F.Cu" "F.Mask" "F.Paste")
			(roundrect_rratio 0.25)
			(net 495 "/SoM_Power/~{FORCE_RECOVERY}")
			(pinfunction "A")
			(pintype "passive")
		)
	)
	(footprint "antmicro-footprints:C_0402_1005Metric"
		(layer "F.Cu")
		(at 192.4 128.07)
		(descr "Capacitor SMD 0402")
		(tags "capacitor SMD 0402")
		(property "Reference" "C79"
			(at -1.4 8.03 0)
			(layer "F.SilkS")
			(effects
				(font
					(size 0.7 0.7)
					(thickness 0.15)
				)
				(justify left bottom)
			)
		)
		(property "Value" "C_100n_0402"
			(at -1.022927 2.155213 0)
			(layer "F.Fab")
			(effects
				(font
					(size 0.7 0.7)
					(thickness 0.15)
				)
				(justify left bottom)
			)
		)
		(property "Datasheet" "https://www.murata.com/products/productdetail?partno=GRM155R61H104KE14%23"
			(at 0 0 0)
			(layer "F.Fab")
			(hide yes)
			(effects
				(font
					(size 1.27 1.27)
					(thickness 0.15)
				)
			)
		)
		(property "Description" "SMD Multilayer Ceramic Capacitor, 0.1 µF, 50 V, 0402 [1005 Metric], ± 10%, X5R, GRM Series"
			(at 0 0 0)
			(layer "F.Fab")
			(hide yes)
			(effects
				(font
					(size 1.27 1.27)
					(thickness 0.15)
				)
			)
		)
		(property "MPN" "GRM155R61H104KE14D"
			(at 0 0 0)
			(unlocked yes)
			(layer "F.Fab")
			(hide yes)
			(effects
				(font
					(size 1 1)
					(thickness 0.15)
				)
			)
		)
		(property "Manufacturer" "Murata"
			(at 0 0 0)
			(unlocked yes)
			(layer "F.Fab")
			(hide yes)
			(effects
				(font
					(size 1 1)
					(thickness 0.15)
				)
			)
		)
		(property "License" "Apache-2.0"
			(at 0 0 0)
			(unlocked yes)
			(layer "F.Fab")
			(hide yes)
			(effects
				(font
					(size 1 1)
					(thickness 0.15)
				)
			)
		)
		(property "Author" "Antmicro"
			(at 0 0 0)
			(unlocked yes)
			(layer "F.Fab")
			(hide yes)
			(effects
				(font
					(size 1 1)
					(thickness 0.15)
				)
			)
		)
		(property "Val" "100n"
			(at 0 0 0)
			(unlocked yes)
			(layer "F.Fab")
			(hide yes)
			(effects
				(font
					(size 1 1)
					(thickness 0.15)
				)
			)
		)
		(property "Voltage" "50V"
			(at 0 0 0)
			(unlocked yes)
			(layer "F.Fab")
			(hide yes)
			(effects
				(font
					(size 1 1)
					(thickness 0.15)
				)
			)
		)
		(property "Dielectric" "X5R"
			(at 0 0 0)
			(unlocked yes)
			(layer "F.Fab")
			(hide yes)
			(effects
				(font
					(size 1 1)
					(thickness 0.15)
				)
			)
		)
		(component_classes
			(class "DCDC_1V15")
		)
		(sheetname "/DCDC/")
		(sheetfile "dcdc.kicad_sch")
		(attr smd)
		(fp_rect
			(start -0.925 -0.47)
			(end 0.925 0.47)
			(stroke
				(width 0.05)
				(type default)
			)
			(fill no)
			(layer "F.CrtYd")
		)
		(fp_line
			(start -0.494 -0.25)
			(end 0.504 -0.25)
			(stroke
				(width 0.15)
				(type solid)
			)
			(layer "F.Fab")
		)
		(fp_line
			(start -0.494 0.248)
			(end -0.494 -0.25)
			(stroke
				(width 0.15)
				(type solid)
			)
			(layer "F.Fab")
		)
		(fp_line
			(start 0.504 -0.25)
			(end 0.504 0.248)
			(stroke
				(width 0.15)
				(type solid)
			)
			(layer "F.Fab")
		)
		(fp_line
			(start 0.504 0.248)
			(end -0.494 0.248)
			(stroke
				(width 0.15)
				(type solid)
			)
			(layer "F.Fab")
		)
		(fp_text user "${REFERENCE}"
			(at -0.939 4.599 0)
			(layer "F.Fab")
			(effects
				(font
					(size 0.7 0.7)
					(thickness 0.15)
				)
				(justify left bottom)
			)
		)
		(fp_text user "Author: Antmicro"
			(at -0.939 3.399 0)
			(layer "F.Fab")
			(effects
				(font
					(size 0.7 0.7)
					(thickness 0.15)
				)
				(justify left bottom)
			)
		)
		(fp_text user "License: Apache-2.0"
			(at -0.939 5.799 0)
			(layer "F.Fab")
			(effects
				(font
					(size 0.7 0.7)
					(thickness 0.15)
				)
				(justify left bottom)
			)
		)
		(pad "1" smd roundrect
			(at -0.48 0)
			(size 0.59 0.64)
			(layers "F.Cu" "F.Mask" "F.Paste")
			(roundrect_rratio 0.25)
			(net 1 "GND")
			(pintype "passive")
		)
		(pad "2" smd roundrect
			(at 0.48 0)
			(size 0.59 0.64)
			(layers "F.Cu" "F.Mask" "F.Paste")
			(roundrect_rratio 0.25)
			(net 280 "/DCDC/1V15_OUT")
			(pintype "passive")
		)
	)
	(footprint "antmicro-footprints:C_0402_1005Metric"
		(layer "F.Cu")
		(at 199.27 84 -90)
		(descr "Capacitor SMD 0402")
		(tags "capacitor SMD 0402")
		(property "Reference" "C139"
			(at -1.3 -0.63 90)
			(layer "F.SilkS")
			(effects
				(font
					(size 0.7 0.7)
					(thickness 0.15)
				)
				(justify right top)
			)
		)
		(property "Value" "C_10u_0402"
			(at -1.022927 2.155213 90)
			(layer "F.Fab")
			(effects
				(font
					(size 0.7 0.7)
					(thickness 0.15)
				)
				(justify right top)
			)
		)
		(property "Datasheet" "https://www.yageo.com/en/Chart/Download/pdf/CC0402MRX5R5BB106"
			(at 0 0 90)
			(layer "F.Fab")
			(hide yes)
			(effects
				(font
					(size 1.27 1.27)
					(thickness 0.15)
				)
			)
		)
		(property "Description" "SMD Multilayer Ceramic Capacitor, 10 µF, 6.3 V, 0402 [1005 Metric], ± 20%, X5R, CC Series"
			(at 0 0 90)
			(layer "F.Fab")
			(hide yes)
			(effects
				(font
					(size 1.27 1.27)
					(thickness 0.15)
				)
			)
		)
		(property "MPN" "CC0402MRX5R5BB106"
			(at 0 0 270)
			(unlocked yes)
			(layer "F.Fab")
			(hide yes)
			(effects
				(font
					(size 1 1)
					(thickness 0.15)
				)
			)
		)
		(property "Manufacturer" "YAGEO"
			(at 0 0 270)
			(unlocked yes)
			(layer "F.Fab")
			(hide yes)
			(effects
				(font
					(size 1 1)
					(thickness 0.15)
				)
			)
		)
		(property "License" "Apache-2.0"
			(at 0 0 270)
			(unlocked yes)
			(layer "F.Fab")
			(hide yes)
			(effects
				(font
					(size 1 1)
					(thickness 0.15)
				)
			)
		)
		(property "Author" "Antmicro"
			(at 0 0 270)
			(unlocked yes)
			(layer "F.Fab")
			(hide yes)
			(effects
				(font
					(size 1 1)
					(thickness 0.15)
				)
			)
		)
		(property "Val" "10u"
			(at 0 0 270)
			(unlocked yes)
			(layer "F.Fab")
			(hide yes)
			(effects
				(font
					(size 1 1)
					(thickness 0.15)
				)
			)
		)
		(property "Voltage" ""
			(at 0 0 270)
			(unlocked yes)
			(layer "F.Fab")
			(hide yes)
			(effects
				(font
					(size 1 1)
					(thickness 0.15)
				)
			)
		)
		(property "Dielectric" ""
			(at 0 0 270)
			(unlocked yes)
			(layer "F.Fab")
			(hide yes)
			(effects
				(font
					(size 1 1)
					(thickness 0.15)
				)
			)
		)
		(sheetname "/USB DP Alt mode/")
		(sheetfile "usb_dp.kicad_sch")
		(attr smd)
		(fp_rect
			(start -0.925 -0.47)
			(end 0.925 0.47)
			(stroke
				(width 0.05)
				(type default)
			)
			(fill no)
			(layer "F.CrtYd")
		)
		(fp_line
			(start -0.494 0.248)
			(end -0.494 -0.25)
			(stroke
				(width 0.15)
				(type solid)
			)
			(layer "F.Fab")
		)
		(fp_line
			(start 0.504 0.248)
			(end -0.494 0.248)
			(stroke
				(width 0.15)
				(type solid)
			)
			(layer "F.Fab")
		)
		(fp_line
			(start -0.494 -0.25)
			(end 0.504 -0.25)
			(stroke
				(width 0.15)
				(type solid)
			)
			(layer "F.Fab")
		)
		(fp_line
			(start 0.504 -0.25)
			(end 0.504 0.248)
			(stroke
				(width 0.15)
				(type solid)
			)
			(layer "F.Fab")
		)
		(fp_text user "${REFERENCE}"
			(at -0.939 4.599 90)
			(layer "F.Fab")
			(effects
				(font
					(size 0.7 0.7)
					(thickness 0.15)
				)
				(justify right top)
			)
		)
		(fp_text user "Author: Antmicro"
			(at -0.939 3.399 90)
			(layer "F.Fab")
			(effects
				(font
					(size 0.7 0.7)
					(thickness 0.15)
				)
				(justify right top)
			)
		)
		(fp_text user "License: Apache-2.0"
			(at -0.939 5.799 90)
			(layer "F.Fab")
			(effects
				(font
					(size 0.7 0.7)
					(thickness 0.15)
				)
				(justify right top)
			)
		)
		(pad "1" smd roundrect
			(at -0.48 0 270)
			(size 0.59 0.64)
			(layers "F.Cu" "F.Mask" "F.Paste")
			(roundrect_rratio 0.25)
			(net 5 "+5V")
			(pintype "passive")
		)
		(pad "2" smd roundrect
			(at 0.48 0 270)
			(size 0.59 0.64)
			(layers "F.Cu" "F.Mask" "F.Paste")
			(roundrect_rratio 0.25)
			(net 1 "GND")
			(pintype "passive")
		)
	)
	(footprint "antmicro-footprints:TP_SMD_0.75mm"
		(layer "F.Cu")
		(at 181 60.5 90)
		(property "Reference" "TP3"
			(at -1.15 -0.75 90)
			(layer "F.SilkS")
			(hide yes)
			(effects
				(font
					(size 0.7 0.7)
					(thickness 0.15)
				)
				(justify left bottom)
			)
		)
		(property "Value" "TP_0.75mm_SMD"
			(at 0 1.2 90)
			(layer "F.Fab")
			(effects
				(font
					(size 0.7 0.7)
					(thickness 0.15)
				)
				(justify left bottom)
			)
		)
		(property "Description" "SMT test point"
			(at 0 0 90)
			(layer "F.Fab")
			(hide yes)
			(effects
				(font
					(size 1.27 1.27)
					(thickness 0.15)
				)
			)
		)
		(property "MPN" ""
			(at 0 0 90)
			(unlocked yes)
			(layer "F.Fab")
			(hide yes)
			(effects
				(font
					(size 1 1)
					(thickness 0.15)
				)
			)
		)
		(property "Manufacturer" ""
			(at 0 0 90)
			(unlocked yes)
			(layer "F.Fab")
			(hide yes)
			(effects
				(font
					(size 1 1)
					(thickness 0.15)
				)
			)
		)
		(property "Author" "Antmicro"
			(at 0 0 90)
			(unlocked yes)
			(layer "F.Fab")
			(hide yes)
			(effects
				(font
					(size 1 1)
					(thickness 0.15)
				)
			)
		)
		(property "License" "Apache-2.0"
			(at 0 0 90)
			(unlocked yes)
			(layer "F.Fab")
			(hide yes)
			(effects
				(font
					(size 1 1)
					(thickness 0.15)
				)
			)
		)
		(sheetname "/Power/")
		(sheetfile "power.kicad_sch")
		(attr exclude_from_pos_files exclude_from_bom)
		(fp_circle
			(center 0 0)
			(end 0.475 0)
			(stroke
				(width 0.05)
				(type default)
			)
			(fill no)
			(layer "F.CrtYd")
		)
		(fp_text user "${REFERENCE}"
			(at -0.4 2.7 90)
			(layer "F.Fab")
			(effects
				(font
					(size 0.7 0.7)
					(thickness 0.15)
				)
				(justify left bottom)
			)
		)
		(fp_text user "License: Apache-2.0"
			(at -0.4 5.101 90)
			(layer "F.Fab")
			(effects
				(font
					(size 0.7 0.7)
					(thickness 0.15)
				)
				(justify left bottom)
			)
		)
		(fp_text user "Author: Antmicro"
			(at -0.4 3.901 90)
			(layer "F.Fab")
			(effects
				(font
					(size 0.7 0.7)
					(thickness 0.15)
				)
				(justify left bottom)
			)
		)
		(pad "1" smd circle
			(at 0 0 90)
			(size 0.75 0.75)
			(layers "F.Cu" "F.Mask")
			(net 1 "GND")
			(pinfunction "1")
			(pintype "passive")
		)
	)
	(footprint "antmicro-footprints:USON-10_2.5x1mm_P0.5mm"
		(layer "F.Cu")
		(at 220.814 114.527)
		(descr "USON-10 2.5x1mm_ Pitch 0.5mm")
		(tags "USON-10 2.5x1mm Pitch 0.5mm")
		(property "Reference" "U28"
			(at 1.766 -1.857 90)
			(layer "F.SilkS")
			(effects
				(font
					(size 0.7 0.7)
					(thickness 0.15)
				)
				(justify left bottom)
			)
		)
		(property "Value" "TPD4E05U06QDQARQ1"
			(at 0.018 2.499 0)
			(layer "F.Fab")
			(effects
				(font
					(size 0.7 0.7)
					(thickness 0.15)
				)
				(justify left bottom)
			)
		)
		(property "Datasheet" "https://www.ti.com/lit/ds/symlink/tpd4e05u06-q1.pdf?HQS=dis-mous-null-mousermode-dsf-pf-null-wwe&ts=1663591265741&ref_url=https%253A%252F%252Fwww.mouser.com%252F"
			(at 0 0 0)
			(layer "F.Fab")
			(hide yes)
			(effects
				(font
					(size 1.27 1.27)
					(thickness 0.15)
				)
			)
		)
		(property "Description" "TVS diode array, 12 kV, USON-10, 5.5 V, 0.5 pF"
			(at 0 0 0)
			(layer "F.Fab")
			(hide yes)
			(effects
				(font
					(size 1.27 1.27)
					(thickness 0.15)
				)
			)
		)
		(property "Manufacturer" "Texas Instruments"
			(at 0 0 0)
			(unlocked yes)
			(layer "F.Fab")
			(hide yes)
			(effects
				(font
					(size 1 1)
					(thickness 0.15)
				)
			)
		)
		(property "MPN" "TPD4E05U06QDQARQ1"
			(at 0 0 0)
			(unlocked yes)
			(layer "F.Fab")
			(hide yes)
			(effects
				(font
					(size 1 1)
					(thickness 0.15)
				)
			)
		)
		(property "Author" "Antmicro"
			(at 0 0 0)
			(unlocked yes)
			(layer "F.Fab")
			(hide yes)
			(effects
				(font
					(size 1 1)
					(thickness 0.15)
				)
			)
		)
		(property "License" "Apache-2.0"
			(at 0 0 0)
			(unlocked yes)
			(layer "F.Fab")
			(hide yes)
			(effects
				(font
					(size 1 1)
					(thickness 0.15)
				)
			)
		)
		(sheetname "/USB Hub/")
		(sheetfile "usb_hub.kicad_sch")
		(attr smd)
		(fp_line
			(start 0.498 -1.401)
			(end -0.5 -1.401)
			(stroke
				(width 0.15)
				(type solid)
			)
			(layer "F.SilkS")
		)
		(fp_line
			(start 0.498 1.398)
			(end -0.5 1.398)
			(stroke
				(width 0.15)
				(type solid)
			)
			(layer "F.SilkS")
		)
		(fp_circle
			(center -0.68 -1.27)
			(end -0.63 -1.27)
			(stroke
				(width 0.15)
				(type solid)
			)
			(fill yes)
			(layer "F.SilkS")
		)
		(fp_rect
			(start -0.8 -1.5)
			(end 0.8 1.499)
			(stroke
				(width 0.05)
				(type solid)
			)
			(fill no)
			(layer "F.CrtYd")
		)
		(fp_line
			(start -0.5 -1)
			(end -0.5 1.249)
			(stroke
				(width 0.15)
				(type solid)
			)
			(layer "F.Fab")
		)
		(fp_line
			(start -0.5 1.249)
			(end 0.498 1.249)
			(stroke
				(width 0.15)
				(type solid)
			)
			(layer "F.Fab")
		)
		(fp_line
			(start -0.25 -1.25)
			(end -0.5 -1)
			(stroke
				(width 0.15)
				(type solid)
			)
			(layer "F.Fab")
		)
		(fp_line
			(start 0.498 -1.25)
			(end -0.25 -1.25)
			(stroke
				(width 0.15)
				(type solid)
			)
			(layer "F.Fab")
		)
		(fp_line
			(start 0.498 -1.25)
			(end 0.498 1.249)
			(stroke
				(width 0.15)
				(type solid)
			)
			(layer "F.Fab")
		)
		(fp_text user "${REFERENCE}"
			(at -0.802 4.498 0)
			(layer "F.Fab")
			(effects
				(font
					(size 0.7 0.7)
					(thickness 0.15)
				)
				(justify left bottom)
			)
		)
		(fp_text user "License: Apache-2.0"
			(at -0.802 6.9 0)
			(layer "F.Fab")
			(effects
				(font
					(size 0.7 0.7)
					(thickness 0.15)
				)
				(justify left bottom)
			)
		)
		(fp_text user "Author: Antmicro"
			(at -0.802 5.7 0)
			(layer "F.Fab")
			(effects
				(font
					(size 0.7 0.7)
					(thickness 0.15)
				)
				(justify left bottom)
			)
		)
		(pad "1" smd roundrect
			(at -0.387 -1 270)
			(size 0.25 0.55)
			(layers "F.Cu" "F.Mask" "F.Paste")
			(roundrect_rratio 0.25)
			(net 508 "/USB Hub/USBC3_D-")
			(pintype "passive")
		)
		(pad "2" smd roundrect
			(at -0.387 -0.5 270)
			(size 0.25 0.55)
			(layers "F.Cu" "F.Mask" "F.Paste")
			(roundrect_rratio 0.25)
			(net 506 "/USB Hub/USBC3_D+")
			(pintype "passive")
		)
		(pad "3" smd roundrect
			(at -0.387 0 270)
			(size 0.4 0.55)
			(layers "F.Cu" "F.Mask" "F.Paste")
			(roundrect_rratio 0.25)
			(net 1 "GND")
			(pintype "power_in")
		)
		(pad "4" smd roundrect
			(at -0.387 0.498 270)
			(size 0.25 0.55)
			(layers "F.Cu" "F.Mask" "F.Paste")
			(roundrect_rratio 0.25)
			(net 509 "/USB Hub/USBC3_CC_{2}")
			(pintype "passive")
		)
		(pad "5" smd roundrect
			(at -0.387 0.998 270)
			(size 0.25 0.55)
			(layers "F.Cu" "F.Mask" "F.Paste")
			(roundrect_rratio 0.25)
			(net 510 "/USB Hub/USBC3_CC_{1}")
			(pintype "passive")
		)
		(pad "6" smd roundrect
			(at 0.385 0.998 270)
			(size 0.25 0.55)
			(layers "F.Cu" "F.Mask" "F.Paste")
			(roundrect_rratio 0.25)
			(net 510 "/USB Hub/USBC3_CC_{1}")
			(pintype "passive")
		)
		(pad "7" smd roundrect
			(at 0.385 0.498 270)
			(size 0.25 0.55)
			(layers "F.Cu" "F.Mask" "F.Paste")
			(roundrect_rratio 0.25)
			(net 509 "/USB Hub/USBC3_CC_{2}")
			(pintype "passive")
		)
		(pad "8" smd roundrect
			(at 0.385 0 270)
			(size 0.4 0.55)
			(layers "F.Cu" "F.Mask" "F.Paste")
			(roundrect_rratio 0.25)
			(net 1 "GND")
			(pintype "passive")
		)
		(pad "9" smd roundrect
			(at 0.385 -0.5 270)
			(size 0.25 0.55)
			(layers "F.Cu" "F.Mask" "F.Paste")
			(roundrect_rratio 0.25)
			(net 506 "/USB Hub/USBC3_D+")
			(pintype "passive")
		)
		(pad "10" smd roundrect
			(at 0.385 -1 270)
			(size 0.25 0.55)
			(layers "F.Cu" "F.Mask" "F.Paste")
			(roundrect_rratio 0.25)
			(net 508 "/USB Hub/USBC3_D-")
			(pintype "passive")
		)
	)
	(footprint "antmicro-footprints:R_0402_1005Metric"
		(layer "F.Cu")
		(at 216.8 120.1 90)
		(descr "Resistor SMD 0402")
		(tags "resistor SMD 0402")
		(property "Reference" "R87"
			(at 0.8 0.4 90)
			(layer "F.SilkS")
			(effects
				(font
					(size 0.7 0.7)
					(thickness 0.15)
				)
				(justify left bottom)
			)
		)
		(property "Value" "R_10k_0402"
			(at -1.011843 1.772046 90)
			(layer "F.Fab")
			(effects
				(font
					(size 0.7 0.7)
					(thickness 0.15)
				)
				(justify left bottom)
			)
		)
		(property "Datasheet" "https://www.bourns.com/docs/product-datasheets/cr.pdf"
			(at 0 0 90)
			(layer "F.Fab")
			(hide yes)
			(effects
				(font
					(size 1.27 1.27)
					(thickness 0.15)
				)
			)
		)
		(property "Description" "SMD Chip Resistor, 10 kohm, ± 1%, 62.5 mW, 0402 [1005 Metric], Thick Film, General Purpose"
			(at 0 0 90)
			(layer "F.Fab")
			(hide yes)
			(effects
				(font
					(size 1.27 1.27)
					(thickness 0.15)
				)
			)
		)
		(property "Manufacturer" "Bourns"
			(at 0 0 90)
			(unlocked yes)
			(layer "F.Fab")
			(hide yes)
			(effects
				(font
					(size 1 1)
					(thickness 0.15)
				)
			)
		)
		(property "MPN" "CR0402-FX-1002GLF"
			(at 0 0 90)
			(unlocked yes)
			(layer "F.Fab")
			(hide yes)
			(effects
				(font
					(size 1 1)
					(thickness 0.15)
				)
			)
		)
		(property "Val" "10k"
			(at 0 0 90)
			(unlocked yes)
			(layer "F.Fab")
			(hide yes)
			(effects
				(font
					(size 1 1)
					(thickness 0.15)
				)
			)
		)
		(property "License" "Apache-2.0"
			(at 0 0 90)
			(unlocked yes)
			(layer "F.Fab")
			(hide yes)
			(effects
				(font
					(size 1 1)
					(thickness 0.15)
				)
			)
		)
		(property "Author" "Antmicro"
			(at 0 0 90)
			(unlocked yes)
			(layer "F.Fab")
			(hide yes)
			(effects
				(font
					(size 1 1)
					(thickness 0.15)
				)
			)
		)
		(property "Tolerance" "1%"
			(at 0 0 90)
			(unlocked yes)
			(layer "F.Fab")
			(hide yes)
			(effects
				(font
					(size 1 1)
					(thickness 0.15)
				)
			)
		)
		(sheetname "/USB Hub/")
		(sheetfile "usb_hub.kicad_sch")
		(attr smd)
		(fp_poly
			(pts
				(xy -0.925 -0.47) (xy 0.925 -0.47) (xy 0.925 0.47) (xy -0.925 0.47)
			)
			(stroke
				(width 0.05)
				(type default)
			)
			(fill no)
			(layer "F.CrtYd")
		)
		(fp_poly
			(pts
				(xy -0.5 -0.25) (xy 0.5 -0.25) (xy 0.5 0.25) (xy -0.5 0.25)
			)
			(stroke
				(width 0.15)
				(type solid)
			)
			(fill no)
			(layer "F.Fab")
		)
		(fp_text user "${REFERENCE}"
			(at -0.95 3.168 90)
			(layer "F.Fab")
			(effects
				(font
					(size 0.7 0.7)
					(thickness 0.15)
				)
				(justify left bottom)
			)
		)
		(fp_text user "Author: Antmicro"
			(at -0.95 4.169 90)
			(layer "F.Fab")
			(effects
				(font
					(size 0.7 0.7)
					(thickness 0.15)
				)
				(justify left bottom)
			)
		)
		(fp_text user "License: Apache-2.0"
			(at -0.949999 5.169 90)
			(layer "F.Fab")
			(effects
				(font
					(size 0.7 0.7)
					(thickness 0.15)
				)
				(justify left bottom)
			)
		)
		(pad "1" smd roundrect
			(at -0.48 0 90)
			(size 0.59 0.64)
			(layers "F.Cu" "F.Mask" "F.Paste")
			(roundrect_rratio 0.25)
			(net 913 "/USB Hub/CFG_STRAP1")
			(pintype "passive")
		)
		(pad "2" smd roundrect
			(at 0.48 0 90)
			(size 0.59 0.64)
			(layers "F.Cu" "F.Mask" "F.Paste")
			(roundrect_rratio 0.25)
			(net 2 "+3V3")
			(pintype "passive")
		)
	)
	(footprint "antmicro-footprints:R_0402_1005Metric"
		(layer "F.Cu")
		(at 96.45 55.87 180)
		(descr "Resistor SMD 0402")
		(tags "resistor SMD 0402")
		(property "Reference" "R305"
			(at 0.85 0.42 0)
			(layer "F.SilkS")
			(effects
				(font
					(size 0.7 0.7)
					(thickness 0.15)
				)
				(justify right top)
			)
		)
		(property "Value" "R_10k_0402"
			(at -1.011843 1.772047 0)
			(layer "F.Fab")
			(effects
				(font
					(size 0.7 0.7)
					(thickness 0.15)
				)
				(justify right top)
			)
		)
		(property "Datasheet" "https://www.bourns.com/docs/product-datasheets/cr.pdf"
			(at 0 0 0)
			(layer "F.Fab")
			(hide yes)
			(effects
				(font
					(size 1.27 1.27)
					(thickness 0.15)
				)
			)
		)
		(property "Description" "SMD Chip Resistor, 10 kohm, ± 1%, 62.5 mW, 0402 [1005 Metric], Thick Film, General Purpose"
			(at 0 0 0)
			(layer "F.Fab")
			(hide yes)
			(effects
				(font
					(size 1.27 1.27)
					(thickness 0.15)
				)
			)
		)
		(property "MPN" "CR0402-FX-1002GLF"
			(at 0 0 180)
			(unlocked yes)
			(layer "F.Fab")
			(hide yes)
			(effects
				(font
					(size 1 1)
					(thickness 0.15)
				)
			)
		)
		(property "Manufacturer" "Bourns"
			(at 0 0 180)
			(unlocked yes)
			(layer "F.Fab")
			(hide yes)
			(effects
				(font
					(size 1 1)
					(thickness 0.15)
				)
			)
		)
		(property "License" "Apache-2.0"
			(at 0 0 180)
			(unlocked yes)
			(layer "F.Fab")
			(hide yes)
			(effects
				(font
					(size 1 1)
					(thickness 0.15)
				)
			)
		)
		(property "Author" "Antmicro"
			(at 0 0 180)
			(unlocked yes)
			(layer "F.Fab")
			(hide yes)
			(effects
				(font
					(size 1 1)
					(thickness 0.15)
				)
			)
		)
		(property "Val" "10k"
			(at 0 0 180)
			(unlocked yes)
			(layer "F.Fab")
			(hide yes)
			(effects
				(font
					(size 1 1)
					(thickness 0.15)
				)
			)
		)
		(property "Tolerance" "1%"
			(at 0 0 180)
			(unlocked yes)
			(layer "F.Fab")
			(hide yes)
			(effects
				(font
					(size 1 1)
					(thickness 0.15)
				)
			)
		)
		(sheetname "/SoM_Power/")
		(sheetfile "som_power.kicad_sch")
		(attr smd)
		(fp_rect
			(start -0.925 -0.47)
			(end 0.925 0.47)
			(stroke
				(width 0.05)
				(type default)
			)
			(fill no)
			(layer "F.CrtYd")
		)
		(fp_rect
			(start -0.5 -0.25)
			(end 0.5 0.25)
			(stroke
				(width 0.15)
				(type solid)
			)
			(fill no)
			(layer "F.Fab")
		)
		(fp_text user "Author: Antmicro"
			(at -0.95 4.169 0)
			(layer "F.Fab")
			(effects
				(font
					(size 0.7 0.7)
					(thickness 0.15)
				)
				(justify right top)
			)
		)
		(fp_text user "License: Apache-2.0"
			(at -0.95 5.169 0)
			(layer "F.Fab")
			(effects
				(font
					(size 0.7 0.7)
					(thickness 0.15)
				)
				(justify right top)
			)
		)
		(fp_text user "${REFERENCE}"
			(at -0.95 3.168 0)
			(layer "F.Fab")
			(effects
				(font
					(size 0.7 0.7)
					(thickness 0.15)
				)
				(justify right top)
			)
		)
		(pad "1" smd roundrect
			(at -0.48 0 180)
			(size 0.59 0.64)
			(layers "F.Cu" "F.Mask" "F.Paste")
			(roundrect_rratio 0.25)
			(net 1 "GND")
			(pintype "passive")
		)
		(pad "2" smd roundrect
			(at 0.48 0 180)
			(size 0.59 0.64)
			(layers "F.Cu" "F.Mask" "F.Paste")
			(roundrect_rratio 0.25)
			(net 1380 "Net-(U3-DIV)")
			(pintype "passive")
		)
	)
	(footprint "antmicro-footprints:C_0402_1005Metric"
		(layer "F.Cu")
		(at 88 63.5 180)
		(descr "Capacitor SMD 0402")
		(tags "capacitor SMD 0402")
		(property "Reference" "C236"
			(at 16.3 -8.7 180)
			(layer "F.SilkS")
			(effects
				(font
					(size 0.7 0.7)
					(thickness 0.15)
				)
				(justify right top)
			)
		)
		(property "Value" "C_100n_0402"
			(at -1.022927 2.155213 0)
			(layer "F.Fab")
			(effects
				(font
					(size 0.7 0.7)
					(thickness 0.15)
				)
				(justify right top)
			)
		)
		(property "Datasheet" "https://www.murata.com/products/productdetail?partno=GRM155R61H104KE14%23"
			(at 0 0 0)
			(layer "F.Fab")
			(hide yes)
			(effects
				(font
					(size 1.27 1.27)
					(thickness 0.15)
				)
			)
		)
		(property "Description" "SMD Multilayer Ceramic Capacitor, 0.1 µF, 50 V, 0402 [1005 Metric], ± 10%, X5R, GRM Series"
			(at 0 0 0)
			(layer "F.Fab")
			(hide yes)
			(effects
				(font
					(size 1.27 1.27)
					(thickness 0.15)
				)
			)
		)
		(property "MPN" "GRM155R61H104KE14D"
			(at 0 0 180)
			(unlocked yes)
			(layer "F.Fab")
			(hide yes)
			(effects
				(font
					(size 1 1)
					(thickness 0.15)
				)
			)
		)
		(property "Manufacturer" "Murata"
			(at 0 0 180)
			(unlocked yes)
			(layer "F.Fab")
			(hide yes)
			(effects
				(font
					(size 1 1)
					(thickness 0.15)
				)
			)
		)
		(property "License" "Apache-2.0"
			(at 0 0 180)
			(unlocked yes)
			(layer "F.Fab")
			(hide yes)
			(effects
				(font
					(size 1 1)
					(thickness 0.15)
				)
			)
		)
		(property "Author" "Antmicro"
			(at 0 0 180)
			(unlocked yes)
			(layer "F.Fab")
			(hide yes)
			(effects
				(font
					(size 1 1)
					(thickness 0.15)
				)
			)
		)
		(property "Val" "100n"
			(at 0 0 180)
			(unlocked yes)
			(layer "F.Fab")
			(hide yes)
			(effects
				(font
					(size 1 1)
					(thickness 0.15)
				)
			)
		)
		(property "Voltage" "50V"
			(at 0 0 180)
			(unlocked yes)
			(layer "F.Fab")
			(hide yes)
			(effects
				(font
					(size 1 1)
					(thickness 0.15)
				)
			)
		)
		(property "Dielectric" "X5R"
			(at 0 0 180)
			(unlocked yes)
			(layer "F.Fab")
			(hide yes)
			(effects
				(font
					(size 1 1)
					(thickness 0.15)
				)
			)
		)
		(sheetname "/SoM_Power/")
		(sheetfile "som_power.kicad_sch")
		(attr smd)
		(fp_rect
			(start -0.925 -0.47)
			(end 0.925 0.47)
			(stroke
				(width 0.05)
				(type default)
			)
			(fill no)
			(layer "F.CrtYd")
		)
		(fp_line
			(start 0.504 0.248)
			(end -0.494 0.248)
			(stroke
				(width 0.15)
				(type solid)
			)
			(layer "F.Fab")
		)
		(fp_line
			(start 0.504 -0.25)
			(end 0.504 0.248)
			(stroke
				(width 0.15)
				(type solid)
			)
			(layer "F.Fab")
		)
		(fp_line
			(start -0.494 0.248)
			(end -0.494 -0.25)
			(stroke
				(width 0.15)
				(type solid)
			)
			(layer "F.Fab")
		)
		(fp_line
			(start -0.494 -0.25)
			(end 0.504 -0.25)
			(stroke
				(width 0.15)
				(type solid)
			)
			(layer "F.Fab")
		)
		(fp_text user "Author: Antmicro"
			(at -0.939 3.399 0)
			(layer "F.Fab")
			(effects
				(font
					(size 0.7 0.7)
					(thickness 0.15)
				)
				(justify right top)
			)
		)
		(fp_text user "${REFERENCE}"
			(at -0.939 4.599 0)
			(layer "F.Fab")
			(effects
				(font
					(size 0.7 0.7)
					(thickness 0.15)
				)
				(justify right top)
			)
		)
		(fp_text user "License: Apache-2.0"
			(at -0.939 5.799 0)
			(layer "F.Fab")
			(effects
				(font
					(size 0.7 0.7)
					(thickness 0.15)
				)
				(justify right top)
			)
		)
		(pad "1" smd roundrect
			(at -0.48 0 180)
			(size 0.59 0.64)
			(layers "F.Cu" "F.Mask" "F.Paste")
			(roundrect_rratio 0.25)
			(net 1 "GND")
			(pintype "passive")
		)
		(pad "2" smd roundrect
			(at 0.48 0 180)
			(size 0.59 0.64)
			(layers "F.Cu" "F.Mask" "F.Paste")
			(roundrect_rratio 0.25)
			(net 246 "/SoM_Power/~{VDDIN_PWR_BAD}")
			(pintype "passive")
		)
	)
	(footprint "antmicro-footprints:LED_0603_1608Metric_G"
		(layer "F.Cu")
		(at 170.75 55.3 -90)
		(descr "LED SMD 0603 Green")
		(tags "LED SMD 0603 Green")
		(property "Reference" "D12"
			(at -0.85 1.6 90)
			(layer "F.SilkS")
			(effects
				(font
					(size 0.7 0.7)
					(thickness 0.15)
				)
				(justify right top)
			)
		)
		(property "Value" "LED_G_0603_LTST-C190GKT"
			(at -0.001 1.599 90)
			(layer "F.Fab")
			(effects
				(font
					(size 0.7 0.7)
					(thickness 0.15)
				)
				(justify right top)
			)
		)
		(property "Datasheet" "https://media.digikey.com/pdf/Data%20Sheets/Lite-On%20PDFs/LTST-C190GKT.pdf"
			(at 0 0 90)
			(layer "F.Fab")
			(hide yes)
			(effects
				(font
					(size 1.27 1.27)
					(thickness 0.15)
				)
			)
		)
		(property "Description" "LED, Green, SMD, 0603, 20 mA, 2.1 V, 569 nm"
			(at 0 0 90)
			(layer "F.Fab")
			(hide yes)
			(effects
				(font
					(size 1.27 1.27)
					(thickness 0.15)
				)
			)
		)
		(property "MPN" "LTST-C190GKT"
			(at 0 0 270)
			(unlocked yes)
			(layer "F.Fab")
			(hide yes)
			(effects
				(font
					(size 1 1)
					(thickness 0.15)
				)
			)
		)
		(property "Manufacturer" "Lite-On"
			(at 0 0 270)
			(unlocked yes)
			(layer "F.Fab")
			(hide yes)
			(effects
				(font
					(size 1 1)
					(thickness 0.15)
				)
			)
		)
		(property "Author" "Antmicro"
			(at 0 0 270)
			(unlocked yes)
			(layer "F.Fab")
			(hide yes)
			(effects
				(font
					(size 1 1)
					(thickness 0.15)
				)
			)
		)
		(property "License" "Apache-2.0"
			(at 0 0 270)
			(unlocked yes)
			(layer "F.Fab")
			(hide yes)
			(effects
				(font
					(size 1 1)
					(thickness 0.15)
				)
			)
		)
		(property "Color" "Green"
			(at 0 0 270)
			(unlocked yes)
			(layer "F.Fab")
			(hide yes)
			(effects
				(font
					(size 1 1)
					(thickness 0.15)
				)
			)
		)
		(sheetname "/Power/")
		(sheetfile "power.kicad_sch")
		(attr smd)
		(fp_line
			(start 0.22 0.35)
			(end -0.22 0.35)
			(stroke
				(width 0.15)
				(type solid)
			)
			(layer "F.SilkS")
		)
		(fp_line
			(start -0.094672 0.201008)
			(end -0.094672 -0.198992)
			(stroke
				(width 0.1)
				(type solid)
			)
			(layer "F.SilkS")
		)
		(fp_line
			(start 0.105328 0.201008)
			(end -0.094672 0.001008)
			(stroke
				(width 0.1)
				(type solid)
			)
			(layer "F.SilkS")
		)
		(fp_line
			(start 0.105328 0.201008)
			(end 0.105328 -0.198992)
			(stroke
				(width 0.1)
				(type solid)
			)
			(layer "F.SilkS")
		)
		(fp_line
			(start -0.094672 0.001008)
			(end -0.24 0.001008)
			(stroke
				(width 0.1)
				(type solid)
			)
			(layer "F.SilkS")
		)
		(fp_line
			(start -0.094672 0.001008)
			(end 0.105328 -0.198992)
			(stroke
				(width 0.1)
				(type solid)
			)
			(layer "F.SilkS")
		)
		(fp_line
			(start 0.105328 0.001008)
			(end 0.24 0.001)
			(stroke
				(width 0.1)
				(type solid)
			)
			(layer "F.SilkS")
		)
		(fp_line
			(start -1.18 -0.319)
			(end -1.18 0.321)
			(stroke
				(width 0.15)
				(type solid)
			)
			(layer "F.SilkS")
		)
		(fp_line
			(start 0.22 -0.35)
			(end -0.22 -0.35)
			(stroke
				(width 0.15)
				(type solid)
			)
			(layer "F.SilkS")
		)
		(fp_rect
			(start 1.25 0.65)
			(end -1.25 -0.65)
			(stroke
				(width 0.05)
				(type solid)
			)
			(fill no)
			(layer "F.CrtYd")
		)
		(fp_line
			(start -0.199 0.2)
			(end -0.199 0.1)
			(stroke
				(width 0.15)
				(type solid)
			)
			(layer "F.Fab")
		)
		(fp_line
			(start 0.201 0.2)
			(end 0.201 0)
			(stroke
				(width 0.15)
				(type solid)
			)
			(layer "F.Fab")
		)
		(fp_line
			(start -0.199 0)
			(end -0.597 0)
			(stroke
				(width 0.15)
				(type solid)
			)
			(layer "F.Fab")
		)
		(fp_line
			(start -0.101 0)
			(end 0.201 0.2)
			(stroke
				(width 0.15)
				(type solid)
			)
			(layer "F.Fab")
		)
		(fp_line
			(start 0.201 0)
			(end 0.201 -0.202)
			(stroke
				(width 0.15)
				(type solid)
			)
			(layer "F.Fab")
		)
		(fp_line
			(start 0.599 0)
			(end 0.201 0)
			(stroke
				(width 0.15)
				(type solid)
			)
			(layer "F.Fab")
		)
		(fp_line
			(start -0.199 -0.202)
			(end -0.199 0.1)
			(stroke
				(width 0.15)
				(type solid)
			)
			(layer "F.Fab")
		)
		(fp_line
			(start 0.201 -0.202)
			(end -0.101 0)
			(stroke
				(width 0.15)
				(type solid)
			)
			(layer "F.Fab")
		)
		(fp_rect
			(start 0.848 0.4)
			(end -0.85 -0.402)
			(stroke
				(width 0.15)
				(type solid)
			)
			(fill no)
			(layer "F.Fab")
		)
		(fp_text user "License: Apache-2.0"
			(at -1.4224 3.599 90)
			(layer "F.Fab")
			(effects
				(font
					(size 0.7 0.7)
					(thickness 0.15)
				)
				(justify right top)
			)
		)
		(fp_text user "Author: Antmicro"
			(at -1.4224 4.799 90)
			(layer "F.Fab")
			(effects
				(font
					(size 0.7 0.7)
					(thickness 0.15)
				)
				(justify right top)
			)
		)
		(fp_text user "${REFERENCE}"
			(at -1.4224 5.999 90)
			(layer "F.Fab")
			(effects
				(font
					(size 0.7 0.7)
					(thickness 0.15)
				)
				(justify right top)
			)
		)
		(pad "1" smd roundrect
			(at -0.7 0 90)
			(size 0.8 1)
			(layers "F.Cu" "F.Mask" "F.Paste")
			(roundrect_rratio 0.2)
			(net 1 "GND")
			(pinfunction "C")
			(pintype "passive")
		)
		(pad "2" smd roundrect
			(at 0.7 0 90)
			(size 0.8 1)
			(layers "F.Cu" "F.Mask" "F.Paste")
			(roundrect_rratio 0.2)
			(net 490 "Net-(D12-A)")
			(pinfunction "A")
			(pintype "passive")
		)
	)
	(footprint "antmicro-footprints:C_0805_2012Metric"
		(layer "F.Cu")
		(at 115.12 56.74 -90)
		(descr "Capacitor SMD 0805")
		(tags "capacitor SMD 0805")
		(property "Reference" "C378"
			(at -1.87 0.05 180)
			(layer "F.SilkS")
			(effects
				(font
					(size 0.7 0.7)
					(thickness 0.15)
				)
				(justify left bottom)
			)
		)
		(property "Value" "C_22u_25V_0805"
			(at -2.055717 1.963152 90)
			(layer "F.Fab")
			(effects
				(font
					(size 0.7 0.7)
					(thickness 0.15)
				)
				(justify right top)
			)
		)
		(property "Datasheet" "https://product.samsungsem.com/mlcc/CL21A226MAYNNN.do"
			(at 0 0 90)
			(layer "F.Fab")
			(hide yes)
			(effects
				(font
					(size 1.27 1.27)
					(thickness 0.15)
				)
			)
		)
		(property "Description" "SMT Multilayer Ceramic Capacitor, 22uF, +/-20%, 25V, X5R, 0805 [2012 Metric]"
			(at 0 0 90)
			(layer "F.Fab")
			(hide yes)
			(effects
				(font
					(size 1.27 1.27)
					(thickness 0.15)
				)
			)
		)
		(property "MPN" "CL21A226MAYNNNE"
			(at 0 0 270)
			(unlocked yes)
			(layer "F.Fab")
			(hide yes)
			(effects
				(font
					(size 1 1)
					(thickness 0.15)
				)
			)
		)
		(property "Manufacturer" "Samsung Electro-Mechanics"
			(at 0 0 270)
			(unlocked yes)
			(layer "F.Fab")
			(hide yes)
			(effects
				(font
					(size 1 1)
					(thickness 0.15)
				)
			)
		)
		(property "License" "Apache-2.0"
			(at 0 0 270)
			(unlocked yes)
			(layer "F.Fab")
			(hide yes)
			(effects
				(font
					(size 1 1)
					(thickness 0.15)
				)
			)
		)
		(property "Author" "Antmicro"
			(at 0 0 270)
			(unlocked yes)
			(layer "F.Fab")
			(hide yes)
			(effects
				(font
					(size 1 1)
					(thickness 0.15)
				)
			)
		)
		(property "Val" "22u"
			(at 0 0 270)
			(unlocked yes)
			(layer "F.Fab")
			(hide yes)
			(effects
				(font
					(size 1 1)
					(thickness 0.15)
				)
			)
		)
		(property "Voltage" "25V"
			(at 0 0 270)
			(unlocked yes)
			(layer "F.Fab")
			(hide yes)
			(effects
				(font
					(size 1 1)
					(thickness 0.15)
				)
			)
		)
		(property "Dielectric" "X5R"
			(at 0 0 270)
			(unlocked yes)
			(layer "F.Fab")
			(hide yes)
			(effects
				(font
					(size 1 1)
					(thickness 0.15)
				)
			)
		)
		(property "Public" "False"
			(at 0 0 270)
			(unlocked yes)
			(layer "F.Fab")
			(hide yes)
			(effects
				(font
					(size 1 1)
					(thickness 0.15)
				)
			)
		)
		(sheetname "/DCDC/")
		(sheetfile "dcdc.kicad_sch")
		(attr smd)
		(fp_line
			(start -0.3 0.7)
			(end 0.3 0.7)
			(stroke
				(width 0.15)
				(type solid)
			)
			(layer "F.SilkS")
		)
		(fp_line
			(start -0.3 -0.7)
			(end 0.3 -0.7)
			(stroke
				(width 0.15)
				(type solid)
			)
			(layer "F.SilkS")
		)
		(fp_rect
			(start 1.95 -0.9)
			(end -1.95 0.9)
			(stroke
				(width 0.05)
				(type default)
			)
			(fill no)
			(layer "F.CrtYd")
		)
		(fp_rect
			(start -0.95 -0.675)
			(end 0.95 0.675)
			(stroke
				(width 0.15)
				(type solid)
			)
			(fill no)
			(layer "F.Fab")
		)
		(fp_text user "${REFERENCE}"
			(at -1.9 3.947 90)
			(layer "F.Fab")
			(effects
				(font
					(size 0.7 0.7)
					(thickness 0.15)
				)
				(justify right top)
			)
		)
		(fp_text user "Author: Antmicro"
			(at -1.9 5.947 90)
			(layer "F.Fab")
			(effects
				(font
					(size 0.7 0.7)
					(thickness 0.15)
				)
				(justify right top)
			)
		)
		(fp_text user "License: Apache-2.0"
			(at -1.9 4.947 90)
			(layer "F.Fab")
			(effects
				(font
					(size 0.7 0.7)
					(thickness 0.15)
				)
				(justify right top)
			)
		)
		(pad "1" smd roundrect
			(at -1.1 0 270)
			(size 1.2 1.3)
			(layers "F.Cu" "F.Mask" "F.Paste")
			(roundrect_rratio 0.25)
			(net 1 "GND")
			(pintype "passive")
		)
		(pad "2" smd roundrect
			(at 1.1 0 270)
			(size 1.2 1.3)
			(layers "F.Cu" "F.Mask" "F.Paste")
			(roundrect_rratio 0.25)
			(net 1278 "/DCDC/5V_{AON}_OUT")
			(pintype "passive")
		)
	)
	(footprint "antmicro-footprints:USON-10_2.5x1mm_P0.5mm"
		(layer "F.Cu")
		(at 220.853 131.573 180)
		(descr "USON-10 2.5x1mm_ Pitch 0.5mm")
		(tags "USON-10 2.5x1mm Pitch 0.5mm")
		(property "Reference" "U19"
			(at -1.107 0.393 90)
			(layer "F.SilkS")
			(effects
				(font
					(size 0.7 0.7)
					(thickness 0.15)
				)
				(justify right top)
			)
		)
		(property "Value" "TPD4E05U06QDQARQ1"
			(at 0.018 2.499 0)
			(layer "F.Fab")
			(effects
				(font
					(size 0.7 0.7)
					(thickness 0.15)
				)
				(justify right top)
			)
		)
		(property "Datasheet" "https://www.ti.com/lit/ds/symlink/tpd4e05u06-q1.pdf?HQS=dis-mous-null-mousermode-dsf-pf-null-wwe&ts=1663591265741&ref_url=https%253A%252F%252Fwww.mouser.com%252F"
			(at 0 0 0)
			(layer "F.Fab")
			(hide yes)
			(effects
				(font
					(size 1.27 1.27)
					(thickness 0.15)
				)
			)
		)
		(property "Description" "TVS diode array, 12 kV, USON-10, 5.5 V, 0.5 pF"
			(at 0 0 0)
			(layer "F.Fab")
			(hide yes)
			(effects
				(font
					(size 1.27 1.27)
					(thickness 0.15)
				)
			)
		)
		(property "Manufacturer" "Texas Instruments"
			(at 0 0 180)
			(unlocked yes)
			(layer "F.Fab")
			(hide yes)
			(effects
				(font
					(size 1 1)
					(thickness 0.15)
				)
			)
		)
		(property "MPN" "TPD4E05U06QDQARQ1"
			(at 0 0 180)
			(unlocked yes)
			(layer "F.Fab")
			(hide yes)
			(effects
				(font
					(size 1 1)
					(thickness 0.15)
				)
			)
		)
		(property "Author" "Antmicro"
			(at 0 0 180)
			(unlocked yes)
			(layer "F.Fab")
			(hide yes)
			(effects
				(font
					(size 1 1)
					(thickness 0.15)
				)
			)
		)
		(property "License" "Apache-2.0"
			(at 0 0 180)
			(unlocked yes)
			(layer "F.Fab")
			(hide yes)
			(effects
				(font
					(size 1 1)
					(thickness 0.15)
				)
			)
		)
		(sheetname "/USB Hub/")
		(sheetfile "usb_hub.kicad_sch")
		(attr smd)
		(fp_line
			(start 0.498 1.398)
			(end -0.5 1.398)
			(stroke
				(width 0.15)
				(type solid)
			)
			(layer "F.SilkS")
		)
		(fp_line
			(start 0.498 -1.401)
			(end -0.5 -1.401)
			(stroke
				(width 0.15)
				(type solid)
			)
			(layer "F.SilkS")
		)
		(fp_circle
			(center -0.68 -1.27)
			(end -0.63 -1.27)
			(stroke
				(width 0.15)
				(type solid)
			)
			(fill yes)
			(layer "F.SilkS")
		)
		(fp_rect
			(start -0.8 -1.5)
			(end 0.8 1.499)
			(stroke
				(width 0.05)
				(type solid)
			)
			(fill no)
			(layer "F.CrtYd")
		)
		(fp_line
			(start 0.498 -1.25)
			(end 0.498 1.249)
			(stroke
				(width 0.15)
				(type solid)
			)
			(layer "F.Fab")
		)
		(fp_line
			(start 0.498 -1.25)
			(end -0.25 -1.25)
			(stroke
				(width 0.15)
				(type solid)
			)
			(layer "F.Fab")
		)
		(fp_line
			(start -0.25 -1.25)
			(end -0.5 -1)
			(stroke
				(width 0.15)
				(type solid)
			)
			(layer "F.Fab")
		)
		(fp_line
			(start -0.5 1.249)
			(end 0.498 1.249)
			(stroke
				(width 0.15)
				(type solid)
			)
			(layer "F.Fab")
		)
		(fp_line
			(start -0.5 -1)
			(end -0.5 1.249)
			(stroke
				(width 0.15)
				(type solid)
			)
			(layer "F.Fab")
		)
		(fp_text user "License: Apache-2.0"
			(at -0.802 6.9 0)
			(layer "F.Fab")
			(effects
				(font
					(size 0.7 0.7)
					(thickness 0.15)
				)
				(justify right top)
			)
		)
		(fp_text user "Author: Antmicro"
			(at -0.802 5.7 0)
			(layer "F.Fab")
			(effects
				(font
					(size 0.7 0.7)
					(thickness 0.15)
				)
				(justify right top)
			)
		)
		(fp_text user "${REFERENCE}"
			(at -0.802 4.498 0)
			(layer "F.Fab")
			(effects
				(font
					(size 0.7 0.7)
					(thickness 0.15)
				)
				(justify right top)
			)
		)
		(pad "1" smd roundrect
			(at -0.387 -1 90)
			(size 0.25 0.55)
			(layers "F.Cu" "F.Mask" "F.Paste")
			(roundrect_rratio 0.25)
			(net 78 "/USB Hub/USBC4_CONN_TX1_P")
			(pintype "passive")
		)
		(pad "2" smd roundrect
			(at -0.387 -0.5 90)
			(size 0.25 0.55)
			(layers "F.Cu" "F.Mask" "F.Paste")
			(roundrect_rratio 0.25)
			(net 91 "/USB Hub/USBC4_CONN_TX1_N")
			(pintype "passive")
		)
		(pad "3" smd roundrect
			(at -0.387 0 90)
			(size 0.4 0.55)
			(layers "F.Cu" "F.Mask" "F.Paste")
			(roundrect_rratio 0.25)
			(net 1 "GND")
			(pintype "power_in")
		)
		(pad "4" smd roundrect
			(at -0.387 0.498 90)
			(size 0.25 0.55)
			(layers "F.Cu" "F.Mask" "F.Paste")
			(roundrect_rratio 0.25)
			(net 504 "/USB Hub/USBC4_RX_{1}+")
			(pintype "passive")
		)
		(pad "5" smd roundrect
			(at -0.387 0.998 90)
			(size 0.25 0.55)
			(layers "F.Cu" "F.Mask" "F.Paste")
			(roundrect_rratio 0.25)
			(net 501 "/USB Hub/USBC4_RX_{1}-")
			(pintype "passive")
		)
		(pad "6" smd roundrect
			(at 0.385 0.998 90)
			(size 0.25 0.55)
			(layers "F.Cu" "F.Mask" "F.Paste")
			(roundrect_rratio 0.25)
			(net 501 "/USB Hub/USBC4_RX_{1}-")
			(pintype "passive")
		)
		(pad "7" smd roundrect
			(at 0.385 0.498 90)
			(size 0.25 0.55)
			(layers "F.Cu" "F.Mask" "F.Paste")
			(roundrect_rratio 0.25)
			(net 504 "/USB Hub/USBC4_RX_{1}+")
			(pintype "passive")
		)
		(pad "8" smd roundrect
			(at 0.385 0 90)
			(size 0.4 0.55)
			(layers "F.Cu" "F.Mask" "F.Paste")
			(roundrect_rratio 0.25)
			(net 1 "GND")
			(pintype "passive")
		)
		(pad "9" smd roundrect
			(at 0.385 -0.5 90)
			(size 0.25 0.55)
			(layers "F.Cu" "F.Mask" "F.Paste")
			(roundrect_rratio 0.25)
			(net 91 "/USB Hub/USBC4_CONN_TX1_N")
			(pintype "passive")
		)
		(pad "10" smd roundrect
			(at 0.385 -1 90)
			(size 0.25 0.55)
			(layers "F.Cu" "F.Mask" "F.Paste")
			(roundrect_rratio 0.25)
			(net 78 "/USB Hub/USBC4_CONN_TX1_P")
			(pintype "passive")
		)
	)
	(footprint "antmicro-footprints:Oscillator_SMD_ECS_2016MV_2x1.6x0.85mm"
		(layer "F.Cu")
		(at 210.8 135.2 180)
		(property "Reference" "Y2"
			(at -3.1 -0.6 90)
			(layer "F.SilkS")
			(effects
				(font
					(size 0.7 0.7)
					(thickness 0.15)
				)
				(justify left bottom)
			)
		)
		(property "Value" "Oscillator_25MHz_ESC_2016MV"
			(at 0 2.2 0)
			(layer "F.Fab")
			(effects
				(font
					(size 0.7 0.7)
					(thickness 0.15)
				)
				(justify right top)
			)
		)
		(property "Datasheet" "https://ecsxtal.com/store/pdf/ECS-2016MV.pdf"
			(at 0 0 0)
			(layer "F.Fab")
			(hide yes)
			(effects
				(font
					(size 1.27 1.27)
					(thickness 0.15)
				)
			)
		)
		(property "Description" "Oscillator, 25 MHz, HCMOS, SMD, 2mm x 1.6mm, MultiVolt ECS-2016MV Series"
			(at 0 0 0)
			(layer "F.Fab")
			(hide yes)
			(effects
				(font
					(size 1.27 1.27)
					(thickness 0.15)
				)
			)
		)
		(property "MPN" "ECS-2016MV-250-CN-TR"
			(at 0 0 180)
			(unlocked yes)
			(layer "F.Fab")
			(hide yes)
			(effects
				(font
					(size 1 1)
					(thickness 0.15)
				)
			)
		)
		(property "Manufacturer" "ECS Inc. International"
			(at 0 0 180)
			(unlocked yes)
			(layer "F.Fab")
			(hide yes)
			(effects
				(font
					(size 1 1)
					(thickness 0.15)
				)
			)
		)
		(property "Val" "25 MHz"
			(at 0 0 180)
			(unlocked yes)
			(layer "F.Fab")
			(hide yes)
			(effects
				(font
					(size 1 1)
					(thickness 0.15)
				)
			)
		)
		(property "Author" "Antmicro"
			(at 0 0 180)
			(unlocked yes)
			(layer "F.Fab")
			(hide yes)
			(effects
				(font
					(size 1 1)
					(thickness 0.15)
				)
			)
		)
		(property "License" "Apache-2.0"
			(at 0 0 180)
			(unlocked yes)
			(layer "F.Fab")
			(hide yes)
			(effects
				(font
					(size 1 1)
					(thickness 0.15)
				)
			)
		)
		(sheetname "/USB Hub/")
		(sheetfile "usb_hub.kicad_sch")
		(attr smd)
		(fp_line
			(start 0.95 0.4)
			(end 0.95 -0.4)
			(stroke
				(width 0.15)
				(type solid)
			)
			(layer "F.SilkS")
		)
		(fp_line
			(start -0.4 1.15)
			(end 0.4 1.15)
			(stroke
				(width 0.15)
				(type solid)
			)
			(layer "F.SilkS")
		)
		(fp_line
			(start -0.4 -1.15)
			(end 0.4 -1.15)
			(stroke
				(width 0.15)
				(type solid)
			)
			(layer "F.SilkS")
		)
		(fp_line
			(start -0.95 0.4)
			(end -0.95 -0.4)
			(stroke
				(width 0.15)
				(type solid)
			)
			(layer "F.SilkS")
		)
		(fp_circle
			(center -0.95 -1.15)
			(end -0.9 -1.15)
			(stroke
				(width 0.15)
				(type solid)
			)
			(fill yes)
			(layer "F.SilkS")
		)
		(fp_rect
			(start -1.05 -1.25)
			(end 1.05 1.24)
			(stroke
				(width 0.05)
				(type solid)
			)
			(fill no)
			(layer "F.CrtYd")
		)
		(fp_rect
			(start -0.85 -1.054)
			(end 0.852 1.054)
			(stroke
				(width 0.15)
				(type solid)
			)
			(fill no)
			(layer "F.Fab")
		)
		(fp_text user "${REFERENCE}"
			(at -1.05 3.4 0)
			(layer "F.Fab")
			(effects
				(font
					(size 0.7 0.7)
					(thickness 0.15)
				)
				(justify right top)
			)
		)
		(fp_text user "License: Apache-2.0"
			(at -1.05 5.8 0)
			(layer "F.Fab")
			(effects
				(font
					(size 0.7 0.7)
					(thickness 0.15)
				)
				(justify right top)
			)
		)
		(fp_text user "Author: Antmicro"
			(at -1.05 4.6 0)
			(layer "F.Fab")
			(effects
				(font
					(size 0.7 0.7)
					(thickness 0.15)
				)
				(justify right top)
			)
		)
		(pad "1" smd rect
			(at -0.486 -0.637 180)
			(size 0.6858 0.7874)
			(layers "F.Cu" "F.Mask" "F.Paste")
			(net 2 "+3V3")
			(pinfunction "EN")
			(pintype "input")
		)
		(pad "2" smd rect
			(at -0.486 0.636 180)
			(size 0.6858 0.7874)
			(layers "F.Cu" "F.Mask" "F.Paste")
			(net 1 "GND")
			(pinfunction "GND")
			(pintype "power_in")
		)
		(pad "3" smd rect
			(at 0.487 0.636 180)
			(size 0.6858 0.7874)
			(layers "F.Cu" "F.Mask" "F.Paste")
			(net 1078 "Net-(U21-XTALI)")
			(pinfunction "OUT")
			(pintype "output")
		)
		(pad "4" smd rect
			(at 0.487 -0.637 180)
			(size 0.6858 0.7874)
			(layers "F.Cu" "F.Mask" "F.Paste")
			(net 2 "+3V3")
			(pinfunction "VDD")
			(pintype "power_in")
		)
	)
	(footprint "antmicro-footprints:R_0402_1005Metric"
		(layer "F.Cu")
		(at 143.56 135.04 180)
		(descr "Resistor SMD 0402")
		(tags "resistor SMD 0402")
		(property "Reference" "R60"
			(at -1.122484 -0.772697 0)
			(layer "F.SilkS")
			(effects
				(font
					(size 0.7 0.7)
					(thickness 0.15)
				)
				(justify right top)
			)
		)
		(property "Value" "R_470R_0402"
			(at -1.011843 1.772047 0)
			(layer "F.Fab")
			(effects
				(font
					(size 0.7 0.7)
					(thickness 0.15)
				)
				(justify right top)
			)
		)
		(property "Datasheet" "https://www.bourns.com/docs/product-datasheets/cr.pdf"
			(at 0 0 0)
			(layer "F.Fab")
			(hide yes)
			(effects
				(font
					(size 1.27 1.27)
					(thickness 0.15)
				)
			)
		)
		(property "Description" "SMD Chip Resistor, 470 ohm, ± 1%, 62.5 mW, 0402 [1005 Metric], Thick Film, General Purpose"
			(at 0 0 0)
			(layer "F.Fab")
			(hide yes)
			(effects
				(font
					(size 1.27 1.27)
					(thickness 0.15)
				)
			)
		)
		(property "MPN" "CR0402-FX-4700GLF"
			(at 0 0 180)
			(unlocked yes)
			(layer "F.Fab")
			(hide yes)
			(effects
				(font
					(size 1 1)
					(thickness 0.15)
				)
			)
		)
		(property "Manufacturer" "Bourns"
			(at 0 0 180)
			(unlocked yes)
			(layer "F.Fab")
			(hide yes)
			(effects
				(font
					(size 1 1)
					(thickness 0.15)
				)
			)
		)
		(property "License" "Apache-2.0"
			(at 0 0 180)
			(unlocked yes)
			(layer "F.Fab")
			(hide yes)
			(effects
				(font
					(size 1 1)
					(thickness 0.15)
				)
			)
		)
		(property "Author" "Antmicro"
			(at 0 0 180)
			(unlocked yes)
			(layer "F.Fab")
			(hide yes)
			(effects
				(font
					(size 1 1)
					(thickness 0.15)
				)
			)
		)
		(property "Val" "470R"
			(at 0 0 180)
			(unlocked yes)
			(layer "F.Fab")
			(hide yes)
			(effects
				(font
					(size 1 1)
					(thickness 0.15)
				)
			)
		)
		(property "Tolerance" "1%"
			(at 0 0 180)
			(unlocked yes)
			(layer "F.Fab")
			(hide yes)
			(effects
				(font
					(size 1 1)
					(thickness 0.15)
				)
			)
		)
		(sheetname "/SoM_Power/")
		(sheetfile "som_power.kicad_sch")
		(attr smd)
		(fp_rect
			(start -0.925 -0.47)
			(end 0.925 0.47)
			(stroke
				(width 0.05)
				(type default)
			)
			(fill no)
			(layer "F.CrtYd")
		)
		(fp_rect
			(start -0.5 -0.25)
			(end 0.5 0.25)
			(stroke
				(width 0.15)
				(type solid)
			)
			(fill no)
			(layer "F.Fab")
		)
		(fp_text user "License: Apache-2.0"
			(at -0.95 5.169 0)
			(layer "F.Fab")
			(effects
				(font
					(size 0.7 0.7)
					(thickness 0.15)
				)
				(justify right top)
			)
		)
		(fp_text user "Author: Antmicro"
			(at -0.95 4.169 0)
			(layer "F.Fab")
			(effects
				(font
					(size 0.7 0.7)
					(thickness 0.15)
				)
				(justify right top)
			)
		)
		(fp_text user "${REFERENCE}"
			(at -0.95 3.168 0)
			(layer "F.Fab")
			(effects
				(font
					(size 0.7 0.7)
					(thickness 0.15)
				)
				(justify right top)
			)
		)
		(pad "1" smd roundrect
			(at -0.48 0 180)
			(size 0.59 0.64)
			(layers "F.Cu" "F.Mask" "F.Paste")
			(roundrect_rratio 0.25)
			(net 1303 "Net-(Q38-D)")
			(pintype "passive")
		)
		(pad "2" smd roundrect
			(at 0.48 0 180)
			(size 0.59 0.64)
			(layers "F.Cu" "F.Mask" "F.Paste")
			(roundrect_rratio 0.25)
			(net 11 "+1V8")
			(pintype "passive")
		)
	)
	(footprint "antmicro-footprints:R_0402_1005Metric"
		(layer "F.Cu")
		(at 196.6 73.5 -90)
		(descr "Resistor SMD 0402")
		(tags "resistor SMD 0402")
		(property "Reference" "R225"
			(at -3.8 0.4 90)
			(layer "F.SilkS")
			(effects
				(font
					(size 0.7 0.7)
					(thickness 0.15)
				)
				(justify right top)
			)
		)
		(property "Value" "R_4k7_0402"
			(at -1.011843 1.772046 90)
			(layer "F.Fab")
			(effects
				(font
					(size 0.7 0.7)
					(thickness 0.15)
				)
				(justify right top)
			)
		)
		(property "Datasheet" "https://www.bourns.com/docs/product-datasheets/cr.pdf"
			(at 0 0 90)
			(layer "F.Fab")
			(hide yes)
			(effects
				(font
					(size 1.27 1.27)
					(thickness 0.15)
				)
			)
		)
		(property "Description" "SMD Chip Resistor, 4.7 kohm, ± 1%, 62.5 mW, 0402 [1005 Metric], Thick Film, General Purpose"
			(at 0 0 90)
			(layer "F.Fab")
			(hide yes)
			(effects
				(font
					(size 1.27 1.27)
					(thickness 0.15)
				)
			)
		)
		(property "Manufacturer" "Bourns"
			(at 0 0 270)
			(unlocked yes)
			(layer "F.Fab")
			(hide yes)
			(effects
				(font
					(size 1 1)
					(thickness 0.15)
				)
			)
		)
		(property "MPN" "CR0402-FX-4701GLF"
			(at 0 0 270)
			(unlocked yes)
			(layer "F.Fab")
			(hide yes)
			(effects
				(font
					(size 1 1)
					(thickness 0.15)
				)
			)
		)
		(property "Val" "4k7"
			(at 0 0 270)
			(unlocked yes)
			(layer "F.Fab")
			(hide yes)
			(effects
				(font
					(size 1 1)
					(thickness 0.15)
				)
			)
		)
		(property "License" "Apache-2.0"
			(at 0 0 270)
			(unlocked yes)
			(layer "F.Fab")
			(hide yes)
			(effects
				(font
					(size 1 1)
					(thickness 0.15)
				)
			)
		)
		(property "Author" "Antmicro"
			(at 0 0 270)
			(unlocked yes)
			(layer "F.Fab")
			(hide yes)
			(effects
				(font
					(size 1 1)
					(thickness 0.15)
				)
			)
		)
		(property "Tolerance" "1%"
			(at 0 0 270)
			(unlocked yes)
			(layer "F.Fab")
			(hide yes)
			(effects
				(font
					(size 1 1)
					(thickness 0.15)
				)
			)
		)
		(sheetname "/USB Debug, PD/")
		(sheetfile "usb_debug_pd.kicad_sch")
		(attr smd)
		(fp_poly
			(pts
				(xy -0.925 -0.47) (xy 0.925 -0.47) (xy 0.925 0.47) (xy -0.925 0.47)
			)
			(stroke
				(width 0.05)
				(type default)
			)
			(fill no)
			(layer "F.CrtYd")
		)
		(fp_poly
			(pts
				(xy -0.5 -0.25) (xy 0.5 -0.25) (xy 0.5 0.25) (xy -0.5 0.25)
			)
			(stroke
				(width 0.15)
				(type solid)
			)
			(fill no)
			(layer "F.Fab")
		)
		(fp_text user "${REFERENCE}"
			(at -0.95 3.168 90)
			(layer "F.Fab")
			(effects
				(font
					(size 0.7 0.7)
					(thickness 0.15)
				)
				(justify right top)
			)
		)
		(fp_text user "Author: Antmicro"
			(at -0.95 4.169 90)
			(layer "F.Fab")
			(effects
				(font
					(size 0.7 0.7)
					(thickness 0.15)
				)
				(justify right top)
			)
		)
		(fp_text user "License: Apache-2.0"
			(at -0.949999 5.169 90)
			(layer "F.Fab")
			(effects
				(font
					(size 0.7 0.7)
					(thickness 0.15)
				)
				(justify right top)
			)
		)
		(pad "1" smd roundrect
			(at -0.48 0 270)
			(size 0.59 0.64)
			(layers "F.Cu" "F.Mask" "F.Paste")
			(roundrect_rratio 0.25)
			(net 2 "+3V3")
			(pintype "passive")
		)
		(pad "2" smd roundrect
			(at 0.48 0 270)
			(size 0.59 0.64)
			(layers "F.Cu" "F.Mask" "F.Paste")
			(roundrect_rratio 0.25)
			(net 953 "/USB Debug, PD/PDC_I2C1_IRQn")
			(pintype "passive")
		)
	)
	(footprint "antmicro-footprints:C_0805_2012Metric"
		(layer "F.Cu")
		(at 172.555 126.93 90)
		(descr "Capacitor SMD 0805")
		(tags "capacitor SMD 0805")
		(property "Reference" "C273"
			(at 1.53 -4.855 90)
			(layer "F.SilkS")
			(effects
				(font
					(size 0.7 0.7)
					(thickness 0.15)
				)
				(justify left bottom)
			)
		)
		(property "Value" "C_22u_25V_0805"
			(at -2.055717 1.963152 90)
			(layer "F.Fab")
			(effects
				(font
					(size 0.7 0.7)
					(thickness 0.15)
				)
				(justify left bottom)
			)
		)
		(property "Datasheet" "https://product.samsungsem.com/mlcc/CL21A226MAYNNN.do"
			(at 0 0 90)
			(layer "F.Fab")
			(hide yes)
			(effects
				(font
					(size 1.27 1.27)
					(thickness 0.15)
				)
			)
		)
		(property "Description" "SMT Multilayer Ceramic Capacitor, 22uF, +/-20%, 25V, X5R, 0805 [2012 Metric]"
			(at 0 0 90)
			(layer "F.Fab")
			(hide yes)
			(effects
				(font
					(size 1.27 1.27)
					(thickness 0.15)
				)
			)
		)
		(property "MPN" "CL21A226MAYNNNE"
			(at 0 0 90)
			(unlocked yes)
			(layer "F.Fab")
			(hide yes)
			(effects
				(font
					(size 1 1)
					(thickness 0.15)
				)
			)
		)
		(property "Manufacturer" "Samsung Electro-Mechanics"
			(at 0 0 90)
			(unlocked yes)
			(layer "F.Fab")
			(hide yes)
			(effects
				(font
					(size 1 1)
					(thickness 0.15)
				)
			)
		)
		(property "License" "Apache-2.0"
			(at 0 0 90)
			(unlocked yes)
			(layer "F.Fab")
			(hide yes)
			(effects
				(font
					(size 1 1)
					(thickness 0.15)
				)
			)
		)
		(property "Author" "Antmicro"
			(at 0 0 90)
			(unlocked yes)
			(layer "F.Fab")
			(hide yes)
			(effects
				(font
					(size 1 1)
					(thickness 0.15)
				)
			)
		)
		(property "Val" "22u"
			(at 0 0 90)
			(unlocked yes)
			(layer "F.Fab")
			(hide yes)
			(effects
				(font
					(size 1 1)
					(thickness 0.15)
				)
			)
		)
		(property "Voltage" "25V"
			(at 0 0 90)
			(unlocked yes)
			(layer "F.Fab")
			(hide yes)
			(effects
				(font
					(size 1 1)
					(thickness 0.15)
				)
			)
		)
		(property "Dielectric" "X5R"
			(at 0 0 90)
			(unlocked yes)
			(layer "F.Fab")
			(hide yes)
			(effects
				(font
					(size 1 1)
					(thickness 0.15)
				)
			)
		)
		(property "Public" "False"
			(at 0 0 90)
			(unlocked yes)
			(layer "F.Fab")
			(hide yes)
			(effects
				(font
					(size 1 1)
					(thickness 0.15)
				)
			)
		)
		(sheetname "/DCDC/")
		(sheetfile "dcdc.kicad_sch")
		(attr smd)
		(fp_line
			(start -0.3 -0.7)
			(end 0.3 -0.7)
			(stroke
				(width 0.15)
				(type solid)
			)
			(layer "F.SilkS")
		)
		(fp_line
			(start -0.3 0.7)
			(end 0.3 0.7)
			(stroke
				(width 0.15)
				(type solid)
			)
			(layer "F.SilkS")
		)
		(fp_rect
			(start 1.95 -0.9)
			(end -1.95 0.9)
			(stroke
				(width 0.05)
				(type default)
			)
			(fill no)
			(layer "F.CrtYd")
		)
		(fp_rect
			(start -0.95 -0.675)
			(end 0.95 0.675)
			(stroke
				(width 0.15)
				(type solid)
			)
			(fill no)
			(layer "F.Fab")
		)
		(fp_text user "Author: Antmicro"
			(at -1.9 5.947 90)
			(layer "F.Fab")
			(effects
				(font
					(size 0.7 0.7)
					(thickness 0.15)
				)
				(justify left bottom)
			)
		)
		(fp_text user "License: Apache-2.0"
			(at -1.9 4.947 90)
			(layer "F.Fab")
			(effects
				(font
					(size 0.7 0.7)
					(thickness 0.15)
				)
				(justify left bottom)
			)
		)
		(fp_text user "${REFERENCE}"
			(at -1.9 3.947 90)
			(layer "F.Fab")
			(effects
				(font
					(size 0.7 0.7)
					(thickness 0.15)
				)
				(justify left bottom)
			)
		)
		(pad "1" smd roundrect
			(at -1.1 0 90)
			(size 1.2 1.3)
			(layers "F.Cu" "F.Mask" "F.Paste")
			(roundrect_rratio 0.25)
			(net 1 "GND")
			(pintype "passive")
		)
		(pad "2" smd roundrect
			(at 1.1 0 90)
			(size 1.2 1.3)
			(layers "F.Cu" "F.Mask" "F.Paste")
			(roundrect_rratio 0.25)
			(net 13 "VCC")
			(pintype "passive")
		)
	)
	(footprint "antmicro-footprints:C_0402_1005Metric"
		(layer "F.Cu")
		(at 127.819999 64.87 180)
		(descr "Capacitor SMD 0402")
		(tags "capacitor SMD 0402")
		(property "Reference" "C375"
			(at -1.860001 -0.52 0)
			(layer "F.SilkS")
			(effects
				(font
					(size 0.7 0.7)
					(thickness 0.15)
				)
				(justify right top)
			)
		)
		(property "Value" "C_1u_0402"
			(at -1.022927 2.155213 0)
			(layer "F.Fab")
			(effects
				(font
					(size 0.7 0.7)
					(thickness 0.15)
				)
				(justify right top)
			)
		)
		(property "Datasheet" "https://product.tdk.com/en/search/capacitor/ceramic/mlcc/info?part_no=C1005X6S1A105K050BC"
			(at 0 0 0)
			(layer "F.Fab")
			(hide yes)
			(effects
				(font
					(size 1.27 1.27)
					(thickness 0.15)
				)
			)
		)
		(property "Description" "SMD Multilayer Ceramic Capacitor, 1 µF, 10 V, 0402 [1005 Metric], ± 10%, X6S, C"
			(at 0 0 0)
			(layer "F.Fab")
			(hide yes)
			(effects
				(font
					(size 1.27 1.27)
					(thickness 0.15)
				)
			)
		)
		(property "Manufacturer" "TDK"
			(at 0 0 180)
			(unlocked yes)
			(layer "F.Fab")
			(hide yes)
			(effects
				(font
					(size 1 1)
					(thickness 0.15)
				)
			)
		)
		(property "MPN" "C1005X6S1A105K050BC"
			(at 0 0 180)
			(unlocked yes)
			(layer "F.Fab")
			(hide yes)
			(effects
				(font
					(size 1 1)
					(thickness 0.15)
				)
			)
		)
		(property "Val" "1u"
			(at 0 0 180)
			(unlocked yes)
			(layer "F.Fab")
			(hide yes)
			(effects
				(font
					(size 1 1)
					(thickness 0.15)
				)
			)
		)
		(property "License" "Apache-2.0"
			(at 0 0 180)
			(unlocked yes)
			(layer "F.Fab")
			(hide yes)
			(effects
				(font
					(size 1 1)
					(thickness 0.15)
				)
			)
		)
		(property "Author" "Antmicro"
			(at 0 0 180)
			(unlocked yes)
			(layer "F.Fab")
			(hide yes)
			(effects
				(font
					(size 1 1)
					(thickness 0.15)
				)
			)
		)
		(property "Voltage" ""
			(at 0 0 180)
			(unlocked yes)
			(layer "F.Fab")
			(hide yes)
			(effects
				(font
					(size 1 1)
					(thickness 0.15)
				)
			)
		)
		(property "Dielectric" ""
			(at 0 0 180)
			(unlocked yes)
			(layer "F.Fab")
			(hide yes)
			(effects
				(font
					(size 1 1)
					(thickness 0.15)
				)
			)
		)
		(sheetname "/DCDC/")
		(sheetfile "dcdc.kicad_sch")
		(attr smd)
		(fp_poly
			(pts
				(xy -0.925 -0.47) (xy -0.925 0.47) (xy 0.925 0.47) (xy 0.925 -0.47)
			)
			(stroke
				(width 0.05)
				(type default)
			)
			(fill no)
			(layer "F.CrtYd")
		)
		(fp_line
			(start 0.504 0.248)
			(end -0.494 0.248)
			(stroke
				(width 0.15)
				(type solid)
			)
			(layer "F.Fab")
		)
		(fp_line
			(start 0.504 -0.25)
			(end 0.504 0.248)
			(stroke
				(width 0.15)
				(type solid)
			)
			(layer "F.Fab")
		)
		(fp_line
			(start -0.494 0.248)
			(end -0.494 -0.25)
			(stroke
				(width 0.15)
				(type solid)
			)
			(layer "F.Fab")
		)
		(fp_line
			(start -0.494 -0.25)
			(end 0.504 -0.25)
			(stroke
				(width 0.15)
				(type solid)
			)
			(layer "F.Fab")
		)
		(fp_text user "License: Apache-2.0"
			(at -0.939 5.799 0)
			(layer "F.Fab")
			(effects
				(font
					(size 0.7 0.7)
					(thickness 0.15)
				)
				(justify right top)
			)
		)
		(fp_text user "${REFERENCE}"
			(at -0.939 4.599 0)
			(layer "F.Fab")
			(effects
				(font
					(size 0.7 0.7)
					(thickness 0.15)
				)
				(justify right top)
			)
		)
		(fp_text user "Author: Antmicro"
			(at -0.939 3.399 0)
			(layer "F.Fab")
			(effects
				(font
					(size 0.7 0.7)
					(thickness 0.15)
				)
				(justify right top)
			)
		)
		(pad "1" smd roundrect
			(at -0.48 0 180)
			(size 0.59 0.64)
			(layers "F.Cu" "F.Mask" "F.Paste")
			(roundrect_rratio 0.25)
			(net 1 "GND")
			(pintype "passive")
		)
		(pad "2" smd roundrect
			(at 0.48 0 180)
			(size 0.59 0.64)
			(layers "F.Cu" "F.Mask" "F.Paste")
			(roundrect_rratio 0.25)
			(net 1274 "/DCDC/5V_{AON}_VDD")
			(pintype "passive")
		)
	)
	(footprint "antmicro-footprints:C_0805_2012Metric"
		(layer "F.Cu")
		(at 174.99 93.32 -90)
		(descr "Capacitor SMD 0805")
		(tags "capacitor SMD 0805")
		(property "Reference" "C286"
			(at 1.745 0.425 90)
			(layer "F.SilkS")
			(effects
				(font
					(size 0.7 0.7)
					(thickness 0.15)
				)
				(justify right top)
			)
		)
		(property "Value" "C_22u_25V_0805"
			(at -2.055717 1.963152 90)
			(layer "F.Fab")
			(effects
				(font
					(size 0.7 0.7)
					(thickness 0.15)
				)
				(justify right top)
			)
		)
		(property "Datasheet" "https://product.samsungsem.com/mlcc/CL21A226MAYNNN.do"
			(at 0 0 90)
			(layer "F.Fab")
			(hide yes)
			(effects
				(font
					(size 1.27 1.27)
					(thickness 0.15)
				)
			)
		)
		(property "Description" "SMT Multilayer Ceramic Capacitor, 22uF, +/-20%, 25V, X5R, 0805 [2012 Metric]"
			(at 0 0 90)
			(layer "F.Fab")
			(hide yes)
			(effects
				(font
					(size 1.27 1.27)
					(thickness 0.15)
				)
			)
		)
		(property "MPN" "CL21A226MAYNNNE"
			(at 0 0 270)
			(unlocked yes)
			(layer "F.Fab")
			(hide yes)
			(effects
				(font
					(size 1 1)
					(thickness 0.15)
				)
			)
		)
		(property "Manufacturer" "Samsung Electro-Mechanics"
			(at 0 0 270)
			(unlocked yes)
			(layer "F.Fab")
			(hide yes)
			(effects
				(font
					(size 1 1)
					(thickness 0.15)
				)
			)
		)
		(property "License" "Apache-2.0"
			(at 0 0 270)
			(unlocked yes)
			(layer "F.Fab")
			(hide yes)
			(effects
				(font
					(size 1 1)
					(thickness 0.15)
				)
			)
		)
		(property "Author" "Antmicro"
			(at 0 0 270)
			(unlocked yes)
			(layer "F.Fab")
			(hide yes)
			(effects
				(font
					(size 1 1)
					(thickness 0.15)
				)
			)
		)
		(property "Val" "22u"
			(at 0 0 270)
			(unlocked yes)
			(layer "F.Fab")
			(hide yes)
			(effects
				(font
					(size 1 1)
					(thickness 0.15)
				)
			)
		)
		(property "Voltage" "25V"
			(at 0 0 270)
			(unlocked yes)
			(layer "F.Fab")
			(hide yes)
			(effects
				(font
					(size 1 1)
					(thickness 0.15)
				)
			)
		)
		(property "Dielectric" "X5R"
			(at 0 0 270)
			(unlocked yes)
			(layer "F.Fab")
			(hide yes)
			(effects
				(font
					(size 1 1)
					(thickness 0.15)
				)
			)
		)
		(property "Public" "False"
			(at 0 0 270)
			(unlocked yes)
			(layer "F.Fab")
			(hide yes)
			(effects
				(font
					(size 1 1)
					(thickness 0.15)
				)
			)
		)
		(component_classes
			(class "DCDC_SOM")
		)
		(sheetname "/DCDC/")
		(sheetfile "dcdc.kicad_sch")
		(attr smd)
		(fp_line
			(start -0.3 0.7)
			(end 0.3 0.7)
			(stroke
				(width 0.15)
				(type solid)
			)
			(layer "F.SilkS")
		)
		(fp_line
			(start -0.3 -0.7)
			(end 0.3 -0.7)
			(stroke
				(width 0.15)
				(type solid)
			)
			(layer "F.SilkS")
		)
		(fp_rect
			(start 1.95 -0.9)
			(end -1.95 0.9)
			(stroke
				(width 0.05)
				(type default)
			)
			(fill no)
			(layer "F.CrtYd")
		)
		(fp_rect
			(start -0.95 -0.675)
			(end 0.95 0.675)
			(stroke
				(width 0.15)
				(type solid)
			)
			(fill no)
			(layer "F.Fab")
		)
		(fp_text user "Author: Antmicro"
			(at -1.9 5.947 90)
			(layer "F.Fab")
			(effects
				(font
					(size 0.7 0.7)
					(thickness 0.15)
				)
				(justify right top)
			)
		)
		(fp_text user "License: Apache-2.0"
			(at -1.9 4.947 90)
			(layer "F.Fab")
			(effects
				(font
					(size 0.7 0.7)
					(thickness 0.15)
				)
				(justify right top)
			)
		)
		(fp_text user "${REFERENCE}"
			(at -1.9 3.947 90)
			(layer "F.Fab")
			(effects
				(font
					(size 0.7 0.7)
					(thickness 0.15)
				)
				(justify right top)
			)
		)
		(pad "1" smd roundrect
			(at -1.1 0 270)
			(size 1.2 1.3)
			(layers "F.Cu" "F.Mask" "F.Paste")
			(roundrect_rratio 0.25)
			(net 1 "GND")
			(pintype "passive")
		)
		(pad "2" smd roundrect
			(at 1.1 0 270)
			(size 1.2 1.3)
			(layers "F.Cu" "F.Mask" "F.Paste")
			(roundrect_rratio 0.25)
			(net 903 "/DCDC/16V_OUT")
			(pintype "passive")
		)
	)
	(footprint "antmicro-footprints:C_0402_1005Metric"
		(layer "F.Cu")
		(at 182.764468 91.565 -90)
		(descr "Capacitor SMD 0402")
		(tags "capacitor SMD 0402")
		(property "Reference" "C245"
			(at -0.91 -0.5 90)
			(layer "F.SilkS")
			(effects
				(font
					(size 0.7 0.7)
					(thickness 0.15)
				)
				(justify right top)
			)
		)
		(property "Value" "C_4u7_25V_0402"
			(at -1.022927 2.155213 90)
			(layer "F.Fab")
			(effects
				(font
					(size 0.7 0.7)
					(thickness 0.15)
				)
				(justify right top)
			)
		)
		(property "Datasheet" "https://www.murata.com/products/productdetail?partno=GRM155C61E475ME15%23"
			(at 0 0 90)
			(layer "F.Fab")
			(hide yes)
			(effects
				(font
					(size 1.27 1.27)
					(thickness 0.15)
				)
			)
		)
		(property "Description" "SMD Multilayer Ceramic Capacitor"
			(at 0 0 90)
			(layer "F.Fab")
			(hide yes)
			(effects
				(font
					(size 1.27 1.27)
					(thickness 0.15)
				)
			)
		)
		(property "MPN" "GRM155C61E475ME15J"
			(at 0 0 270)
			(unlocked yes)
			(layer "F.Fab")
			(hide yes)
			(effects
				(font
					(size 1 1)
					(thickness 0.15)
				)
			)
		)
		(property "Manufacturer" "Murata"
			(at 0 0 270)
			(unlocked yes)
			(layer "F.Fab")
			(hide yes)
			(effects
				(font
					(size 1 1)
					(thickness 0.15)
				)
			)
		)
		(property "License" "Apache-2.0"
			(at 0 0 270)
			(unlocked yes)
			(layer "F.Fab")
			(hide yes)
			(effects
				(font
					(size 1 1)
					(thickness 0.15)
				)
			)
		)
		(property "Author" "Antmicro"
			(at 0 0 270)
			(unlocked yes)
			(layer "F.Fab")
			(hide yes)
			(effects
				(font
					(size 1 1)
					(thickness 0.15)
				)
			)
		)
		(property "Val" "4u7"
			(at 0 0 270)
			(unlocked yes)
			(layer "F.Fab")
			(hide yes)
			(effects
				(font
					(size 1 1)
					(thickness 0.15)
				)
			)
		)
		(property "Voltage" "25V"
			(at 0 0 270)
			(unlocked yes)
			(layer "F.Fab")
			(hide yes)
			(effects
				(font
					(size 1 1)
					(thickness 0.15)
				)
			)
		)
		(property "Dielectric" "X5S"
			(at 0 0 270)
			(unlocked yes)
			(layer "F.Fab")
			(hide yes)
			(effects
				(font
					(size 1 1)
					(thickness 0.15)
				)
			)
		)
		(component_classes
			(class "DCDC_SOM")
		)
		(sheetname "/DCDC/")
		(sheetfile "dcdc.kicad_sch")
		(attr smd)
		(fp_rect
			(start -0.925 -0.47)
			(end 0.925 0.47)
			(stroke
				(width 0.05)
				(type default)
			)
			(fill no)
			(layer "F.CrtYd")
		)
		(fp_line
			(start -0.494 0.248)
			(end -0.494 -0.25)
			(stroke
				(width 0.15)
				(type solid)
			)
			(layer "F.Fab")
		)
		(fp_line
			(start 0.504 0.248)
			(end -0.494 0.248)
			(stroke
				(width 0.15)
				(type solid)
			)
			(layer "F.Fab")
		)
		(fp_line
			(start -0.494 -0.25)
			(end 0.504 -0.25)
			(stroke
				(width 0.15)
				(type solid)
			)
			(layer "F.Fab")
		)
		(fp_line
			(start 0.504 -0.25)
			(end 0.504 0.248)
			(stroke
				(width 0.15)
				(type solid)
			)
			(layer "F.Fab")
		)
		(fp_text user "${REFERENCE}"
			(at -0.939 4.599 90)
			(layer "F.Fab")
			(effects
				(font
					(size 0.7 0.7)
					(thickness 0.15)
				)
				(justify right top)
			)
		)
		(fp_text user "Author: Antmicro"
			(at -0.939 3.399 90)
			(layer "F.Fab")
			(effects
				(font
					(size 0.7 0.7)
					(thickness 0.15)
				)
				(justify right top)
			)
		)
		(fp_text user "License: Apache-2.0"
			(at -0.939 5.799 90)
			(layer "F.Fab")
			(effects
				(font
					(size 0.7 0.7)
					(thickness 0.15)
				)
				(justify right top)
			)
		)
		(pad "1" smd roundrect
			(at -0.48 0 270)
			(size 0.59 0.64)
			(layers "F.Cu" "F.Mask" "F.Paste")
			(roundrect_rratio 0.25)
			(net 1 "GND")
			(pintype "passive")
		)
		(pad "2" smd roundrect
			(at 0.48 0 270)
			(size 0.59 0.64)
			(layers "F.Cu" "F.Mask" "F.Paste")
			(roundrect_rratio 0.25)
			(net 900 "/DCDC/16V_VDRV")
			(pintype "passive")
		)
	)
	(footprint "antmicro-footprints:C_0805_2012Metric"
		(layer "F.Cu")
		(at 173.17 89.11 90)
		(descr "Capacitor SMD 0805")
		(tags "capacitor SMD 0805")
		(property "Reference" "C242"
			(at -1.67 -5.57 90)
			(layer "F.SilkS")
			(effects
				(font
					(size 0.7 0.7)
					(thickness 0.15)
				)
				(justify left bottom)
			)
		)
		(property "Value" "C_22u_25V_0805"
			(at -2.055717 1.963152 90)
			(layer "F.Fab")
			(effects
				(font
					(size 0.7 0.7)
					(thickness 0.15)
				)
				(justify left bottom)
			)
		)
		(property "Datasheet" "https://product.samsungsem.com/mlcc/CL21A226MAYNNN.do"
			(at 0 0 90)
			(layer "F.Fab")
			(hide yes)
			(effects
				(font
					(size 1.27 1.27)
					(thickness 0.15)
				)
			)
		)
		(property "Description" "SMT Multilayer Ceramic Capacitor, 22uF, +/-20%, 25V, X5R, 0805 [2012 Metric]"
			(at 0 0 90)
			(layer "F.Fab")
			(hide yes)
			(effects
				(font
					(size 1.27 1.27)
					(thickness 0.15)
				)
			)
		)
		(property "MPN" "CL21A226MAYNNNE"
			(at 0 0 90)
			(unlocked yes)
			(layer "F.Fab")
			(hide yes)
			(effects
				(font
					(size 1 1)
					(thickness 0.15)
				)
			)
		)
		(property "Manufacturer" "Samsung Electro-Mechanics"
			(at 0 0 90)
			(unlocked yes)
			(layer "F.Fab")
			(hide yes)
			(effects
				(font
					(size 1 1)
					(thickness 0.15)
				)
			)
		)
		(property "License" "Apache-2.0"
			(at 0 0 90)
			(unlocked yes)
			(layer "F.Fab")
			(hide yes)
			(effects
				(font
					(size 1 1)
					(thickness 0.15)
				)
			)
		)
		(property "Author" "Antmicro"
			(at 0 0 90)
			(unlocked yes)
			(layer "F.Fab")
			(hide yes)
			(effects
				(font
					(size 1 1)
					(thickness 0.15)
				)
			)
		)
		(property "Val" "22u"
			(at 0 0 90)
			(unlocked yes)
			(layer "F.Fab")
			(hide yes)
			(effects
				(font
					(size 1 1)
					(thickness 0.15)
				)
			)
		)
		(property "Voltage" "25V"
			(at 0 0 90)
			(unlocked yes)
			(layer "F.Fab")
			(hide yes)
			(effects
				(font
					(size 1 1)
					(thickness 0.15)
				)
			)
		)
		(property "Dielectric" "X5R"
			(at 0 0 90)
			(unlocked yes)
			(layer "F.Fab")
			(hide yes)
			(effects
				(font
					(size 1 1)
					(thickness 0.15)
				)
			)
		)
		(property "Public" "False"
			(at 0 0 90)
			(unlocked yes)
			(layer "F.Fab")
			(hide yes)
			(effects
				(font
					(size 1 1)
					(thickness 0.15)
				)
			)
		)
		(component_classes
			(class "DCDC_SOM")
		)
		(sheetname "/DCDC/")
		(sheetfile "dcdc.kicad_sch")
		(attr smd)
		(fp_line
			(start -0.3 -0.7)
			(end 0.3 -0.7)
			(stroke
				(width 0.15)
				(type solid)
			)
			(layer "F.SilkS")
		)
		(fp_line
			(start -0.3 0.7)
			(end 0.3 0.7)
			(stroke
				(width 0.15)
				(type solid)
			)
			(layer "F.SilkS")
		)
		(fp_rect
			(start 1.95 -0.9)
			(end -1.95 0.9)
			(stroke
				(width 0.05)
				(type default)
			)
			(fill no)
			(layer "F.CrtYd")
		)
		(fp_rect
			(start -0.95 -0.675)
			(end 0.95 0.675)
			(stroke
				(width 0.15)
				(type solid)
			)
			(fill no)
			(layer "F.Fab")
		)
		(fp_text user "License: Apache-2.0"
			(at -1.9 4.947 90)
			(layer "F.Fab")
			(effects
				(font
					(size 0.7 0.7)
					(thickness 0.15)
				)
				(justify left bottom)
			)
		)
		(fp_text user "${REFERENCE}"
			(at -1.9 3.947 90)
			(layer "F.Fab")
			(effects
				(font
					(size 0.7 0.7)
					(thickness 0.15)
				)
				(justify left bottom)
			)
		)
		(fp_text user "Author: Antmicro"
			(at -1.9 5.947 90)
			(layer "F.Fab")
			(effects
				(font
					(size 0.7 0.7)
					(thickness 0.15)
				)
				(justify left bottom)
			)
		)
		(pad "1" smd roundrect
			(at -1.1 0 90)
			(size 1.2 1.3)
			(layers "F.Cu" "F.Mask" "F.Paste")
			(roundrect_rratio 0.25)
			(net 1 "GND")
			(pintype "passive")
		)
		(pad "2" smd roundrect
			(at 1.1 0 90)
			(size 1.2 1.3)
			(layers "F.Cu" "F.Mask" "F.Paste")
			(roundrect_rratio 0.25)
			(net 13 "VCC")
			(pintype "passive")
		)
	)
	(footprint "antmicro-footprints:TP_SMD_0.75mm"
		(layer "F.Cu")
		(at 179.75 57.19 90)
		(property "Reference" "TP5"
			(at -1.5 -0.69 90)
			(layer "F.SilkS")
			(hide yes)
			(effects
				(font
					(size 0.7 0.7)
					(thickness 0.15)
				)
				(justify left bottom)
			)
		)
		(property "Value" "TP_0.75mm_SMD"
			(at 0 1.2 90)
			(layer "F.Fab")
			(effects
				(font
					(size 0.7 0.7)
					(thickness 0.15)
				)
				(justify left bottom)
			)
		)
		(property "Description" "SMT test point"
			(at 0 0 90)
			(layer "F.Fab")
			(hide yes)
			(effects
				(font
					(size 1.27 1.27)
					(thickness 0.15)
				)
			)
		)
		(property "MPN" ""
			(at 0 0 90)
			(unlocked yes)
			(layer "F.Fab")
			(hide yes)
			(effects
				(font
					(size 1 1)
					(thickness 0.15)
				)
			)
		)
		(property "Manufacturer" ""
			(at 0 0 90)
			(unlocked yes)
			(layer "F.Fab")
			(hide yes)
			(effects
				(font
					(size 1 1)
					(thickness 0.15)
				)
			)
		)
		(property "Author" "Antmicro"
			(at 0 0 90)
			(unlocked yes)
			(layer "F.Fab")
			(hide yes)
			(effects
				(font
					(size 1 1)
					(thickness 0.15)
				)
			)
		)
		(property "License" "Apache-2.0"
			(at 0 0 90)
			(unlocked yes)
			(layer "F.Fab")
			(hide yes)
			(effects
				(font
					(size 1 1)
					(thickness 0.15)
				)
			)
		)
		(sheetname "/Power/")
		(sheetfile "power.kicad_sch")
		(attr exclude_from_pos_files exclude_from_bom)
		(fp_circle
			(center 0 0)
			(end 0.475 0)
			(stroke
				(width 0.05)
				(type default)
			)
			(fill no)
			(layer "F.CrtYd")
		)
		(fp_text user "${REFERENCE}"
			(at -0.4 2.7 90)
			(layer "F.Fab")
			(effects
				(font
					(size 0.7 0.7)
					(thickness 0.15)
				)
				(justify left bottom)
			)
		)
		(fp_text user "License: Apache-2.0"
			(at -0.4 5.101 90)
			(layer "F.Fab")
			(effects
				(font
					(size 0.7 0.7)
					(thickness 0.15)
				)
				(justify left bottom)
			)
		)
		(fp_text user "Author: Antmicro"
			(at -0.4 3.901 90)
			(layer "F.Fab")
			(effects
				(font
					(size 0.7 0.7)
					(thickness 0.15)
				)
				(justify left bottom)
			)
		)
		(pad "1" smd circle
			(at 0 0 90)
			(size 0.75 0.75)
			(layers "F.Cu" "F.Mask")
			(net 12 "SYS_VIN_HV")
			(pinfunction "1")
			(pintype "passive")
		)
	)
	(footprint "antmicro-footprints:L_WE-MAPI-4020"
		(layer "F.Cu")
		(at 191.25 130.96)
		(property "Reference" "L5"
			(at -1.05 2.54 0)
			(layer "F.SilkS")
			(effects
				(font
					(size 0.7 0.7)
					(thickness 0.15)
				)
				(justify right top)
			)
		)
		(property "Value" "L_1u8_6.8A_WE-MAPI-4020"
			(at -2.4 3.4 0)
			(layer "F.Fab")
			(effects
				(font
					(size 0.7 0.7)
					(thickness 0.15)
				)
				(justify right top)
			)
		)
		(property "Datasheet" "https://www.we-online.com/components/products/datasheet/74438356018.pdf"
			(at 0 0 0)
			(layer "F.Fab")
			(hide yes)
			(effects
				(font
					(size 1.27 1.27)
					(thickness 0.15)
				)
			)
		)
		(property "Description" "Power Inductors - SMD WE-MAPI 1.8uH 4.6A DCR=30mOhms AEC-Q200"
			(at 0 0 0)
			(layer "F.Fab")
			(hide yes)
			(effects
				(font
					(size 1.27 1.27)
					(thickness 0.15)
				)
			)
		)
		(property "Val" "1u8/6.8A"
			(at 0 0 0)
			(unlocked yes)
			(layer "F.Fab")
			(hide yes)
			(effects
				(font
					(size 1 1)
					(thickness 0.15)
				)
			)
		)
		(property "Manufacturer" "Würth Elektronik"
			(at 0 0 0)
			(unlocked yes)
			(layer "F.Fab")
			(hide yes)
			(effects
				(font
					(size 1 1)
					(thickness 0.15)
				)
			)
		)
		(property "MPN" "74438356018"
			(at 0 0 0)
			(unlocked yes)
			(layer "F.Fab")
			(hide yes)
			(effects
				(font
					(size 1 1)
					(thickness 0.15)
				)
			)
		)
		(property "ISat" "6.5 A"
			(at 0 0 0)
			(unlocked yes)
			(layer "F.Fab")
			(hide yes)
			(effects
				(font
					(size 1 1)
					(thickness 0.15)
				)
			)
		)
		(property "IMax" "6.8 A"
			(at 0 0 0)
			(unlocked yes)
			(layer "F.Fab")
			(hide yes)
			(effects
				(font
					(size 1 1)
					(thickness 0.15)
				)
			)
		)
		(property "Size" "4.1x4.1mm"
			(at 0 0 0)
			(unlocked yes)
			(layer "F.Fab")
			(hide yes)
			(effects
				(font
					(size 1 1)
					(thickness 0.15)
				)
			)
		)
		(property "Author" "Antmicro"
			(at 0 0 0)
			(unlocked yes)
			(layer "F.Fab")
			(hide yes)
			(effects
				(font
					(size 1 1)
					(thickness 0.15)
				)
			)
		)
		(property "License" "Apache-2.0"
			(at 0 0 0)
			(unlocked yes)
			(layer "F.Fab")
			(hide yes)
			(effects
				(font
					(size 1 1)
					(thickness 0.15)
				)
			)
		)
		(component_classes
			(class "DCDC_1V15")
		)
		(sheetname "/DCDC/")
		(sheetfile "dcdc.kicad_sch")
		(attr smd)
		(fp_rect
			(start -2.2 -2.2)
			(end 2.2 2.2)
			(stroke
				(width 0.15)
				(type solid)
			)
			(fill no)
			(layer "F.SilkS")
		)
		(fp_rect
			(start -2.3 -2.3)
			(end 2.3 2.3)
			(stroke
				(width 0.05)
				(type solid)
			)
			(fill no)
			(layer "F.CrtYd")
		)
		(fp_rect
			(start -2.05 -2.05)
			(end 2.05 2.05)
			(stroke
				(width 0.15)
				(type solid)
			)
			(fill no)
			(layer "F.Fab")
		)
		(fp_text user "${REFERENCE}"
			(at -2.4 7.8 0)
			(layer "F.Fab")
			(effects
				(font
					(size 0.7 0.7)
					(thickness 0.15)
				)
				(justify left bottom)
			)
		)
		(fp_text user "Author: Antmicro"
			(at -2.4 6.6 0)
			(layer "F.Fab")
			(effects
				(font
					(size 0.7 0.7)
					(thickness 0.15)
				)
				(justify left bottom)
			)
		)
		(fp_text user "License: Apache-2.0"
			(at -2.4 5.4 0)
			(layer "F.Fab")
			(effects
				(font
					(size 0.7 0.7)
					(thickness 0.15)
				)
				(justify left bottom)
			)
		)
		(pad "1" smd roundrect
			(at -1.185 0 90)
			(size 3.7 1)
			(layers "F.Cu" "F.Mask" "F.Paste")
			(roundrect_rratio 0.1)
			(net 1034 "/DCDC/1V15_SW")
			(pintype "passive")
		)
		(pad "2" smd roundrect
			(at 1.185 0 90)
			(size 3.7 1)
			(layers "F.Cu" "F.Mask" "F.Paste")
			(roundrect_rratio 0.1)
			(net 280 "/DCDC/1V15_OUT")
			(pintype "passive")
		)
	)
	(footprint "antmicro-footprints:C_0805_2012Metric"
		(layer "F.Cu")
		(at 174.98 89.11 90)
		(descr "Capacitor SMD 0805")
		(tags "capacitor SMD 0805")
		(property "Reference" "C270"
			(at -1.69 -6.38 90)
			(layer "F.SilkS")
			(effects
				(font
					(size 0.7 0.7)
					(thickness 0.15)
				)
				(justify left bottom)
			)
		)
		(property "Value" "C_22u_25V_0805"
			(at -2.055717 1.963152 90)
			(layer "F.Fab")
			(effects
				(font
					(size 0.7 0.7)
					(thickness 0.15)
				)
				(justify left bottom)
			)
		)
		(property "Datasheet" "https://product.samsungsem.com/mlcc/CL21A226MAYNNN.do"
			(at 0 0 90)
			(layer "F.Fab")
			(hide yes)
			(effects
				(font
					(size 1.27 1.27)
					(thickness 0.15)
				)
			)
		)
		(property "Description" "SMT Multilayer Ceramic Capacitor, 22uF, +/-20%, 25V, X5R, 0805 [2012 Metric]"
			(at 0 0 90)
			(layer "F.Fab")
			(hide yes)
			(effects
				(font
					(size 1.27 1.27)
					(thickness 0.15)
				)
			)
		)
		(property "MPN" "CL21A226MAYNNNE"
			(at 0 0 90)
			(unlocked yes)
			(layer "F.Fab")
			(hide yes)
			(effects
				(font
					(size 1 1)
					(thickness 0.15)
				)
			)
		)
		(property "Manufacturer" "Samsung Electro-Mechanics"
			(at 0 0 90)
			(unlocked yes)
			(layer "F.Fab")
			(hide yes)
			(effects
				(font
					(size 1 1)
					(thickness 0.15)
				)
			)
		)
		(property "License" "Apache-2.0"
			(at 0 0 90)
			(unlocked yes)
			(layer "F.Fab")
			(hide yes)
			(effects
				(font
					(size 1 1)
					(thickness 0.15)
				)
			)
		)
		(property "Author" "Antmicro"
			(at 0 0 90)
			(unlocked yes)
			(layer "F.Fab")
			(hide yes)
			(effects
				(font
					(size 1 1)
					(thickness 0.15)
				)
			)
		)
		(property "Val" "22u"
			(at 0 0 90)
			(unlocked yes)
			(layer "F.Fab")
			(hide yes)
			(effects
				(font
					(size 1 1)
					(thickness 0.15)
				)
			)
		)
		(property "Voltage" "25V"
			(at 0 0 90)
			(unlocked yes)
			(layer "F.Fab")
			(hide yes)
			(effects
				(font
					(size 1 1)
					(thickness 0.15)
				)
			)
		)
		(property "Dielectric" "X5R"
			(at 0 0 90)
			(unlocked yes)
			(layer "F.Fab")
			(hide yes)
			(effects
				(font
					(size 1 1)
					(thickness 0.15)
				)
			)
		)
		(property "Public" "False"
			(at 0 0 90)
			(unlocked yes)
			(layer "F.Fab")
			(hide yes)
			(effects
				(font
					(size 1 1)
					(thickness 0.15)
				)
			)
		)
		(component_classes
			(class "DCDC_SOM")
		)
		(sheetname "/DCDC/")
		(sheetfile "dcdc.kicad_sch")
		(attr smd)
		(fp_line
			(start -0.3 -0.7)
			(end 0.3 -0.7)
			(stroke
				(width 0.15)
				(type solid)
			)
			(layer "F.SilkS")
		)
		(fp_line
			(start -0.3 0.7)
			(end 0.3 0.7)
			(stroke
				(width 0.15)
				(type solid)
			)
			(layer "F.SilkS")
		)
		(fp_rect
			(start 1.95 -0.9)
			(end -1.95 0.9)
			(stroke
				(width 0.05)
				(type default)
			)
			(fill no)
			(layer "F.CrtYd")
		)
		(fp_rect
			(start -0.95 -0.675)
			(end 0.95 0.675)
			(stroke
				(width 0.15)
				(type solid)
			)
			(fill no)
			(layer "F.Fab")
		)
		(fp_text user "Author: Antmicro"
			(at -1.9 5.947 90)
			(layer "F.Fab")
			(effects
				(font
					(size 0.7 0.7)
					(thickness 0.15)
				)
				(justify left bottom)
			)
		)
		(fp_text user "License: Apache-2.0"
			(at -1.9 4.947 90)
			(layer "F.Fab")
			(effects
				(font
					(size 0.7 0.7)
					(thickness 0.15)
				)
				(justify left bottom)
			)
		)
		(fp_text user "${REFERENCE}"
			(at -1.9 3.947 90)
			(layer "F.Fab")
			(effects
				(font
					(size 0.7 0.7)
					(thickness 0.15)
				)
				(justify left bottom)
			)
		)
		(pad "1" smd roundrect
			(at -1.1 0 90)
			(size 1.2 1.3)
			(layers "F.Cu" "F.Mask" "F.Paste")
			(roundrect_rratio 0.25)
			(net 1 "GND")
			(pintype "passive")
		)
		(pad "2" smd roundrect
			(at 1.1 0 90)
			(size 1.2 1.3)
			(layers "F.Cu" "F.Mask" "F.Paste")
			(roundrect_rratio 0.25)
			(net 13 "VCC")
			(pintype "passive")
		)
	)
	(footprint "antmicro-footprints:R_0402_1005Metric"
		(layer "F.Cu")
		(at 216.2 77)
		(descr "Resistor SMD 0402")
		(tags "resistor SMD 0402")
		(property "Reference" "R123"
			(at 1.4 -1.4 180)
			(layer "F.SilkS")
			(effects
				(font
					(size 0.7 0.7)
					(thickness 0.15)
				)
				(justify right top)
			)
		)
		(property "Value" "R_0R_0402"
			(at -1.011843 1.772046 180)
			(layer "F.Fab")
			(effects
				(font
					(size 0.7 0.7)
					(thickness 0.15)
				)
				(justify right top)
			)
		)
		(property "Datasheet" "https://industrial.panasonic.com/cdbs/www-data/pdf/RDA0000/AOA0000C301.pdf"
			(at 0 0 180)
			(layer "F.Fab")
			(hide yes)
			(effects
				(font
					(size 1.27 1.27)
					(thickness 0.15)
				)
			)
		)
		(property "Description" "SMD Chip Resistor, Jumper, 0 ohm, 100 mW, 0402 [1005 Metric], Thick Film, General Purpose"
			(at 0 0 180)
			(layer "F.Fab")
			(hide yes)
			(effects
				(font
					(size 1.27 1.27)
					(thickness 0.15)
				)
			)
		)
		(property "Manufacturer" "Panasonic"
			(at 0 0 0)
			(unlocked yes)
			(layer "F.Fab")
			(hide yes)
			(effects
				(font
					(size 1 1)
					(thickness 0.15)
				)
			)
		)
		(property "MPN" "ERJ2GE0R00X"
			(at 0 0 0)
			(unlocked yes)
			(layer "F.Fab")
			(hide yes)
			(effects
				(font
					(size 1 1)
					(thickness 0.15)
				)
			)
		)
		(property "Val" "0R"
			(at 0 0 0)
			(unlocked yes)
			(layer "F.Fab")
			(hide yes)
			(effects
				(font
					(size 1 1)
					(thickness 0.15)
				)
			)
		)
		(property "License" "Apache-2.0"
			(at 0 0 0)
			(unlocked yes)
			(layer "F.Fab")
			(hide yes)
			(effects
				(font
					(size 1 1)
					(thickness 0.15)
				)
			)
		)
		(property "Author" "Antmicro"
			(at 0 0 0)
			(unlocked yes)
			(layer "F.Fab")
			(hide yes)
			(effects
				(font
					(size 1 1)
					(thickness 0.15)
				)
			)
		)
		(property "Tolerance" "~"
			(at 0 0 0)
			(unlocked yes)
			(layer "F.Fab")
			(hide yes)
			(effects
				(font
					(size 1 1)
					(thickness 0.15)
				)
			)
		)
		(property "Current" "1A"
			(at 0 0 0)
			(unlocked yes)
			(layer "F.Fab")
			(hide yes)
			(effects
				(font
					(size 1 1)
					(thickness 0.15)
				)
			)
		)
		(sheetname "/USB Debug, PD/")
		(sheetfile "usb_debug_pd.kicad_sch")
		(attr smd)
		(fp_poly
			(pts
				(xy -0.925 -0.47) (xy -0.925 0.47) (xy 0.925 0.47) (xy 0.925 -0.47)
			)
			(stroke
				(width 0.05)
				(type default)
			)
			(fill no)
			(layer "F.CrtYd")
		)
		(fp_poly
			(pts
				(xy -0.5 -0.25) (xy -0.5 0.25) (xy 0.5 0.25) (xy 0.5 -0.25)
			)
			(stroke
				(width 0.15)
				(type solid)
			)
			(fill no)
			(layer "F.Fab")
		)
		(fp_text user "${REFERENCE}"
			(at -0.95 3.168 180)
			(layer "F.Fab")
			(effects
				(font
					(size 0.7 0.7)
					(thickness 0.15)
				)
				(justify right top)
			)
		)
		(fp_text user "Author: Antmicro"
			(at -0.95 4.169 180)
			(layer "F.Fab")
			(effects
				(font
					(size 0.7 0.7)
					(thickness 0.15)
				)
				(justify right top)
			)
		)
		(fp_text user "License: Apache-2.0"
			(at -0.949999 5.169 180)
			(layer "F.Fab")
			(effects
				(font
					(size 0.7 0.7)
					(thickness 0.15)
				)
				(justify right top)
			)
		)
		(pad "1" smd roundrect
			(at -0.48 0)
			(size 0.59 0.64)
			(layers "F.Cu" "F.Mask" "F.Paste")
			(roundrect_rratio 0.25)
			(net 959 "/SoM_IO/UART3_DEBUG.TX")
			(pintype "passive")
		)
		(pad "2" smd roundrect
			(at 0.48 0)
			(size 0.59 0.64)
			(layers "F.Cu" "F.Mask" "F.Paste")
			(roundrect_rratio 0.25)
			(net 961 "Net-(U34-RXD)")
			(pintype "passive")
		)
	)
	(footprint "antmicro-footprints:SOT-523"
		(layer "F.Cu")
		(at 140.89 131.15 -90)
		(property "Reference" "Q40"
			(at -2 -1.08 180)
			(layer "F.SilkS")
			(effects
				(font
					(size 0.7 0.7)
					(thickness 0.15)
				)
				(justify right top)
			)
		)
		(property "Value" "DMG1012T-7"
			(at 0.1 1.824 90)
			(layer "F.Fab")
			(effects
				(font
					(size 0.7 0.7)
					(thickness 0.15)
				)
				(justify right top)
			)
		)
		(property "Datasheet" "https://www.diodes.com/assets/Datasheets/ds31783.pdf"
			(at 0 0 90)
			(layer "F.Fab")
			(hide yes)
			(effects
				(font
					(size 1.27 1.27)
					(thickness 0.15)
				)
			)
		)
		(property "Description" "Power MOSFET, N Channel, 20 V, 630 mA, 0.3 ohm, SOT-523, Surface Mount"
			(at 0 0 90)
			(layer "F.Fab")
			(hide yes)
			(effects
				(font
					(size 1.27 1.27)
					(thickness 0.15)
				)
			)
		)
		(property "MPN" "DMG1012T-7"
			(at 0 0 270)
			(unlocked yes)
			(layer "F.Fab")
			(hide yes)
			(effects
				(font
					(size 1 1)
					(thickness 0.15)
				)
			)
		)
		(property "Manufacturer" "Diodes Incorporated"
			(at 0 0 270)
			(unlocked yes)
			(layer "F.Fab")
			(hide yes)
			(effects
				(font
					(size 1 1)
					(thickness 0.15)
				)
			)
		)
		(property "Author" "Antmicro"
			(at 0 0 270)
			(unlocked yes)
			(layer "F.Fab")
			(hide yes)
			(effects
				(font
					(size 1 1)
					(thickness 0.15)
				)
			)
		)
		(property "License" "Apache-2.0"
			(at 0 0 270)
			(unlocked yes)
			(layer "F.Fab")
			(hide yes)
			(effects
				(font
					(size 1 1)
					(thickness 0.15)
				)
			)
		)
		(sheetname "/SoM_Power/")
		(sheetfile "som_power.kicad_sch")
		(attr smd)
		(fp_line
			(start -0.927 -0.051)
			(end -0.927 -0.351)
			(stroke
				(width 0.15)
				(type solid)
			)
			(layer "F.SilkS")
		)
		(fp_line
			(start -0.927 -0.351)
			(end -0.725 -0.551)
			(stroke
				(width 0.15)
				(type solid)
			)
			(layer "F.SilkS")
		)
		(fp_line
			(start -0.725 -0.551)
			(end -0.277 -0.551)
			(stroke
				(width 0.15)
				(type solid)
			)
			(layer "F.SilkS")
		)
		(fp_line
			(start -0.277 -0.551)
			(end -0.277 -0.75)
			(stroke
				(width 0.15)
				(type solid)
			)
			(layer "F.SilkS")
		)
		(fp_circle
			(center -0.9652 0.9652)
			(end -0.9152 0.9652)
			(stroke
				(width 0.15)
				(type solid)
			)
			(fill yes)
			(layer "F.SilkS")
		)
		(fp_line
			(start -1.12 1.15)
			(end 1.1 1.15)
			(stroke
				(width 0.05)
				(type solid)
			)
			(layer "F.CrtYd")
		)
		(fp_line
			(start -1.12 -1.16)
			(end -1.12 1.15)
			(stroke
				(width 0.05)
				(type solid)
			)
			(layer "F.CrtYd")
		)
		(fp_line
			(start -1.12 -1.16)
			(end 1.1 -1.16)
			(stroke
				(width 0.05)
				(type solid)
			)
			(layer "F.CrtYd")
		)
		(fp_line
			(start 1.1 -1.16)
			(end 1.1 1.15)
			(stroke
				(width 0.05)
				(type solid)
			)
			(layer "F.CrtYd")
		)
		(fp_line
			(start 0.8 0.424)
			(end -0.802 0.424)
			(stroke
				(width 0.15)
				(type solid)
			)
			(layer "F.Fab")
		)
		(fp_line
			(start -0.802 -0.276)
			(end -0.802 0.424)
			(stroke
				(width 0.15)
				(type solid)
			)
			(layer "F.Fab")
		)
		(fp_line
			(start -0.652 -0.425)
			(end -0.802 -0.276)
			(stroke
				(width 0.15)
				(type solid)
			)
			(layer "F.Fab")
		)
		(fp_line
			(start 0.8 -0.425)
			(end 0.8 0.424)
			(stroke
				(width 0.15)
				(type solid)
			)
			(layer "F.Fab")
		)
		(fp_line
			(start 0.8 -0.425)
			(end -0.652 -0.425)
			(stroke
				(width 0.15)
				(type solid)
			)
			(layer "F.Fab")
		)
		(fp_circle
			(center -0.9652 0.9652)
			(end -0.9144 0.9652)
			(stroke
				(width 0.15)
				(type solid)
			)
			(fill no)
			(layer "F.Fab")
		)
		(fp_text user "License: Apache-2.0"
			(at -1.12 5.024 90)
			(layer "F.Fab")
			(effects
				(font
					(size 0.7 0.7)
					(thickness 0.15)
				)
				(justify right top)
			)
		)
		(fp_text user "${REFERENCE}"
			(at -1.12 3.824 90)
			(layer "F.Fab")
			(effects
				(font
					(size 0.7 0.7)
					(thickness 0.15)
				)
				(justify right top)
			)
		)
		(fp_text user "Author: Antmicro"
			(at -1.12 6.224 90)
			(layer "F.Fab")
			(effects
				(font
					(size 0.7 0.7)
					(thickness 0.15)
				)
				(justify right top)
			)
		)
		(pad "1" smd rect
			(at -0.5 0.65 270)
			(size 0.4 0.51)
			(layers "F.Cu" "F.Mask" "F.Paste")
			(net 1293 "/DCDC/CARRIER_PWR_ON")
			(pinfunction "G")
			(pintype "input")
		)
		(pad "2" smd rect
			(at 0.498 0.65 270)
			(size 0.4 0.51)
			(layers "F.Cu" "F.Mask" "F.Paste")
			(net 1 "GND")
			(pinfunction "S")
			(pintype "passive")
		)
		(pad "3" smd rect
			(at 0 -0.652 270)
			(size 0.4 0.51)
			(layers "F.Cu" "F.Mask" "F.Paste")
			(net 883 "Net-(Q10-G)")
			(pinfunction "D")
			(pintype "passive")
		)
	)
	(footprint "antmicro-footprints:C_0402_1005Metric"
		(layer "F.Cu")
		(at 89.1 101.6 180)
		(descr "Capacitor SMD 0402")
		(tags "capacitor SMD 0402")
		(property "Reference" "C352"
			(at 3.8 -0.4 180)
			(layer "F.SilkS")
			(effects
				(font
					(size 0.7 0.7)
					(thickness 0.15)
				)
				(justify left bottom)
			)
		)
		(property "Value" "C_100n_0402"
			(at -1.022927 2.155213 180)
			(layer "F.Fab")
			(effects
				(font
					(size 0.7 0.7)
					(thickness 0.15)
				)
				(justify left bottom)
			)
		)
		(property "Datasheet" "https://www.murata.com/products/productdetail?partno=GRM155R61H104KE14%23"
			(at 0 0 180)
			(layer "F.Fab")
			(hide yes)
			(effects
				(font
					(size 1.27 1.27)
					(thickness 0.15)
				)
			)
		)
		(property "Description" "SMD Multilayer Ceramic Capacitor, 0.1 µF, 50 V, 0402 [1005 Metric], ± 10%, X5R, GRM Series"
			(at 0 0 180)
			(layer "F.Fab")
			(hide yes)
			(effects
				(font
					(size 1.27 1.27)
					(thickness 0.15)
				)
			)
		)
		(property "Manufacturer" "Murata"
			(at 0 0 180)
			(unlocked yes)
			(layer "F.Fab")
			(hide yes)
			(effects
				(font
					(size 1 1)
					(thickness 0.15)
				)
			)
		)
		(property "MPN" "GRM155R61H104KE14D"
			(at 0 0 180)
			(unlocked yes)
			(layer "F.Fab")
			(hide yes)
			(effects
				(font
					(size 1 1)
					(thickness 0.15)
				)
			)
		)
		(property "Val" "100n"
			(at 0 0 180)
			(unlocked yes)
			(layer "F.Fab")
			(hide yes)
			(effects
				(font
					(size 1 1)
					(thickness 0.15)
				)
			)
		)
		(property "License" "Apache-2.0"
			(at 0 0 180)
			(unlocked yes)
			(layer "F.Fab")
			(hide yes)
			(effects
				(font
					(size 1 1)
					(thickness 0.15)
				)
			)
		)
		(property "Author" "Antmicro"
			(at 0 0 180)
			(unlocked yes)
			(layer "F.Fab")
			(hide yes)
			(effects
				(font
					(size 1 1)
					(thickness 0.15)
				)
			)
		)
		(property "Voltage" "50V"
			(at 0 0 180)
			(unlocked yes)
			(layer "F.Fab")
			(hide yes)
			(effects
				(font
					(size 1 1)
					(thickness 0.15)
				)
			)
		)
		(property "Dielectric" "X5R"
			(at 0 0 180)
			(unlocked yes)
			(layer "F.Fab")
			(hide yes)
			(effects
				(font
					(size 1 1)
					(thickness 0.15)
				)
			)
		)
		(sheetname "/SoM_IO2/")
		(sheetfile "som_io2.kicad_sch")
		(attr smd)
		(fp_poly
			(pts
				(xy -0.925 -0.47) (xy 0.925 -0.47) (xy 0.925 0.47) (xy -0.925 0.47)
			)
			(stroke
				(width 0.05)
				(type default)
			)
			(fill no)
			(layer "F.CrtYd")
		)
		(fp_line
			(start 0.504 0.248)
			(end -0.494 0.248)
			(stroke
				(width 0.15)
				(type solid)
			)
			(layer "F.Fab")
		)
		(fp_line
			(start 0.504 -0.25)
			(end 0.504 0.248)
			(stroke
				(width 0.15)
				(type solid)
			)
			(layer "F.Fab")
		)
		(fp_line
			(start -0.494 0.248)
			(end -0.494 -0.25)
			(stroke
				(width 0.15)
				(type solid)
			)
			(layer "F.Fab")
		)
		(fp_line
			(start -0.494 -0.25)
			(end 0.504 -0.25)
			(stroke
				(width 0.15)
				(type solid)
			)
			(layer "F.Fab")
		)
		(fp_text user "Author: Antmicro"
			(at -0.939 3.399 180)
			(layer "F.Fab")
			(effects
				(font
					(size 0.7 0.7)
					(thickness 0.15)
				)
				(justify left bottom)
			)
		)
		(fp_text user "License: Apache-2.0"
			(at -0.939 5.799 180)
			(layer "F.Fab")
			(effects
				(font
					(size 0.7 0.7)
					(thickness 0.15)
				)
				(justify left bottom)
			)
		)
		(fp_text user "${REFERENCE}"
			(at -0.939 4.599 180)
			(layer "F.Fab")
			(effects
				(font
					(size 0.7 0.7)
					(thickness 0.15)
				)
				(justify left bottom)
			)
		)
		(pad "1" smd roundrect
			(at -0.48 0 180)
			(size 0.59 0.64)
			(layers "F.Cu" "F.Mask" "F.Paste")
			(roundrect_rratio 0.25)
			(net 1272 "/SoM_IO2/DP3.AUX_C+")
			(pintype "passive")
		)
		(pad "2" smd roundrect
			(at 0.48 0 180)
			(size 0.59 0.64)
			(layers "F.Cu" "F.Mask" "F.Paste")
			(roundrect_rratio 0.25)
			(net 776 "/Expansion connector/DP3.AUX+")
			(pintype "passive")
		)
	)
	(footprint "antmicro-footprints:C_0402_1005Metric"
		(layer "F.Cu")
		(at 66.6 92.7 180)
		(descr "Capacitor SMD 0402")
		(tags "capacitor SMD 0402")
		(property "Reference" "C165"
			(at -1.1 -0.4 180)
			(layer "F.SilkS")
			(effects
				(font
					(size 0.7 0.7)
					(thickness 0.15)
				)
				(justify left bottom)
			)
		)
		(property "Value" "C_1u_0402"
			(at -1.022927 2.155213 180)
			(layer "F.Fab")
			(effects
				(font
					(size 0.7 0.7)
					(thickness 0.15)
				)
				(justify left bottom)
			)
		)
		(property "Datasheet" "https://product.tdk.com/en/search/capacitor/ceramic/mlcc/info?part_no=C1005X6S1A105K050BC"
			(at 0 0 180)
			(layer "F.Fab")
			(hide yes)
			(effects
				(font
					(size 1.27 1.27)
					(thickness 0.15)
				)
			)
		)
		(property "Description" "SMD Multilayer Ceramic Capacitor, 1 µF, 10 V, 0402 [1005 Metric], ± 10%, X6S, C"
			(at 0 0 180)
			(layer "F.Fab")
			(hide yes)
			(effects
				(font
					(size 1.27 1.27)
					(thickness 0.15)
				)
			)
		)
		(property "Manufacturer" "TDK"
			(at 0 0 180)
			(unlocked yes)
			(layer "F.Fab")
			(hide yes)
			(effects
				(font
					(size 1 1)
					(thickness 0.15)
				)
			)
		)
		(property "MPN" "C1005X6S1A105K050BC"
			(at 0 0 180)
			(unlocked yes)
			(layer "F.Fab")
			(hide yes)
			(effects
				(font
					(size 1 1)
					(thickness 0.15)
				)
			)
		)
		(property "Val" "1u"
			(at 0 0 180)
			(unlocked yes)
			(layer "F.Fab")
			(hide yes)
			(effects
				(font
					(size 1 1)
					(thickness 0.15)
				)
			)
		)
		(property "License" "Apache-2.0"
			(at 0 0 180)
			(unlocked yes)
			(layer "F.Fab")
			(hide yes)
			(effects
				(font
					(size 1 1)
					(thickness 0.15)
				)
			)
		)
		(property "Author" "Antmicro"
			(at 0 0 180)
			(unlocked yes)
			(layer "F.Fab")
			(hide yes)
			(effects
				(font
					(size 1 1)
					(thickness 0.15)
				)
			)
		)
		(property "Voltage" ""
			(at 0 0 180)
			(unlocked yes)
			(layer "F.Fab")
			(hide yes)
			(effects
				(font
					(size 1 1)
					(thickness 0.15)
				)
			)
		)
		(property "Dielectric" ""
			(at 0 0 180)
			(unlocked yes)
			(layer "F.Fab")
			(hide yes)
			(effects
				(font
					(size 1 1)
					(thickness 0.15)
				)
			)
		)
		(sheetname "/CSI/")
		(sheetfile "csi.kicad_sch")
		(attr smd)
		(fp_rect
			(start -0.925 -0.47)
			(end 0.925 0.47)
			(stroke
				(width 0.05)
				(type default)
			)
			(fill no)
			(layer "F.CrtYd")
		)
		(fp_line
			(start 0.504 0.248)
			(end -0.494 0.248)
			(stroke
				(width 0.15)
				(type solid)
			)
			(layer "F.Fab")
		)
		(fp_line
			(start 0.504 -0.25)
			(end 0.504 0.248)
			(stroke
				(width 0.15)
				(type solid)
			)
			(layer "F.Fab")
		)
		(fp_line
			(start -0.494 0.248)
			(end -0.494 -0.25)
			(stroke
				(width 0.15)
				(type solid)
			)
			(layer "F.Fab")
		)
		(fp_line
			(start -0.494 -0.25)
			(end 0.504 -0.25)
			(stroke
				(width 0.15)
				(type solid)
			)
			(layer "F.Fab")
		)
		(fp_text user "License: Apache-2.0"
			(at -0.939 5.799 180)
			(layer "F.Fab")
			(effects
				(font
					(size 0.7 0.7)
					(thickness 0.15)
				)
				(justify left bottom)
			)
		)
		(fp_text user "Author: Antmicro"
			(at -0.939 3.399 180)
			(layer "F.Fab")
			(effects
				(font
					(size 0.7 0.7)
					(thickness 0.15)
				)
				(justify left bottom)
			)
		)
		(fp_text user "${REFERENCE}"
			(at -0.939 4.599 180)
			(layer "F.Fab")
			(effects
				(font
					(size 0.7 0.7)
					(thickness 0.15)
				)
				(justify left bottom)
			)
		)
		(pad "1" smd roundrect
			(at -0.48 0 180)
			(size 0.59 0.64)
			(layers "F.Cu" "F.Mask" "F.Paste")
			(roundrect_rratio 0.25)
			(net 1 "GND")
			(pintype "passive")
		)
		(pad "2" smd roundrect
			(at 0.48 0 180)
			(size 0.59 0.64)
			(layers "F.Cu" "F.Mask" "F.Paste")
			(roundrect_rratio 0.25)
			(net 7 "/CSI/CSIA_5V")
			(pintype "passive")
		)
	)
	(footprint "antmicro-footprints:C_0402_1005Metric"
		(layer "F.Cu")
		(at 63.9 98 90)
		(descr "Capacitor SMD 0402")
		(tags "capacitor SMD 0402")
		(property "Reference" "C166"
			(at -1.6 -0.6 90)
			(layer "F.SilkS")
			(effects
				(font
					(size 0.7 0.7)
					(thickness 0.15)
				)
				(justify left bottom)
			)
		)
		(property "Value" "C_100n_0402"
			(at -1.022927 2.155213 90)
			(layer "F.Fab")
			(effects
				(font
					(size 0.7 0.7)
					(thickness 0.15)
				)
				(justify left bottom)
			)
		)
		(property "Datasheet" "https://www.murata.com/products/productdetail?partno=GRM155R61H104KE14%23"
			(at 0 0 90)
			(layer "F.Fab")
			(hide yes)
			(effects
				(font
					(size 1.27 1.27)
					(thickness 0.15)
				)
			)
		)
		(property "Description" "SMD Multilayer Ceramic Capacitor, 0.1 µF, 50 V, 0402 [1005 Metric], ± 10%, X5R, GRM Series"
			(at 0 0 90)
			(layer "F.Fab")
			(hide yes)
			(effects
				(font
					(size 1.27 1.27)
					(thickness 0.15)
				)
			)
		)
		(property "Manufacturer" "Murata"
			(at 0 0 90)
			(unlocked yes)
			(layer "F.Fab")
			(hide yes)
			(effects
				(font
					(size 1 1)
					(thickness 0.15)
				)
			)
		)
		(property "MPN" "GRM155R61H104KE14D"
			(at 0 0 90)
			(unlocked yes)
			(layer "F.Fab")
			(hide yes)
			(effects
				(font
					(size 1 1)
					(thickness 0.15)
				)
			)
		)
		(property "Val" "100n"
			(at 0 0 90)
			(unlocked yes)
			(layer "F.Fab")
			(hide yes)
			(effects
				(font
					(size 1 1)
					(thickness 0.15)
				)
			)
		)
		(property "License" "Apache-2.0"
			(at 0 0 90)
			(unlocked yes)
			(layer "F.Fab")
			(hide yes)
			(effects
				(font
					(size 1 1)
					(thickness 0.15)
				)
			)
		)
		(property "Author" "Antmicro"
			(at 0 0 90)
			(unlocked yes)
			(layer "F.Fab")
			(hide yes)
			(effects
				(font
					(size 1 1)
					(thickness 0.15)
				)
			)
		)
		(property "Voltage" "50V"
			(at 0 0 90)
			(unlocked yes)
			(layer "F.Fab")
			(hide yes)
			(effects
				(font
					(size 1 1)
					(thickness 0.15)
				)
			)
		)
		(property "Dielectric" "X5R"
			(at 0 0 90)
			(unlocked yes)
			(layer "F.Fab")
			(hide yes)
			(effects
				(font
					(size 1 1)
					(thickness 0.15)
				)
			)
		)
		(sheetname "/CSI/")
		(sheetfile "csi.kicad_sch")
		(attr smd)
		(fp_poly
			(pts
				(xy -0.925 -0.47) (xy -0.925 0.47) (xy 0.925 0.47) (xy 0.925 -0.47)
			)
			(stroke
				(width 0.05)
				(type default)
			)
			(fill no)
			(layer "F.CrtYd")
		)
		(fp_line
			(start 0.504 -0.25)
			(end 0.504 0.248)
			(stroke
				(width 0.15)
				(type solid)
			)
			(layer "F.Fab")
		)
		(fp_line
			(start -0.494 -0.25)
			(end 0.504 -0.25)
			(stroke
				(width 0.15)
				(type solid)
			)
			(layer "F.Fab")
		)
		(fp_line
			(start 0.504 0.248)
			(end -0.494 0.248)
			(stroke
				(width 0.15)
				(type solid)
			)
			(layer "F.Fab")
		)
		(fp_line
			(start -0.494 0.248)
			(end -0.494 -0.25)
			(stroke
				(width 0.15)
				(type solid)
			)
			(layer "F.Fab")
		)
		(fp_text user "License: Apache-2.0"
			(at -0.939 5.799 90)
			(layer "F.Fab")
			(effects
				(font
					(size 0.7 0.7)
					(thickness 0.15)
				)
				(justify left bottom)
			)
		)
		(fp_text user "Author: Antmicro"
			(at -0.939 3.399 90)
			(layer "F.Fab")
			(effects
				(font
					(size 0.7 0.7)
					(thickness 0.15)
				)
				(justify left bottom)
			)
		)
		(fp_text user "${REFERENCE}"
			(at -0.939 4.599 90)
			(layer "F.Fab")
			(effects
				(font
					(size 0.7 0.7)
					(thickness 0.15)
				)
				(justify left bottom)
			)
		)
		(pad "1" smd roundrect
			(at -0.48 0 90)
			(size 0.59 0.64)
			(layers "F.Cu" "F.Mask" "F.Paste")
			(roundrect_rratio 0.25)
			(net 1 "GND")
			(pintype "passive")
		)
		(pad "2" smd roundrect
			(at 0.48 0 90)
			(size 0.59 0.64)
			(layers "F.Cu" "F.Mask" "F.Paste")
			(roundrect_rratio 0.25)
			(net 2 "+3V3")
			(pintype "passive")
		)
	)
	(footprint "antmicro-footprints:USON-10_2.5x1mm_P0.5mm"
		(layer "F.Cu")
		(at 221.404132 89.587)
		(descr "USON-10 2.5x1mm_ Pitch 0.5mm")
		(tags "USON-10 2.5x1mm Pitch 0.5mm")
		(property "Reference" "U38"
			(at 1.928 1.005 90)
			(layer "F.SilkS")
			(effects
				(font
					(size 0.7 0.7)
					(thickness 0.15)
				)
				(justify left bottom)
			)
		)
		(property "Value" "TPD4E05U06QDQARQ1"
			(at 0.018 2.499 0)
			(layer "F.Fab")
			(effects
				(font
					(size 0.7 0.7)
					(thickness 0.15)
				)
				(justify left bottom)
			)
		)
		(property "Datasheet" "https://www.ti.com/lit/ds/symlink/tpd4e05u06-q1.pdf?HQS=dis-mous-null-mousermode-dsf-pf-null-wwe&ts=1663591265741&ref_url=https%253A%252F%252Fwww.mouser.com%252F"
			(at 0 0 0)
			(layer "F.Fab")
			(hide yes)
			(effects
				(font
					(size 1.27 1.27)
					(thickness 0.15)
				)
			)
		)
		(property "Description" "TVS diode array, 12 kV, USON-10, 5.5 V, 0.5 pF"
			(at 0 0 0)
			(layer "F.Fab")
			(hide yes)
			(effects
				(font
					(size 1.27 1.27)
					(thickness 0.15)
				)
			)
		)
		(property "Manufacturer" "Texas Instruments"
			(at 0 0 0)
			(unlocked yes)
			(layer "F.Fab")
			(hide yes)
			(effects
				(font
					(size 1 1)
					(thickness 0.15)
				)
			)
		)
		(property "MPN" "TPD4E05U06QDQARQ1"
			(at 0 0 0)
			(unlocked yes)
			(layer "F.Fab")
			(hide yes)
			(effects
				(font
					(size 1 1)
					(thickness 0.15)
				)
			)
		)
		(property "Author" "Antmicro"
			(at 0 0 0)
			(unlocked yes)
			(layer "F.Fab")
			(hide yes)
			(effects
				(font
					(size 1 1)
					(thickness 0.15)
				)
			)
		)
		(property "License" "Apache-2.0"
			(at 0 0 0)
			(unlocked yes)
			(layer "F.Fab")
			(hide yes)
			(effects
				(font
					(size 1 1)
					(thickness 0.15)
				)
			)
		)
		(sheetname "/USB DP Alt mode/")
		(sheetfile "usb_dp.kicad_sch")
		(attr smd)
		(fp_line
			(start 0.498 -1.401)
			(end -0.5 -1.401)
			(stroke
				(width 0.15)
				(type solid)
			)
			(layer "F.SilkS")
		)
		(fp_line
			(start 0.498 1.398)
			(end -0.5 1.398)
			(stroke
				(width 0.15)
				(type solid)
			)
			(layer "F.SilkS")
		)
		(fp_circle
			(center -0.68 -1.27)
			(end -0.63 -1.27)
			(stroke
				(width 0.15)
				(type solid)
			)
			(fill yes)
			(layer "F.SilkS")
		)
		(fp_rect
			(start -0.8 -1.5)
			(end 0.8 1.499)
			(stroke
				(width 0.05)
				(type solid)
			)
			(fill no)
			(layer "F.CrtYd")
		)
		(fp_line
			(start -0.5 -1)
			(end -0.5 1.249)
			(stroke
				(width 0.15)
				(type solid)
			)
			(layer "F.Fab")
		)
		(fp_line
			(start -0.5 1.249)
			(end 0.498 1.249)
			(stroke
				(width 0.15)
				(type solid)
			)
			(layer "F.Fab")
		)
		(fp_line
			(start -0.25 -1.25)
			(end -0.5 -1)
			(stroke
				(width 0.15)
				(type solid)
			)
			(layer "F.Fab")
		)
		(fp_line
			(start 0.498 -1.25)
			(end -0.25 -1.25)
			(stroke
				(width 0.15)
				(type solid)
			)
			(layer "F.Fab")
		)
		(fp_line
			(start 0.498 -1.25)
			(end 0.498 1.249)
			(stroke
				(width 0.15)
				(type solid)
			)
			(layer "F.Fab")
		)
		(fp_text user "Author: Antmicro"
			(at -0.802 5.7 0)
			(layer "F.Fab")
			(effects
				(font
					(size 0.7 0.7)
					(thickness 0.15)
				)
				(justify left bottom)
			)
		)
		(fp_text user "License: Apache-2.0"
			(at -0.802 6.9 0)
			(layer "F.Fab")
			(effects
				(font
					(size 0.7 0.7)
					(thickness 0.15)
				)
				(justify left bottom)
			)
		)
		(fp_text user "${REFERENCE}"
			(at -0.802 4.498 0)
			(layer "F.Fab")
			(effects
				(font
					(size 0.7 0.7)
					(thickness 0.15)
				)
				(justify left bottom)
			)
		)
		(pad "1" smd roundrect
			(at -0.387 -1 270)
			(size 0.25 0.55)
			(layers "F.Cu" "F.Mask" "F.Paste")
			(roundrect_rratio 0.25)
			(net 140 "/SoM_IO2/USB1.D-")
			(pintype "passive")
		)
		(pad "2" smd roundrect
			(at -0.387 -0.5 270)
			(size 0.25 0.55)
			(layers "F.Cu" "F.Mask" "F.Paste")
			(roundrect_rratio 0.25)
			(net 55 "/SoM_IO2/USB1.D+")
			(pintype "passive")
		)
		(pad "3" smd roundrect
			(at -0.387 0 270)
			(size 0.4 0.55)
			(layers "F.Cu" "F.Mask" "F.Paste")
			(roundrect_rratio 0.25)
			(net 1 "GND")
			(pintype "power_in")
		)
		(pad "4" smd roundrect
			(at -0.387 0.498 270)
			(size 0.25 0.55)
			(layers "F.Cu" "F.Mask" "F.Paste")
			(roundrect_rratio 0.25)
			(net 816 "/USB DP Alt mode/USBC1_CC2")
			(pintype "passive")
		)
		(pad "5" smd roundrect
			(at -0.387 0.998 270)
			(size 0.25 0.55)
			(layers "F.Cu" "F.Mask" "F.Paste")
			(roundrect_rratio 0.25)
			(net 817 "/USB DP Alt mode/USBC1_CC1")
			(pintype "passive")
		)
		(pad "6" smd roundrect
			(at 0.385 0.998 270)
			(size 0.25 0.55)
			(layers "F.Cu" "F.Mask" "F.Paste")
			(roundrect_rratio 0.25)
			(net 817 "/USB DP Alt mode/USBC1_CC1")
			(pintype "passive")
		)
		(pad "7" smd roundrect
			(at 0.385 0.498 270)
			(size 0.25 0.55)
			(layers "F.Cu" "F.Mask" "F.Paste")
			(roundrect_rratio 0.25)
			(net 816 "/USB DP Alt mode/USBC1_CC2")
			(pintype "passive")
		)
		(pad "8" smd roundrect
			(at 0.385 0 270)
			(size 0.4 0.55)
			(layers "F.Cu" "F.Mask" "F.Paste")
			(roundrect_rratio 0.25)
			(net 1 "GND")
			(pintype "passive")
		)
		(pad "9" smd roundrect
			(at 0.385 -0.5 270)
			(size 0.25 0.55)
			(layers "F.Cu" "F.Mask" "F.Paste")
			(roundrect_rratio 0.25)
			(net 55 "/SoM_IO2/USB1.D+")
			(pintype "passive")
		)
		(pad "10" smd roundrect
			(at 0.385 -1 270)
			(size 0.25 0.55)
			(layers "F.Cu" "F.Mask" "F.Paste")
			(roundrect_rratio 0.25)
			(net 140 "/SoM_IO2/USB1.D-")
			(pintype "passive")
		)
	)
	(footprint "antmicro-footprints:R_0402_1005Metric"
		(layer "F.Cu")
		(at 179.45 138.95 180)
		(descr "Resistor SMD 0402")
		(tags "resistor SMD 0402")
		(property "Reference" "R12"
			(at 0.85 0.65 0)
			(layer "F.SilkS")
			(effects
				(font
					(size 0.7 0.7)
					(thickness 0.15)
				)
				(justify right top)
			)
		)
		(property "Value" "R_499k_0402"
			(at -1.011843 1.772047 0)
			(layer "F.Fab")
			(effects
				(font
					(size 0.7 0.7)
					(thickness 0.15)
				)
				(justify right top)
			)
		)
		(property "Datasheet" "https://www.mouser.com/datasheet/2/54/cr-1858361.pdf"
			(at 0 0 0)
			(layer "F.Fab")
			(hide yes)
			(effects
				(font
					(size 1.27 1.27)
					(thickness 0.15)
				)
			)
		)
		(property "Description" "SMD Chip Resistor, 499 kohm, ± 1%, 63 mW, 0402 [1005 Metric], Thick Film, General Purpose"
			(at 0 0 0)
			(layer "F.Fab")
			(hide yes)
			(effects
				(font
					(size 1.27 1.27)
					(thickness 0.15)
				)
			)
		)
		(property "MPN" "CR0402-FX-4993GLF"
			(at 0 0 180)
			(unlocked yes)
			(layer "F.Fab")
			(hide yes)
			(effects
				(font
					(size 1 1)
					(thickness 0.15)
				)
			)
		)
		(property "Manufacturer" "Bourns"
			(at 0 0 180)
			(unlocked yes)
			(layer "F.Fab")
			(hide yes)
			(effects
				(font
					(size 1 1)
					(thickness 0.15)
				)
			)
		)
		(property "License" "Apache-2.0"
			(at 0 0 180)
			(unlocked yes)
			(layer "F.Fab")
			(hide yes)
			(effects
				(font
					(size 1 1)
					(thickness 0.15)
				)
			)
		)
		(property "Author" "Antmicro"
			(at 0 0 180)
			(unlocked yes)
			(layer "F.Fab")
			(hide yes)
			(effects
				(font
					(size 1 1)
					(thickness 0.15)
				)
			)
		)
		(property "Val" "499k"
			(at 0 0 180)
			(unlocked yes)
			(layer "F.Fab")
			(hide yes)
			(effects
				(font
					(size 1 1)
					(thickness 0.15)
				)
			)
		)
		(property "Tolerance" "1%"
			(at 0 0 180)
			(unlocked yes)
			(layer "F.Fab")
			(hide yes)
			(effects
				(font
					(size 1 1)
					(thickness 0.15)
				)
			)
		)
		(sheetname "/DCDC/")
		(sheetfile "dcdc.kicad_sch")
		(attr smd exclude_from_pos_files exclude_from_bom dnp)
		(fp_rect
			(start -0.925 -0.47)
			(end 0.925 0.47)
			(stroke
				(width 0.05)
				(type default)
			)
			(fill no)
			(layer "F.CrtYd")
		)
		(fp_rect
			(start -0.5 -0.25)
			(end 0.5 0.25)
			(stroke
				(width 0.15)
				(type solid)
			)
			(fill no)
			(layer "F.Fab")
		)
		(fp_text user "Author: Antmicro"
			(at -0.95 4.169 0)
			(layer "F.Fab")
			(effects
				(font
					(size 0.7 0.7)
					(thickness 0.15)
				)
				(justify right top)
			)
		)
		(fp_text user "${REFERENCE}"
			(at -0.95 3.168 0)
			(layer "F.Fab")
			(effects
				(font
					(size 0.7 0.7)
					(thickness 0.15)
				)
				(justify right top)
			)
		)
		(fp_text user "License: Apache-2.0"
			(at -0.95 5.169 0)
			(layer "F.Fab")
			(effects
				(font
					(size 0.7 0.7)
					(thickness 0.15)
				)
				(justify right top)
			)
		)
		(pad "1" smd roundrect
			(at -0.48 0 180)
			(size 0.59 0.64)
			(layers "F.Cu" "F.Mask" "F.Paste")
			(roundrect_rratio 0.25)
			(net 1204 "/DCDC/12V_MODE1")
			(pintype "passive")
		)
		(pad "2" smd roundrect
			(at 0.48 0 180)
			(size 0.59 0.64)
			(layers "F.Cu" "F.Mask" "F.Paste")
			(roundrect_rratio 0.25)
			(net 20 "/DCDC/12V_VDD")
			(pintype "passive")
		)
	)
	(footprint "antmicro-footprints:DFN-6-1EP_3x2mm_P0.5mm_EP1.65x1.35mm"
		(layer "F.Cu")
		(at 97.7 59.35 -90)
		(property "Reference" "U3"
			(at -0.8 -1.45 90)
			(layer "F.SilkS")
			(effects
				(font
					(size 0.7 0.7)
					(thickness 0.15)
				)
				(justify right top)
			)
		)
		(property "Value" "LTC6994CDCB-1_DFN"
			(at -1.1 2.2 90)
			(layer "F.Fab")
			(effects
				(font
					(size 0.7 0.7)
					(thickness 0.15)
				)
				(justify right top)
			)
		)
		(property "Datasheet" "https://www.analog.com/media/en/technical-documentation/data-sheets/699412fb.pdf"
			(at 0 0 90)
			(layer "F.Fab")
			(hide yes)
			(effects
				(font
					(size 1.27 1.27)
					(thickness 0.15)
				)
			)
		)
		(property "Description" "Programmable delay block"
			(at 0 0 90)
			(layer "F.Fab")
			(hide yes)
			(effects
				(font
					(size 1.27 1.27)
					(thickness 0.15)
				)
			)
		)
		(property "MPN" "LTC6994CDCB-1#TRMPBF"
			(at 0 0 270)
			(unlocked yes)
			(layer "F.Fab")
			(hide yes)
			(effects
				(font
					(size 1 1)
					(thickness 0.15)
				)
			)
		)
		(property "Manufacturer" "Analog Devices"
			(at 0 0 270)
			(unlocked yes)
			(layer "F.Fab")
			(hide yes)
			(effects
				(font
					(size 1 1)
					(thickness 0.15)
				)
			)
		)
		(property "Author" "Antmicro"
			(at 0 0 270)
			(unlocked yes)
			(layer "F.Fab")
			(hide yes)
			(effects
				(font
					(size 1 1)
					(thickness 0.15)
				)
			)
		)
		(property "License" "Apache-2.0"
			(at 0 0 270)
			(unlocked yes)
			(layer "F.Fab")
			(hide yes)
			(effects
				(font
					(size 1 1)
					(thickness 0.15)
				)
			)
		)
		(sheetname "/SoM_Power/")
		(sheetfile "som_power.kicad_sch")
		(attr smd)
		(fp_line
			(start -1.5 1.1)
			(end 1.5 1.1)
			(stroke
				(width 0.15)
				(type solid)
			)
			(layer "F.SilkS")
		)
		(fp_line
			(start 0 -1.1)
			(end 1.5 -1.1)
			(stroke
				(width 0.15)
				(type solid)
			)
			(layer "F.SilkS")
		)
		(fp_circle
			(center -1.7 -0.9)
			(end -1.65 -0.9)
			(stroke
				(width 0.15)
				(type solid)
			)
			(fill yes)
			(layer "F.SilkS")
		)
		(fp_rect
			(start -1.9 -1.25)
			(end 1.9 1.25)
			(stroke
				(width 0.05)
				(type solid)
			)
			(fill no)
			(layer "F.CrtYd")
		)
		(fp_line
			(start -1.5 1)
			(end -1.5 -0.5)
			(stroke
				(width 0.15)
				(type solid)
			)
			(layer "F.Fab")
		)
		(fp_line
			(start 1.5 1)
			(end -1.5 1)
			(stroke
				(width 0.15)
				(type solid)
			)
			(layer "F.Fab")
		)
		(fp_line
			(start -1.5 -0.5)
			(end -1 -1)
			(stroke
				(width 0.15)
				(type solid)
			)
			(layer "F.Fab")
		)
		(fp_line
			(start -1 -1)
			(end 1.5 -1)
			(stroke
				(width 0.15)
				(type solid)
			)
			(layer "F.Fab")
		)
		(fp_line
			(start 1.5 -1)
			(end 1.5 1)
			(stroke
				(width 0.15)
				(type solid)
			)
			(layer "F.Fab")
		)
		(fp_text user "${REFERENCE}"
			(at -2.45 3.95 90)
			(layer "F.Fab")
			(effects
				(font
					(size 0.7 0.7)
					(thickness 0.15)
				)
				(justify right top)
			)
		)
		(fp_text user "License: Apache-2.0"
			(at -2.45 6.35 90)
			(layer "F.Fab")
			(effects
				(font
					(size 0.7 0.7)
					(thickness 0.15)
				)
				(justify right top)
			)
		)
		(fp_text user "Author: Antmicro"
			(at -2.45 5.15 90)
			(layer "F.Fab")
			(effects
				(font
					(size 0.7 0.7)
					(thickness 0.15)
				)
				(justify right top)
			)
		)
		(pad "" smd roundrect
			(at -0.41 -0.34 270)
			(size 0.67 0.54)
			(layers "F.Paste")
			(roundrect_rratio 0.25)
		)
		(pad "" smd roundrect
			(at -0.41 0.34 270)
			(size 0.67 0.54)
			(layers "F.Paste")
			(roundrect_rratio 0.25)
		)
		(pad "" smd roundrect
			(at 0.41 -0.34 270)
			(size 0.67 0.54)
			(layers "F.Paste")
			(roundrect_rratio 0.25)
		)
		(pad "" smd roundrect
			(at 0.41 0.34 270)
			(size 0.67 0.54)
			(layers "F.Paste")
			(roundrect_rratio 0.25)
		)
		(pad "1" smd rect
			(at -1.425 -0.5 270)
			(size 0.7 0.25)
			(layers "F.Cu" "F.Mask" "F.Paste")
			(net 4 "+3V3_AON")
			(pinfunction "V+")
			(pintype "power_in")
		)
		(pad "2" smd rect
			(at -1.425 0 270)
			(size 0.7 0.25)
			(layers "F.Cu" "F.Mask" "F.Paste")
			(net 1380 "Net-(U3-DIV)")
			(pinfunction "DIV")
			(pintype "input")
		)
		(pad "3" smd rect
			(at -1.425 0.5 270)
			(size 0.7 0.25)
			(layers "F.Cu" "F.Mask" "F.Paste")
			(net 1381 "Net-(U3-SET)")
			(pinfunction "SET")
			(pintype "passive")
		)
		(pad "4" smd rect
			(at 1.425 0.5 270)
			(size 0.7 0.25)
			(layers "F.Cu" "F.Mask" "F.Paste")
			(net 1287 "/SoM_Power/MODULE_POWER_ON")
			(pinfunction "IN")
			(pintype "input")
		)
		(pad "5" smd rect
			(at 1.425 0 270)
			(size 0.7 0.25)
			(layers "F.Cu" "F.Mask" "F.Paste")
			(net 1 "GND")
			(pinfunction "GND")
			(pintype "power_in")
		)
		(pad "6" smd rect
			(at 1.425 -0.5 270)
			(size 0.7 0.25)
			(layers "F.Cu" "F.Mask" "F.Paste")
			(net 1235 "Net-(Q30-S)")
			(pinfunction "OUT")
			(pintype "output")
		)
		(pad "7" smd rect
			(at 0 0 270)
			(size 1.65 1.35)
			(layers "F.Cu" "F.Mask")
			(net 1 "GND")
			(pinfunction "EP")
			(pintype "passive")
		)
	)
	(footprint "antmicro-footprints:R_0402_1005Metric"
		(layer "F.Cu")
		(at 91.5 147.75 -90)
		(descr "Resistor SMD 0402")
		(tags "resistor SMD 0402")
		(property "Reference" "R191"
			(at -3.745 0.34 90)
			(layer "F.SilkS")
			(effects
				(font
					(size 0.7 0.7)
					(thickness 0.15)
				)
				(justify right top)
			)
		)
		(property "Value" "R_49R9_0402"
			(at -1.011843 1.772046 90)
			(layer "F.Fab")
			(effects
				(font
					(size 0.7 0.7)
					(thickness 0.15)
				)
				(justify right top)
			)
		)
		(property "Datasheet" "https://www.bourns.com/docs/product-datasheets/cr.pdf"
			(at 0 0 90)
			(layer "F.Fab")
			(hide yes)
			(effects
				(font
					(size 1.27 1.27)
					(thickness 0.15)
				)
			)
		)
		(property "Description" "SMD Chip Resistor, 49.9 ohm, ± 1%, 62.5 mW, 0402 [1005 Metric], Thick Film, General Purpose"
			(at 0 0 90)
			(layer "F.Fab")
			(hide yes)
			(effects
				(font
					(size 1.27 1.27)
					(thickness 0.15)
				)
			)
		)
		(property "MPN" "CR0402-FX-49R9GLF"
			(at 0 0 270)
			(unlocked yes)
			(layer "F.Fab")
			(hide yes)
			(effects
				(font
					(size 1 1)
					(thickness 0.15)
				)
			)
		)
		(property "Manufacturer" "Bourns"
			(at 0 0 270)
			(unlocked yes)
			(layer "F.Fab")
			(hide yes)
			(effects
				(font
					(size 1 1)
					(thickness 0.15)
				)
			)
		)
		(property "License" "Apache-2.0"
			(at 0 0 270)
			(unlocked yes)
			(layer "F.Fab")
			(hide yes)
			(effects
				(font
					(size 1 1)
					(thickness 0.15)
				)
			)
		)
		(property "Author" "Antmicro"
			(at 0 0 270)
			(unlocked yes)
			(layer "F.Fab")
			(hide yes)
			(effects
				(font
					(size 1 1)
					(thickness 0.15)
				)
			)
		)
		(property "Val" "49R9"
			(at 0 0 270)
			(unlocked yes)
			(layer "F.Fab")
			(hide yes)
			(effects
				(font
					(size 1 1)
					(thickness 0.15)
				)
			)
		)
		(property "Tolerance" "1%"
			(at 0 0 270)
			(unlocked yes)
			(layer "F.Fab")
			(hide yes)
			(effects
				(font
					(size 1 1)
					(thickness 0.15)
				)
			)
		)
		(sheetname "/SoM_IO2/")
		(sheetfile "som_io2.kicad_sch")
		(attr smd)
		(fp_poly
			(pts
				(xy -0.925 -0.47) (xy 0.925 -0.47) (xy 0.925 0.47) (xy -0.925 0.47)
			)
			(stroke
				(width 0.05)
				(type default)
			)
			(fill no)
			(layer "F.CrtYd")
		)
		(fp_poly
			(pts
				(xy -0.5 -0.25) (xy 0.5 -0.25) (xy 0.5 0.25) (xy -0.5 0.25)
			)
			(stroke
				(width 0.15)
				(type solid)
			)
			(fill no)
			(layer "F.Fab")
		)
		(fp_text user "License: Apache-2.0"
			(at -0.949999 5.169 90)
			(layer "F.Fab")
			(effects
				(font
					(size 0.7 0.7)
					(thickness 0.15)
				)
				(justify right top)
			)
		)
		(fp_text user "${REFERENCE}"
			(at -0.95 3.168 90)
			(layer "F.Fab")
			(effects
				(font
					(size 0.7 0.7)
					(thickness 0.15)
				)
				(justify right top)
			)
		)
		(fp_text user "Author: Antmicro"
			(at -0.95 4.169 90)
			(layer "F.Fab")
			(effects
				(font
					(size 0.7 0.7)
					(thickness 0.15)
				)
				(justify right top)
			)
		)
		(pad "1" smd roundrect
			(at -0.48 0 270)
			(size 0.59 0.64)
			(layers "F.Cu" "F.Mask" "F.Paste")
			(roundrect_rratio 0.25)
			(net 1 "GND")
			(pintype "passive")
		)
		(pad "2" smd roundrect
			(at 0.48 0 270)
			(size 0.59 0.64)
			(layers "F.Cu" "F.Mask" "F.Paste")
			(roundrect_rratio 0.25)
			(net 1002 "/SoM_IO2/C2_REFCLK-")
			(pintype "passive")
		)
	)
	(footprint "antmicro-footprints:USB-C_Receptacle_Kycon_KUSBX-SL2-CS1N24-B-TR"
		(locked yes)
		(layer "F.Cu")
		(at 236.455532 76.21 90)
		(descr "USB-C (USB TYPE-C) USB 3.2 Gen 2 (USB 3.1 Gen 2, Superspeed + (USB 3.1)) Receptacle Connector 24 Position Through Hole, Right Angle")
		(tags "CONNECTOR, USB")
		(property "Reference" "J7"
			(at 3.11 -10.785532 180)
			(layer "F.SilkS")
			(effects
				(font
					(size 0.7 0.7)
					(thickness 0.15)
				)
				(justify left bottom)
			)
		)
		(property "Value" "USB-C_Kycon_KUSBX-SL2-CS1N24-B-TR"
			(at 0 7.5 90)
			(layer "F.Fab")
			(effects
				(font
					(size 0.7 0.7)
					(thickness 0.15)
				)
				(justify right top)
			)
		)
		(property "Datasheet" "https://www.kycon.com/Pub_Eng_Draw/KUSBX-SL2-CS1N24-B-TR.pdf"
			(at 0 0 90)
			(layer "F.Fab")
			(hide yes)
			(effects
				(font
					(size 1.27 1.27)
					(thickness 0.15)
				)
			)
		)
		(property "Description" "USB-C (USB TYPE-C) USB 3.2 Gen 2 (USB 3.1 Gen 2, Superspeed + (USB 3.1)) USB PD Receptacle Connector 24 Position Surface Mount"
			(at 0 0 90)
			(layer "F.Fab")
			(hide yes)
			(effects
				(font
					(size 1.27 1.27)
					(thickness 0.15)
				)
			)
		)
		(property "MPN" "KUSBX-SL2-CS1N24-B-TR"
			(at 0 0 270)
			(unlocked yes)
			(layer "F.Fab")
			(hide yes)
			(effects
				(font
					(size 1 1)
					(thickness 0.15)
				)
			)
		)
		(property "Manufacturer" "Kycon"
			(at 0 0 270)
			(unlocked yes)
			(layer "F.Fab")
			(hide yes)
			(effects
				(font
					(size 1 1)
					(thickness 0.15)
				)
			)
		)
		(property "License" "Apache-2.0"
			(at 0 0 270)
			(unlocked yes)
			(layer "F.Fab")
			(hide yes)
			(effects
				(font
					(size 1 1)
					(thickness 0.15)
				)
			)
		)
		(property "Author" "Antmicro"
			(at 0 0 270)
			(unlocked yes)
			(layer "F.Fab")
			(hide yes)
			(effects
				(font
					(size 1 1)
					(thickness 0.15)
				)
			)
		)
		(sheetname "/USB Debug, PD/")
		(sheetfile "usb_debug_pd.kicad_sch")
		(attr smd)
		(fp_line
			(start 1 -8.8)
			(end 1 -8.8)
			(stroke
				(width 0.15)
				(type solid)
			)
			(layer "F.SilkS")
		)
		(fp_line
			(start 1 -8.8)
			(end -1 -8.8)
			(stroke
				(width 0.15)
				(type solid)
			)
			(layer "F.SilkS")
		)
		(fp_line
			(start -1 -8.8)
			(end 1 -8.8)
			(stroke
				(width 0.15)
				(type solid)
			)
			(layer "F.SilkS")
		)
		(fp_line
			(start -1 -8.8)
			(end -1 -8.8)
			(stroke
				(width 0.15)
				(type solid)
			)
			(layer "F.SilkS")
		)
		(fp_rect
			(start -4 -9.4)
			(end 4 5.65)
			(stroke
				(width 0.05)
				(type solid)
			)
			(fill no)
			(layer "F.CrtYd")
		)
		(fp_line
			(start 2.25 -8.8)
			(end -2.25 -8.8)
			(stroke
				(width 0.15)
				(type solid)
			)
			(layer "F.Fab")
		)
		(fp_line
			(start -2.25 -8.8)
			(end -2.25 5.5)
			(stroke
				(width 0.15)
				(type solid)
			)
			(layer "F.Fab")
		)
		(fp_line
			(start 2.25 5.5)
			(end 2.25 -8.8)
			(stroke
				(width 0.15)
				(type solid)
			)
			(layer "F.Fab")
		)
		(fp_line
			(start -2.25 5.5)
			(end 2.25 5.5)
			(stroke
				(width 0.15)
				(type solid)
			)
			(layer "F.Fab")
		)
		(fp_text user "License: Apache-2.0"
			(at -5.47 10.9 90)
			(layer "F.Fab")
			(effects
				(font
					(size 0.7 0.7)
					(thickness 0.15)
				)
				(justify left bottom)
			)
		)
		(fp_text user "${REFERENCE}"
			(at -5.47 8.5 90)
			(layer "F.Fab")
			(effects
				(font
					(size 0.7 0.7)
					(thickness 0.15)
				)
				(justify left bottom)
			)
		)
		(fp_text user "Author: Antmicro"
			(at -5.47 9.7 90)
			(layer "F.Fab")
			(effects
				(font
					(size 0.7 0.7)
					(thickness 0.15)
				)
				(justify left bottom)
			)
		)
		(pad "" np_thru_hole circle
			(at 0 -7.6 90)
			(size 1.1 1.1)
			(drill 1.1)
			(layers "*.Cu" "*.Mask")
		)
		(pad "" np_thru_hole circle
			(at 0 0 90)
			(size 1 1)
			(drill 1)
			(layers "*.Cu" "*.Mask")
		)
		(pad "A1" smd rect
			(at 1.1375 -6.525 180)
			(size 0.25 1.625)
			(layers "F.Cu" "F.Mask" "F.Paste")
			(net 1 "GND")
			(pinfunction "GND")
			(pintype "power_in")
		)
		(pad "A2" smd rect
			(at 1.1375 -6.025 180)
			(size 0.25 1.625)
			(layers "F.Cu" "F.Mask" "F.Paste")
			(net 1194 "unconnected-(J7-TX_{1}+-PadA2)")
			(pinfunction "TX_{1}+")
			(pintype "bidirectional+no_connect")
		)
		(pad "A3" smd rect
			(at 1.1375 -5.525 180)
			(size 0.25 1.625)
			(layers "F.Cu" "F.Mask" "F.Paste")
			(net 1193 "unconnected-(J7-TX_{1}--PadA3)")
			(pinfunction "TX_{1}-")
			(pintype "bidirectional+no_connect")
		)
		(pad "A4" smd rect
			(at 1.1375 -5.025 180)
			(size 0.25 1.625)
			(layers "F.Cu" "F.Mask" "F.Paste")
			(net 176 "/USB Debug, PD/USBC0_VBUS")
			(pinfunction "VBUS")
			(pintype "power_in")
		)
		(pad "A5" smd rect
			(at 1.1375 -4.525 180)
			(size 0.25 1.625)
			(layers "F.Cu" "F.Mask" "F.Paste")
			(net 514 "/USB Debug, PD/USBC0_CC1")
			(pinfunction "CC_{1}")
			(pintype "bidirectional")
		)
		(pad "A6" smd rect
			(at 1.1375 -4.025 180)
			(size 0.25 1.625)
			(layers "F.Cu" "F.Mask" "F.Paste")
			(net 489 "/USB Debug, PD/USBC0_D_P")
			(pinfunction "D_{A}+")
			(pintype "bidirectional")
		)
		(pad "A7" smd rect
			(at 1.1375 -3.525 180)
			(size 0.25 1.625)
			(layers "F.Cu" "F.Mask" "F.Paste")
			(net 488 "/USB Debug, PD/USBC0_D_N")
			(pinfunction "D_{A}-")
			(pintype "bidirectional")
		)
		(pad "A8" smd rect
			(at 1.1375 -3.025 180)
			(size 0.25 1.625)
			(layers "F.Cu" "F.Mask" "F.Paste")
			(net 813 "unconnected-(J7-SBU_{1}-PadA8)")
			(pinfunction "SBU_{1}")
			(pintype "bidirectional+no_connect")
		)
		(pad "A9" smd rect
			(at 1.1375 -2.525 180)
			(size 0.25 1.625)
			(layers "F.Cu" "F.Mask" "F.Paste")
			(net 176 "/USB Debug, PD/USBC0_VBUS")
			(pinfunction "VBUS")
			(pintype "passive")
		)
		(pad "A10" smd rect
			(at 1.1375 -2.025 180)
			(size 0.25 1.625)
			(layers "F.Cu" "F.Mask" "F.Paste")
			(net 1195 "unconnected-(J7-RX_{2}--PadA10)")
			(pinfunction "RX_{2}-")
			(pintype "bidirectional+no_connect")
		)
		(pad "A11" smd rect
			(at 1.1375 -1.525 180)
			(size 0.25 1.625)
			(layers "F.Cu" "F.Mask" "F.Paste")
			(net 1196 "unconnected-(J7-RX_{2}+-PadA11)")
			(pinfunction "RX_{2}+")
			(pintype "bidirectional+no_connect")
		)
		(pad "A12" smd rect
			(at 1.1375 -1.025 180)
			(size 0.25 1.625)
			(layers "F.Cu" "F.Mask" "F.Paste")
			(net 1 "GND")
			(pinfunction "GND")
			(pintype "passive")
		)
		(pad "B1" smd rect
			(at -1.1375 -1.025 180)
			(size 0.25 1.625)
			(layers "F.Cu" "F.Mask" "F.Paste")
			(net 1 "GND")
			(pinfunction "GND")
			(pintype "passive")
		)
		(pad "B2" smd rect
			(at -1.1375 -1.525 180)
			(size 0.25 1.625)
			(layers "F.Cu" "F.Mask" "F.Paste")
			(net 1192 "unconnected-(J7-TX_{2}+-PadB2)")
			(pinfunction "TX_{2}+")
			(pintype "bidirectional+no_connect")
		)
		(pad "B3" smd rect
			(at -1.1375 -2.025 180)
			(size 0.25 1.625)
			(layers "F.Cu" "F.Mask" "F.Paste")
			(net 1198 "unconnected-(J7-TX_{2}--PadB3)")
			(pinfunction "TX_{2}-")
			(pintype "bidirectional+no_connect")
		)
		(pad "B4" smd rect
			(at -1.1375 -2.525 180)
			(size 0.25 1.625)
			(layers "F.Cu" "F.Mask" "F.Paste")
			(net 176 "/USB Debug, PD/USBC0_VBUS")
			(pinfunction "VBUS")
			(pintype "passive")
		)
		(pad "B5" smd rect
			(at -1.1375 -3.025 180)
			(size 0.25 1.625)
			(layers "F.Cu" "F.Mask" "F.Paste")
			(net 515 "/USB Debug, PD/USBC0_CC2")
			(pinfunction "CC_{2}")
			(pintype "bidirectional")
		)
		(pad "B6" smd rect
			(at -1.1375 -3.525 180)
			(size 0.25 1.625)
			(layers "F.Cu" "F.Mask" "F.Paste")
			(net 489 "/USB Debug, PD/USBC0_D_P")
			(pinfunction "D_{B}+")
			(pintype "bidirectional")
		)
		(pad "B7" smd rect
			(at -1.1375 -4.025 180)
			(size 0.25 1.625)
			(layers "F.Cu" "F.Mask" "F.Paste")
			(net 488 "/USB Debug, PD/USBC0_D_N")
			(pinfunction "D_{B}-")
			(pintype "bidirectional")
		)
		(pad "B8" smd rect
			(at -1.1375 -4.525 180)
			(size 0.25 1.625)
			(layers "F.Cu" "F.Mask" "F.Paste")
			(net 814 "unconnected-(J7-SBU_{2}-PadB8)")
			(pinfunction "SBU_{2}")
			(pintype "bidirectional+no_connect")
		)
		(pad "B9" smd rect
			(at -1.1375 -5.025 180)
			(size 0.25 1.625)
			(layers "F.Cu" "F.Mask" "F.Paste")
			(net 176 "/USB Debug, PD/USBC0_VBUS")
			(pinfunction "VBUS")
			(pintype "passive")
		)
		(pad "B10" smd rect
			(at -1.1375 -5.525 180)
			(size 0.25 1.625)
			(layers "F.Cu" "F.Mask" "F.Paste")
			(net 1197 "unconnected-(J7-RX_{1}--PadB10)")
			(pinfunction "RX_{1}-")
			(pintype "bidirectional+no_connect")
		)
		(pad "B11" smd rect
			(at -1.1375 -6.025 180)
			(size 0.25 1.625)
			(layers "F.Cu" "F.Mask" "F.Paste")
			(net 1199 "unconnected-(J7-RX_{1}+-PadB11)")
			(pinfunction "RX_{1}+")
			(pintype "bidirectional+no_connect")
		)
		(pad "B12" smd rect
			(at -1.1375 -6.525 180)
			(size 0.25 1.625)
			(layers "F.Cu" "F.Mask" "F.Paste")
			(net 1 "GND")
			(pinfunction "GND")
			(pintype "passive")
		)
		(pad "SH" thru_hole oval
			(at -3 -7.849 90)
			(size 1 2.05)
			(drill oval 0.6 1.65)
			(layers "*.Cu" "*.Mask")
			(remove_unused_layers no)
			(net 1 "GND")
			(pinfunction "SH")
			(pintype "passive")
		)
		(pad "SH" thru_hole oval
			(at -3 0.25 90)
			(size 1 2.05)
			(drill oval 0.6 1.65)
			(layers "*.Cu" "*.Mask")
			(remove_unused_layers no)
			(net 1 "GND")
			(pinfunction "SH")
			(pintype "passive")
		)
		(pad "SH" thru_hole oval
			(at 3 -7.849 90)
			(size 1 2.05)
			(drill oval 0.6 1.65)
			(layers "*.Cu" "*.Mask")
			(remove_unused_layers no)
			(net 1 "GND")
			(pinfunction "SH")
			(pintype "passive")
		)
		(pad "SH" thru_hole oval
			(at 3 0.25 90)
			(size 1 2.05)
			(drill oval 0.6 1.65)
			(layers "*.Cu" "*.Mask")
			(remove_unused_layers no)
			(net 1 "GND")
			(pinfunction "SH")
			(pintype "passive")
		)
	)
	(footprint "antmicro-footprints:C_0402_1005Metric"
		(layer "F.Cu")
		(at 206.75 92.470856 180)
		(descr "Capacitor SMD 0402")
		(tags "capacitor SMD 0402")
		(property "Reference" "C321"
			(at 3.65 -0.929144 180)
			(layer "F.SilkS")
			(effects
				(font
					(size 0.7 0.7)
					(thickness 0.15)
				)
				(justify left bottom)
			)
		)
		(property "Value" "C_100n_0402"
			(at -1.022927 2.155213 180)
			(layer "F.Fab")
			(effects
				(font
					(size 0.7 0.7)
					(thickness 0.15)
				)
				(justify left bottom)
			)
		)
		(property "Datasheet" "https://www.murata.com/products/productdetail?partno=GRM155R61H104KE14%23"
			(at 0 0 180)
			(layer "F.Fab")
			(hide yes)
			(effects
				(font
					(size 1.27 1.27)
					(thickness 0.15)
				)
			)
		)
		(property "Description" "SMD Multilayer Ceramic Capacitor, 0.1 µF, 50 V, 0402 [1005 Metric], ± 10%, X5R, GRM Series"
			(at 0 0 180)
			(layer "F.Fab")
			(hide yes)
			(effects
				(font
					(size 1.27 1.27)
					(thickness 0.15)
				)
			)
		)
		(property "Manufacturer" "Murata"
			(at 0 0 180)
			(unlocked yes)
			(layer "F.Fab")
			(hide yes)
			(effects
				(font
					(size 1 1)
					(thickness 0.15)
				)
			)
		)
		(property "MPN" "GRM155R61H104KE14D"
			(at 0 0 180)
			(unlocked yes)
			(layer "F.Fab")
			(hide yes)
			(effects
				(font
					(size 1 1)
					(thickness 0.15)
				)
			)
		)
		(property "Val" "100n"
			(at 0 0 180)
			(unlocked yes)
			(layer "F.Fab")
			(hide yes)
			(effects
				(font
					(size 1 1)
					(thickness 0.15)
				)
			)
		)
		(property "License" "Apache-2.0"
			(at 0 0 180)
			(unlocked yes)
			(layer "F.Fab")
			(hide yes)
			(effects
				(font
					(size 1 1)
					(thickness 0.15)
				)
			)
		)
		(property "Author" "Antmicro"
			(at 0 0 180)
			(unlocked yes)
			(layer "F.Fab")
			(hide yes)
			(effects
				(font
					(size 1 1)
					(thickness 0.15)
				)
			)
		)
		(property "Voltage" "50V"
			(at 0 0 180)
			(unlocked yes)
			(layer "F.Fab")
			(hide yes)
			(effects
				(font
					(size 1 1)
					(thickness 0.15)
				)
			)
		)
		(property "Dielectric" "X5R"
			(at 0 0 180)
			(unlocked yes)
			(layer "F.Fab")
			(hide yes)
			(effects
				(font
					(size 1 1)
					(thickness 0.15)
				)
			)
		)
		(sheetname "/SoM_IO2/")
		(sheetfile "som_io2.kicad_sch")
		(attr smd)
		(fp_rect
			(start -0.925 -0.47)
			(end 0.925 0.47)
			(stroke
				(width 0.05)
				(type default)
			)
			(fill no)
			(layer "F.CrtYd")
		)
		(fp_line
			(start 0.504 0.248)
			(end -0.494 0.248)
			(stroke
				(width 0.15)
				(type solid)
			)
			(layer "F.Fab")
		)
		(fp_line
			(start 0.504 -0.25)
			(end 0.504 0.248)
			(stroke
				(width 0.15)
				(type solid)
			)
			(layer "F.Fab")
		)
		(fp_line
			(start -0.494 0.248)
			(end -0.494 -0.25)
			(stroke
				(width 0.15)
				(type solid)
			)
			(layer "F.Fab")
		)
		(fp_line
			(start -0.494 -0.25)
			(end 0.504 -0.25)
			(stroke
				(width 0.15)
				(type solid)
			)
			(layer "F.Fab")
		)
		(fp_text user "${REFERENCE}"
			(at -0.939 4.599 180)
			(layer "F.Fab")
			(effects
				(font
					(size 0.7 0.7)
					(thickness 0.15)
				)
				(justify left bottom)
			)
		)
		(fp_text user "License: Apache-2.0"
			(at -0.939 5.799 180)
			(layer "F.Fab")
			(effects
				(font
					(size 0.7 0.7)
					(thickness 0.15)
				)
				(justify left bottom)
			)
		)
		(fp_text user "Author: Antmicro"
			(at -0.939 3.399 180)
			(layer "F.Fab")
			(effects
				(font
					(size 0.7 0.7)
					(thickness 0.15)
				)
				(justify left bottom)
			)
		)
		(pad "1" smd roundrect
			(at -0.48 0 180)
			(size 0.59 0.64)
			(layers "F.Cu" "F.Mask" "F.Paste")
			(roundrect_rratio 0.25)
			(net 553 "/SoM_IO2/DP0.TX3-")
			(pintype "passive")
		)
		(pad "2" smd roundrect
			(at 0.48 0 180)
			(size 0.59 0.64)
			(layers "F.Cu" "F.Mask" "F.Paste")
			(roundrect_rratio 0.25)
			(net 799 "/SoM_IO2/DP0.TX3_C-")
			(pintype "passive")
		)
	)
	(footprint "antmicro-footprints:SC-70-6"
		(layer "F.Cu")
		(at 91 63.5)
		(property "Reference" "U74"
			(at -1.6 -1.2 0)
			(layer "F.SilkS")
			(effects
				(font
					(size 0.7 0.7)
					(thickness 0.15)
				)
				(justify left bottom)
			)
		)
		(property "Value" "SN74LVC2G07DCKR"
			(at 0 2.2 0)
			(layer "F.Fab")
			(effects
				(font
					(size 0.7 0.7)
					(thickness 0.15)
				)
				(justify left bottom)
			)
		)
		(property "Datasheet" "https://www.ti.com/lit/gpn/sn74lvc2g07"
			(at 0 0 0)
			(layer "F.Fab")
			(hide yes)
			(effects
				(font
					(size 1.27 1.27)
					(thickness 0.15)
				)
			)
		)
		(property "Description" "Buffer / Line Driver, SN74LVC2G07DCKR, 1.65 V to 5.5 V, SC-70-5"
			(at 0 0 0)
			(layer "F.Fab")
			(hide yes)
			(effects
				(font
					(size 1.27 1.27)
					(thickness 0.15)
				)
			)
		)
		(property "MPN" "SN74LVC2G07DCKR"
			(at 0 0 0)
			(unlocked yes)
			(layer "F.Fab")
			(hide yes)
			(effects
				(font
					(size 1 1)
					(thickness 0.15)
				)
			)
		)
		(property "Manufacturer" "Texas Instruments"
			(at 0 0 0)
			(unlocked yes)
			(layer "F.Fab")
			(hide yes)
			(effects
				(font
					(size 1 1)
					(thickness 0.15)
				)
			)
		)
		(property "Author" "Antmicro"
			(at 0 0 0)
			(unlocked yes)
			(layer "F.Fab")
			(hide yes)
			(effects
				(font
					(size 1 1)
					(thickness 0.15)
				)
			)
		)
		(property "License" "Apache-2.0"
			(at 0 0 0)
			(unlocked yes)
			(layer "F.Fab")
			(hide yes)
			(effects
				(font
					(size 1 1)
					(thickness 0.15)
				)
			)
		)
		(sheetname "/SoM_Power/")
		(sheetfile "som_power.kicad_sch")
		(attr smd)
		(fp_line
			(start -0.7 -1)
			(end 0.7 -1)
			(stroke
				(width 0.15)
				(type solid)
			)
			(layer "F.SilkS")
		)
		(fp_line
			(start -0.7 1)
			(end 0.7 1)
			(stroke
				(width 0.15)
				(type solid)
			)
			(layer "F.SilkS")
		)
		(fp_circle
			(center -1.1 -1)
			(end -1.025 -1)
			(stroke
				(width 0.15)
				(type solid)
			)
			(fill yes)
			(layer "F.SilkS")
		)
		(fp_rect
			(start -1.6 -1.1)
			(end 1.6 1.1)
			(stroke
				(width 0.05)
				(type solid)
			)
			(fill no)
			(layer "F.CrtYd")
		)
		(fp_line
			(start -0.593 0.993)
			(end -0.593 -0.706)
			(stroke
				(width 0.15)
				(type solid)
			)
			(layer "F.Fab")
		)
		(fp_line
			(start -0.293 -1.006)
			(end -0.593 -0.706)
			(stroke
				(width 0.15)
				(type solid)
			)
			(layer "F.Fab")
		)
		(fp_line
			(start -0.293 -1.006)
			(end 0.657 -1.006)
			(stroke
				(width 0.15)
				(type solid)
			)
			(layer "F.Fab")
		)
		(fp_line
			(start 0.657 -1.006)
			(end 0.657 0.993)
			(stroke
				(width 0.15)
				(type solid)
			)
			(layer "F.Fab")
		)
		(fp_line
			(start 0.657 0.993)
			(end -0.593 0.993)
			(stroke
				(width 0.15)
				(type solid)
			)
			(layer "F.Fab")
		)
		(fp_text user "Author: Antmicro"
			(at -1.45 4.2 0)
			(layer "F.Fab")
			(effects
				(font
					(size 0.7 0.7)
					(thickness 0.15)
				)
				(justify left bottom)
			)
		)
		(fp_text user "License: Apache-2.0"
			(at -1.45 6.6 0)
			(layer "F.Fab")
			(effects
				(font
					(size 0.7 0.7)
					(thickness 0.15)
				)
				(justify left bottom)
			)
		)
		(fp_text user "${REFERENCE}"
			(at -1.45 5.4 0)
			(layer "F.Fab")
			(effects
				(font
					(size 0.7 0.7)
					(thickness 0.15)
				)
				(justify left bottom)
			)
		)
		(pad "1" smd roundrect
			(at -1.1 -0.65)
			(size 0.85 0.35)
			(layers "F.Cu" "F.Mask" "F.Paste")
			(roundrect_rratio 0.25)
			(net 246 "/SoM_Power/~{VDDIN_PWR_BAD}")
			(pinfunction "1A")
			(pintype "input")
		)
		(pad "2" smd roundrect
			(at -1.1 0)
			(size 0.85 0.35)
			(layers "F.Cu" "F.Mask" "F.Paste")
			(roundrect_rratio 0.25)
			(net 1 "GND")
			(pinfunction "GND")
			(pintype "power_in")
		)
		(pad "3" smd roundrect
			(at -1.1 0.65)
			(size 0.85 0.35)
			(layers "F.Cu" "F.Mask" "F.Paste")
			(roundrect_rratio 0.25)
			(net 1032 "/SoM_Power/~{FORCE_SHDN}")
			(pinfunction "2A")
			(pintype "input")
		)
		(pad "4" smd roundrect
			(at 1.1 0.65)
			(size 0.85 0.35)
			(layers "F.Cu" "F.Mask" "F.Paste")
			(roundrect_rratio 0.25)
			(net 1304 "Net-(U74-2Y)")
			(pinfunction "2Y")
			(pintype "open_collector")
		)
		(pad "5" smd roundrect
			(at 1.1 0)
			(size 0.85 0.35)
			(layers "F.Cu" "F.Mask" "F.Paste")
			(roundrect_rratio 0.25)
			(net 4 "+3V3_AON")
			(pinfunction "V_{CC}")
			(pintype "power_in")
		)
		(pad "6" smd roundrect
			(at 1.1 -0.65)
			(size 0.85 0.35)
			(layers "F.Cu" "F.Mask" "F.Paste")
			(roundrect_rratio 0.25)
			(net 1287 "/SoM_Power/MODULE_POWER_ON")
			(pinfunction "1Y")
			(pintype "open_collector")
		)
	)
	(footprint "antmicro-footprints:R_0402_1005Metric"
		(layer "F.Cu")
		(at 212.1 133.1 180)
		(descr "Resistor SMD 0402")
		(tags "resistor SMD 0402")
		(property "Reference" "R85"
			(at 2.9 0.4 0)
			(layer "F.SilkS")
			(effects
				(font
					(size 0.7 0.7)
					(thickness 0.15)
				)
				(justify right top)
			)
		)
		(property "Value" "R_12k_0402"
			(at -1.011843 1.772047 0)
			(layer "F.Fab")
			(effects
				(font
					(size 0.7 0.7)
					(thickness 0.15)
				)
				(justify right top)
			)
		)
		(property "Datasheet" "https://www.bourns.com/docs/product-datasheets/cr.pdf"
			(at 0 0 0)
			(layer "F.Fab")
			(hide yes)
			(effects
				(font
					(size 1.27 1.27)
					(thickness 0.15)
				)
			)
		)
		(property "Description" "SMD Chip Resistor, 12 kohm, ± 1%, 62.5 mW, 0402 [1005 Metric], Thick Film, General Purpose"
			(at 0 0 0)
			(layer "F.Fab")
			(hide yes)
			(effects
				(font
					(size 1.27 1.27)
					(thickness 0.15)
				)
			)
		)
		(property "MPN" "CR0402-FX-1202GLF"
			(at 0 0 180)
			(unlocked yes)
			(layer "F.Fab")
			(hide yes)
			(effects
				(font
					(size 1 1)
					(thickness 0.15)
				)
			)
		)
		(property "Manufacturer" "Bourns"
			(at 0 0 180)
			(unlocked yes)
			(layer "F.Fab")
			(hide yes)
			(effects
				(font
					(size 1 1)
					(thickness 0.15)
				)
			)
		)
		(property "License" "Apache-2.0"
			(at 0 0 180)
			(unlocked yes)
			(layer "F.Fab")
			(hide yes)
			(effects
				(font
					(size 1 1)
					(thickness 0.15)
				)
			)
		)
		(property "Author" "Antmicro"
			(at 0 0 180)
			(unlocked yes)
			(layer "F.Fab")
			(hide yes)
			(effects
				(font
					(size 1 1)
					(thickness 0.15)
				)
			)
		)
		(property "Val" "12k"
			(at 0 0 180)
			(unlocked yes)
			(layer "F.Fab")
			(hide yes)
			(effects
				(font
					(size 1 1)
					(thickness 0.15)
				)
			)
		)
		(property "Tolerance" "1%"
			(at 0 0 180)
			(unlocked yes)
			(layer "F.Fab")
			(hide yes)
			(effects
				(font
					(size 1 1)
					(thickness 0.15)
				)
			)
		)
		(sheetname "/USB Hub/")
		(sheetfile "usb_hub.kicad_sch")
		(attr smd)
		(fp_rect
			(start -0.925 -0.47)
			(end 0.925 0.47)
			(stroke
				(width 0.05)
				(type default)
			)
			(fill no)
			(layer "F.CrtYd")
		)
		(fp_rect
			(start -0.5 -0.25)
			(end 0.5 0.25)
			(stroke
				(width 0.15)
				(type solid)
			)
			(fill no)
			(layer "F.Fab")
		)
		(fp_text user "${REFERENCE}"
			(at -0.95 3.168 0)
			(layer "F.Fab")
			(effects
				(font
					(size 0.7 0.7)
					(thickness 0.15)
				)
				(justify right top)
			)
		)
		(fp_text user "Author: Antmicro"
			(at -0.95 4.169 0)
			(layer "F.Fab")
			(effects
				(font
					(size 0.7 0.7)
					(thickness 0.15)
				)
				(justify right top)
			)
		)
		(fp_text user "License: Apache-2.0"
			(at -0.95 5.169 0)
			(layer "F.Fab")
			(effects
				(font
					(size 0.7 0.7)
					(thickness 0.15)
				)
				(justify right top)
			)
		)
		(pad "1" smd roundrect
			(at -0.48 0 180)
			(size 0.59 0.64)
			(layers "F.Cu" "F.Mask" "F.Paste")
			(roundrect_rratio 0.25)
			(net 1 "GND")
			(pintype "passive")
		)
		(pad "2" smd roundrect
			(at 0.48 0 180)
			(size 0.59 0.64)
			(layers "F.Cu" "F.Mask" "F.Paste")
			(roundrect_rratio 0.25)
			(net 919 "Net-(U21-RBIAS)")
			(pintype "passive")
		)
	)
	(footprint "antmicro-footprints:C_0402_1005Metric"
		(layer "F.Cu")
		(at 162.249468 79.51)
		(descr "Capacitor SMD 0402")
		(tags "capacitor SMD 0402")
		(property "Reference" "C386"
			(at -5.549468 0.49 0)
			(layer "F.SilkS")
			(effects
				(font
					(size 0.7 0.7)
					(thickness 0.15)
				)
				(justify left bottom)
			)
		)
		(property "Value" "C_100n_0402"
			(at -1.022927 2.155213 0)
			(layer "F.Fab")
			(effects
				(font
					(size 0.7 0.7)
					(thickness 0.15)
				)
				(justify left bottom)
			)
		)
		(property "Datasheet" "https://www.murata.com/products/productdetail?partno=GRM155R61H104KE14%23"
			(at 0 0 0)
			(layer "F.Fab")
			(hide yes)
			(effects
				(font
					(size 1.27 1.27)
					(thickness 0.15)
				)
			)
		)
		(property "Description" "SMD Multilayer Ceramic Capacitor, 0.1 µF, 50 V, 0402 [1005 Metric], ± 10%, X5R, GRM Series"
			(at 0 0 0)
			(layer "F.Fab")
			(hide yes)
			(effects
				(font
					(size 1.27 1.27)
					(thickness 0.15)
				)
			)
		)
		(property "Manufacturer" "Murata"
			(at 0 0 0)
			(unlocked yes)
			(layer "F.Fab")
			(hide yes)
			(effects
				(font
					(size 1 1)
					(thickness 0.15)
				)
			)
		)
		(property "MPN" "GRM155R61H104KE14D"
			(at 0 0 0)
			(unlocked yes)
			(layer "F.Fab")
			(hide yes)
			(effects
				(font
					(size 1 1)
					(thickness 0.15)
				)
			)
		)
		(property "Val" "100n"
			(at 0 0 0)
			(unlocked yes)
			(layer "F.Fab")
			(hide yes)
			(effects
				(font
					(size 1 1)
					(thickness 0.15)
				)
			)
		)
		(property "License" "Apache-2.0"
			(at 0 0 0)
			(unlocked yes)
			(layer "F.Fab")
			(hide yes)
			(effects
				(font
					(size 1 1)
					(thickness 0.15)
				)
			)
		)
		(property "Author" "Antmicro"
			(at 0 0 0)
			(unlocked yes)
			(layer "F.Fab")
			(hide yes)
			(effects
				(font
					(size 1 1)
					(thickness 0.15)
				)
			)
		)
		(property "Voltage" "50V"
			(at 0 0 0)
			(unlocked yes)
			(layer "F.Fab")
			(hide yes)
			(effects
				(font
					(size 1 1)
					(thickness 0.15)
				)
			)
		)
		(property "Dielectric" "X5R"
			(at 0 0 0)
			(unlocked yes)
			(layer "F.Fab")
			(hide yes)
			(effects
				(font
					(size 1 1)
					(thickness 0.15)
				)
			)
		)
		(component_classes
			(class "DCDC_20V")
		)
		(sheetname "/DCDC/")
		(sheetfile "dcdc.kicad_sch")
		(attr smd)
		(fp_rect
			(start -0.925 -0.47)
			(end 0.925 0.47)
			(stroke
				(width 0.05)
				(type default)
			)
			(fill no)
			(layer "F.CrtYd")
		)
		(fp_line
			(start -0.494 -0.25)
			(end 0.504 -0.25)
			(stroke
				(width 0.15)
				(type solid)
			)
			(layer "F.Fab")
		)
		(fp_line
			(start -0.494 0.248)
			(end -0.494 -0.25)
			(stroke
				(width 0.15)
				(type solid)
			)
			(layer "F.Fab")
		)
		(fp_line
			(start 0.504 -0.25)
			(end 0.504 0.248)
			(stroke
				(width 0.15)
				(type solid)
			)
			(layer "F.Fab")
		)
		(fp_line
			(start 0.504 0.248)
			(end -0.494 0.248)
			(stroke
				(width 0.15)
				(type solid)
			)
			(layer "F.Fab")
		)
		(fp_text user "License: Apache-2.0"
			(at -0.939 5.799 0)
			(layer "F.Fab")
			(effects
				(font
					(size 0.7 0.7)
					(thickness 0.15)
				)
				(justify left bottom)
			)
		)
		(fp_text user "Author: Antmicro"
			(at -0.939 3.399 0)
			(layer "F.Fab")
			(effects
				(font
					(size 0.7 0.7)
					(thickness 0.15)
				)
				(justify left bottom)
			)
		)
		(fp_text user "${REFERENCE}"
			(at -0.939 4.599 0)
			(layer "F.Fab")
			(effects
				(font
					(size 0.7 0.7)
					(thickness 0.15)
				)
				(justify left bottom)
			)
		)
		(pad "1" smd roundrect
			(at -0.48 0)
			(size 0.59 0.64)
			(layers "F.Cu" "F.Mask" "F.Paste")
			(roundrect_rratio 0.25)
			(net 1221 "Net-(U66-IN-)")
			(pintype "passive")
		)
		(pad "2" smd roundrect
			(at 0.48 0)
			(size 0.59 0.64)
			(layers "F.Cu" "F.Mask" "F.Paste")
			(roundrect_rratio 0.25)
			(net 1284 "Net-(U66-IN+)")
			(pintype "passive")
		)
	)
	(footprint "antmicro-footprints:R_0402_1005Metric"
		(layer "F.Cu")
		(at 201.7 135.7 180)
		(descr "Resistor SMD 0402")
		(tags "resistor SMD 0402")
		(property "Reference" "R66"
			(at 2.9 0.4 0)
			(layer "F.SilkS")
			(effects
				(font
					(size 0.7 0.7)
					(thickness 0.15)
				)
				(justify right top)
			)
		)
		(property "Value" "R_11k_0402"
			(at -1.011843 1.772046 0)
			(layer "F.Fab")
			(effects
				(font
					(size 0.7 0.7)
					(thickness 0.15)
				)
				(justify right top)
			)
		)
		(property "Datasheet" "https://www.bourns.com/docs/product-datasheets/cr.pdf"
			(at 0 0 0)
			(layer "F.Fab")
			(hide yes)
			(effects
				(font
					(size 1.27 1.27)
					(thickness 0.15)
				)
			)
		)
		(property "Description" "SMD Chip Resistor, 11 kohm, ± 1%, 62.5 mW, 0402 [1005 Metric], Thick Film, General Purpose"
			(at 0 0 0)
			(layer "F.Fab")
			(hide yes)
			(effects
				(font
					(size 1.27 1.27)
					(thickness 0.15)
				)
			)
		)
		(property "MPN" "CR0402-FX-1102GLF"
			(at 0 0 180)
			(unlocked yes)
			(layer "F.Fab")
			(hide yes)
			(effects
				(font
					(size 1 1)
					(thickness 0.15)
				)
			)
		)
		(property "Manufacturer" "Bourns"
			(at 0 0 180)
			(unlocked yes)
			(layer "F.Fab")
			(hide yes)
			(effects
				(font
					(size 1 1)
					(thickness 0.15)
				)
			)
		)
		(property "License" "Apache-2.0"
			(at 0 0 180)
			(unlocked yes)
			(layer "F.Fab")
			(hide yes)
			(effects
				(font
					(size 1 1)
					(thickness 0.15)
				)
			)
		)
		(property "Author" "Antmicro"
			(at 0 0 180)
			(unlocked yes)
			(layer "F.Fab")
			(hide yes)
			(effects
				(font
					(size 1 1)
					(thickness 0.15)
				)
			)
		)
		(property "Val" "11k"
			(at 0 0 180)
			(unlocked yes)
			(layer "F.Fab")
			(hide yes)
			(effects
				(font
					(size 1 1)
					(thickness 0.15)
				)
			)
		)
		(property "Tolerance" "1%"
			(at 0 0 180)
			(unlocked yes)
			(layer "F.Fab")
			(hide yes)
			(effects
				(font
					(size 1 1)
					(thickness 0.15)
				)
			)
		)
		(sheetname "/USB Hub/")
		(sheetfile "usb_hub.kicad_sch")
		(attr smd)
		(fp_poly
			(pts
				(xy -0.925 -0.47) (xy -0.925 0.47) (xy 0.925 0.47) (xy 0.925 -0.47)
			)
			(stroke
				(width 0.05)
				(type default)
			)
			(fill no)
			(layer "F.CrtYd")
		)
		(fp_poly
			(pts
				(xy -0.5 -0.25) (xy -0.5 0.25) (xy 0.5 0.25) (xy 0.5 -0.25)
			)
			(stroke
				(width 0.15)
				(type solid)
			)
			(fill no)
			(layer "F.Fab")
		)
		(fp_text user "${REFERENCE}"
			(at -0.95 3.168 0)
			(layer "F.Fab")
			(effects
				(font
					(size 0.7 0.7)
					(thickness 0.15)
				)
				(justify right top)
			)
		)
		(fp_text user "Author: Antmicro"
			(at -0.95 4.169 0)
			(layer "F.Fab")
			(effects
				(font
					(size 0.7 0.7)
					(thickness 0.15)
				)
				(justify right top)
			)
		)
		(fp_text user "License: Apache-2.0"
			(at -0.949999 5.169 0)
			(layer "F.Fab")
			(effects
				(font
					(size 0.7 0.7)
					(thickness 0.15)
				)
				(justify right top)
			)
		)
		(pad "1" smd roundrect
			(at -0.48 0 180)
			(size 0.59 0.64)
			(layers "F.Cu" "F.Mask" "F.Paste")
			(roundrect_rratio 0.25)
			(net 1164 "/USB Hub/VBUS_MON_UP")
			(pintype "passive")
		)
		(pad "2" smd roundrect
			(at 0.48 0 180)
			(size 0.59 0.64)
			(layers "F.Cu" "F.Mask" "F.Paste")
			(roundrect_rratio 0.25)
			(net 2 "+3V3")
			(pintype "passive")
		)
	)
	(footprint "antmicro-footprints:R_0402_1005Metric"
		(layer "F.Cu")
		(at 132.85 56.27 90)
		(descr "Resistor SMD 0402")
		(tags "resistor SMD 0402")
		(property "Reference" "R251"
			(at -2.46 11.53 90)
			(layer "F.SilkS")
			(effects
				(font
					(size 0.7 0.7)
					(thickness 0.15)
				)
				(justify left bottom)
			)
		)
		(property "Value" "R_2k37_0402"
			(at -1.011843 1.772047 90)
			(layer "F.Fab")
			(effects
				(font
					(size 0.7 0.7)
					(thickness 0.15)
				)
				(justify left bottom)
			)
		)
		(property "Datasheet" "https://www.bourns.com/docs/product-datasheets/cr.pdf"
			(at 0 0 90)
			(layer "F.Fab")
			(hide yes)
			(effects
				(font
					(size 1.27 1.27)
					(thickness 0.15)
				)
			)
		)
		(property "Description" "SMD Chip Resistor"
			(at 0 0 90)
			(layer "F.Fab")
			(hide yes)
			(effects
				(font
					(size 1.27 1.27)
					(thickness 0.15)
				)
			)
		)
		(property "Manufacturer" "Bourns"
			(at 0 0 90)
			(unlocked yes)
			(layer "F.Fab")
			(hide yes)
			(effects
				(font
					(size 1 1)
					(thickness 0.15)
				)
			)
		)
		(property "MPN" "CR0402-FX-2371GLF"
			(at 0 0 90)
			(unlocked yes)
			(layer "F.Fab")
			(hide yes)
			(effects
				(font
					(size 1 1)
					(thickness 0.15)
				)
			)
		)
		(property "Val" "2k37"
			(at 0 0 90)
			(unlocked yes)
			(layer "F.Fab")
			(hide yes)
			(effects
				(font
					(size 1 1)
					(thickness 0.15)
				)
			)
		)
		(property "License" "Apache-2.0"
			(at 0 0 90)
			(unlocked yes)
			(layer "F.Fab")
			(hide yes)
			(effects
				(font
					(size 1 1)
					(thickness 0.15)
				)
			)
		)
		(property "Author" "Antmicro"
			(at 0 0 90)
			(unlocked yes)
			(layer "F.Fab")
			(hide yes)
			(effects
				(font
					(size 1 1)
					(thickness 0.15)
				)
			)
		)
		(property "Tolerance" "1%"
			(at 0 0 90)
			(unlocked yes)
			(layer "F.Fab")
			(hide yes)
			(effects
				(font
					(size 1 1)
					(thickness 0.15)
				)
			)
		)
		(sheetname "/DCDC/")
		(sheetfile "dcdc.kicad_sch")
		(attr smd)
		(fp_rect
			(start -0.925 -0.47)
			(end 0.925 0.47)
			(stroke
				(width 0.05)
				(type default)
			)
			(fill no)
			(layer "F.CrtYd")
		)
		(fp_rect
			(start -0.5 -0.25)
			(end 0.5 0.25)
			(stroke
				(width 0.15)
				(type solid)
			)
			(fill no)
			(layer "F.Fab")
		)
		(fp_text user "License: Apache-2.0"
			(at -0.95 5.169 90)
			(layer "F.Fab")
			(effects
				(font
					(size 0.7 0.7)
					(thickness 0.15)
				)
				(justify left bottom)
			)
		)
		(fp_text user "Author: Antmicro"
			(at -0.95 4.169 90)
			(layer "F.Fab")
			(effects
				(font
					(size 0.7 0.7)
					(thickness 0.15)
				)
				(justify left bottom)
			)
		)
		(fp_text user "${REFERENCE}"
			(at -0.95 3.168 90)
			(layer "F.Fab")
			(effects
				(font
					(size 0.7 0.7)
					(thickness 0.15)
				)
				(justify left bottom)
			)
		)
		(pad "1" smd roundrect
			(at -0.48 0 90)
			(size 0.59 0.64)
			(layers "F.Cu" "F.Mask" "F.Paste")
			(roundrect_rratio 0.25)
			(net 1 "GND")
			(pintype "passive")
		)
		(pad "2" smd roundrect
			(at 0.48 0 90)
			(size 0.59 0.64)
			(layers "F.Cu" "F.Mask" "F.Paste")
			(roundrect_rratio 0.25)
			(net 1305 "/DCDC/5V_{AON}_EN")
			(pintype "passive")
		)
	)
	(footprint "antmicro-footprints:C_0402_1005Metric"
		(layer "F.Cu")
		(at 206.75 91.470856 180)
		(descr "Capacitor SMD 0402")
		(tags "capacitor SMD 0402")
		(property "Reference" "C320"
			(at 3.65 -0.929144 180)
			(layer "F.SilkS")
			(effects
				(font
					(size 0.7 0.7)
					(thickness 0.15)
				)
				(justify left bottom)
			)
		)
		(property "Value" "C_100n_0402"
			(at -1.022927 2.155213 180)
			(layer "F.Fab")
			(effects
				(font
					(size 0.7 0.7)
					(thickness 0.15)
				)
				(justify left bottom)
			)
		)
		(property "Datasheet" "https://www.murata.com/products/productdetail?partno=GRM155R61H104KE14%23"
			(at 0 0 180)
			(layer "F.Fab")
			(hide yes)
			(effects
				(font
					(size 1.27 1.27)
					(thickness 0.15)
				)
			)
		)
		(property "Description" "SMD Multilayer Ceramic Capacitor, 0.1 µF, 50 V, 0402 [1005 Metric], ± 10%, X5R, GRM Series"
			(at 0 0 180)
			(layer "F.Fab")
			(hide yes)
			(effects
				(font
					(size 1.27 1.27)
					(thickness 0.15)
				)
			)
		)
		(property "Manufacturer" "Murata"
			(at 0 0 180)
			(unlocked yes)
			(layer "F.Fab")
			(hide yes)
			(effects
				(font
					(size 1 1)
					(thickness 0.15)
				)
			)
		)
		(property "MPN" "GRM155R61H104KE14D"
			(at 0 0 180)
			(unlocked yes)
			(layer "F.Fab")
			(hide yes)
			(effects
				(font
					(size 1 1)
					(thickness 0.15)
				)
			)
		)
		(property "Val" "100n"
			(at 0 0 180)
			(unlocked yes)
			(layer "F.Fab")
			(hide yes)
			(effects
				(font
					(size 1 1)
					(thickness 0.15)
				)
			)
		)
		(property "License" "Apache-2.0"
			(at 0 0 180)
			(unlocked yes)
			(layer "F.Fab")
			(hide yes)
			(effects
				(font
					(size 1 1)
					(thickness 0.15)
				)
			)
		)
		(property "Author" "Antmicro"
			(at 0 0 180)
			(unlocked yes)
			(layer "F.Fab")
			(hide yes)
			(effects
				(font
					(size 1 1)
					(thickness 0.15)
				)
			)
		)
		(property "Voltage" "50V"
			(at 0 0 180)
			(unlocked yes)
			(layer "F.Fab")
			(hide yes)
			(effects
				(font
					(size 1 1)
					(thickness 0.15)
				)
			)
		)
		(property "Dielectric" "X5R"
			(at 0 0 180)
			(unlocked yes)
			(layer "F.Fab")
			(hide yes)
			(effects
				(font
					(size 1 1)
					(thickness 0.15)
				)
			)
		)
		(sheetname "/SoM_IO2/")
		(sheetfile "som_io2.kicad_sch")
		(attr smd)
		(fp_rect
			(start -0.925 -0.47)
			(end 0.925 0.47)
			(stroke
				(width 0.05)
				(type default)
			)
			(fill no)
			(layer "F.CrtYd")
		)
		(fp_line
			(start 0.504 0.248)
			(end -0.494 0.248)
			(stroke
				(width 0.15)
				(type solid)
			)
			(layer "F.Fab")
		)
		(fp_line
			(start 0.504 -0.25)
			(end 0.504 0.248)
			(stroke
				(width 0.15)
				(type solid)
			)
			(layer "F.Fab")
		)
		(fp_line
			(start -0.494 0.248)
			(end -0.494 -0.25)
			(stroke
				(width 0.15)
				(type solid)
			)
			(layer "F.Fab")
		)
		(fp_line
			(start -0.494 -0.25)
			(end 0.504 -0.25)
			(stroke
				(width 0.15)
				(type solid)
			)
			(layer "F.Fab")
		)
		(fp_text user "Author: Antmicro"
			(at -0.939 3.399 180)
			(layer "F.Fab")
			(effects
				(font
					(size 0.7 0.7)
					(thickness 0.15)
				)
				(justify left bottom)
			)
		)
		(fp_text user "${REFERENCE}"
			(at -0.939 4.599 180)
			(layer "F.Fab")
			(effects
				(font
					(size 0.7 0.7)
					(thickness 0.15)
				)
				(justify left bottom)
			)
		)
		(fp_text user "License: Apache-2.0"
			(at -0.939 5.799 180)
			(layer "F.Fab")
			(effects
				(font
					(size 0.7 0.7)
					(thickness 0.15)
				)
				(justify left bottom)
			)
		)
		(pad "1" smd roundrect
			(at -0.48 0 180)
			(size 0.59 0.64)
			(layers "F.Cu" "F.Mask" "F.Paste")
			(roundrect_rratio 0.25)
			(net 557 "/SoM_IO2/DP0.TX3+")
			(pintype "passive")
		)
		(pad "2" smd roundrect
			(at 0.48 0 180)
			(size 0.59 0.64)
			(layers "F.Cu" "F.Mask" "F.Paste")
			(roundrect_rratio 0.25)
			(net 746 "/SoM_IO2/DP0.TX3_C+")
			(pintype "passive")
		)
	)
	(footprint "antmicro-footprints:C_0402_1005Metric"
		(layer "F.Cu")
		(at 105.39 57.179999 -90)
		(descr "Capacitor SMD 0402")
		(tags "capacitor SMD 0402")
		(property "Reference" "C382"
			(at 0.840001 0.53 90)
			(layer "F.SilkS")
			(effects
				(font
					(size 0.7 0.7)
					(thickness 0.15)
				)
				(justify right top)
			)
		)
		(property "Value" "C_100n_0402"
			(at -1.022927 2.155213 90)
			(layer "F.Fab")
			(effects
				(font
					(size 0.7 0.7)
					(thickness 0.15)
				)
				(justify right top)
			)
		)
		(property "Datasheet" "https://www.murata.com/products/productdetail?partno=GRM155R61H104KE14%23"
			(at 0 0 90)
			(layer "F.Fab")
			(hide yes)
			(effects
				(font
					(size 1.27 1.27)
					(thickness 0.15)
				)
			)
		)
		(property "Description" "SMD Multilayer Ceramic Capacitor, 0.1 µF, 50 V, 0402 [1005 Metric], ± 10%, X5R, GRM Series"
			(at 0 0 90)
			(layer "F.Fab")
			(hide yes)
			(effects
				(font
					(size 1.27 1.27)
					(thickness 0.15)
				)
			)
		)
		(property "Manufacturer" "Murata"
			(at 0 0 270)
			(unlocked yes)
			(layer "F.Fab")
			(hide yes)
			(effects
				(font
					(size 1 1)
					(thickness 0.15)
				)
			)
		)
		(property "MPN" "GRM155R61H104KE14D"
			(at 0 0 270)
			(unlocked yes)
			(layer "F.Fab")
			(hide yes)
			(effects
				(font
					(size 1 1)
					(thickness 0.15)
				)
			)
		)
		(property "Val" "100n"
			(at 0 0 270)
			(unlocked yes)
			(layer "F.Fab")
			(hide yes)
			(effects
				(font
					(size 1 1)
					(thickness 0.15)
				)
			)
		)
		(property "License" "Apache-2.0"
			(at 0 0 270)
			(unlocked yes)
			(layer "F.Fab")
			(hide yes)
			(effects
				(font
					(size 1 1)
					(thickness 0.15)
				)
			)
		)
		(property "Author" "Antmicro"
			(at 0 0 270)
			(unlocked yes)
			(layer "F.Fab")
			(hide yes)
			(effects
				(font
					(size 1 1)
					(thickness 0.15)
				)
			)
		)
		(property "Voltage" "50V"
			(at 0 0 270)
			(unlocked yes)
			(layer "F.Fab")
			(hide yes)
			(effects
				(font
					(size 1 1)
					(thickness 0.15)
				)
			)
		)
		(property "Dielectric" "X5R"
			(at 0 0 270)
			(unlocked yes)
			(layer "F.Fab")
			(hide yes)
			(effects
				(font
					(size 1 1)
					(thickness 0.15)
				)
			)
		)
		(sheetname "/DCDC/")
		(sheetfile "dcdc.kicad_sch")
		(attr smd)
		(fp_poly
			(pts
				(xy -0.925 -0.47) (xy 0.925 -0.47) (xy 0.925 0.47) (xy -0.925 0.47)
			)
			(stroke
				(width 0.05)
				(type default)
			)
			(fill no)
			(layer "F.CrtYd")
		)
		(fp_line
			(start -0.494 0.248)
			(end -0.494 -0.25)
			(stroke
				(width 0.15)
				(type solid)
			)
			(layer "F.Fab")
		)
		(fp_line
			(start 0.504 0.248)
			(end -0.494 0.248)
			(stroke
				(width 0.15)
				(type solid)
			)
			(layer "F.Fab")
		)
		(fp_line
			(start -0.494 -0.25)
			(end 0.504 -0.25)
			(stroke
				(width 0.15)
				(type solid)
			)
			(layer "F.Fab")
		)
		(fp_line
			(start 0.504 -0.25)
			(end 0.504 0.248)
			(stroke
				(width 0.15)
				(type solid)
			)
			(layer "F.Fab")
		)
		(fp_text user "License: Apache-2.0"
			(at -0.939 5.799 90)
			(layer "F.Fab")
			(effects
				(font
					(size 0.7 0.7)
					(thickness 0.15)
				)
				(justify right top)
			)
		)
		(fp_text user "Author: Antmicro"
			(at -0.939 3.399 90)
			(layer "F.Fab")
			(effects
				(font
					(size 0.7 0.7)
					(thickness 0.15)
				)
				(justify right top)
			)
		)
		(fp_text user "${REFERENCE}"
			(at -0.939 4.599 90)
			(layer "F.Fab")
			(effects
				(font
					(size 0.7 0.7)
					(thickness 0.15)
				)
				(justify right top)
			)
		)
		(pad "1" smd roundrect
			(at -0.48 0 270)
			(size 0.59 0.64)
			(layers "F.Cu" "F.Mask" "F.Paste")
			(roundrect_rratio 0.25)
			(net 1279 "Net-(U76-IN-)")
			(pintype "passive")
		)
		(pad "2" smd roundrect
			(at 0.48 0 270)
			(size 0.59 0.64)
			(layers "F.Cu" "F.Mask" "F.Paste")
			(roundrect_rratio 0.25)
			(net 1280 "Net-(U76-IN+)")
			(pintype "passive")
		)
	)
	(footprint "antmicro-footprints:SOT-523"
		(layer "F.Cu")
		(at 109.76 63.95 -90)
		(property "Reference" "Q6"
			(at 0.39 2.48 0)
			(layer "F.SilkS")
			(effects
				(font
					(size 0.7 0.7)
					(thickness 0.15)
				)
				(justify left bottom)
			)
		)
		(property "Value" "DMG1012T-7"
			(at 0.1 1.824 90)
			(layer "F.Fab")
			(effects
				(font
					(size 0.7 0.7)
					(thickness 0.15)
				)
				(justify right top)
			)
		)
		(property "Datasheet" "https://www.diodes.com/assets/Datasheets/ds31783.pdf"
			(at 0 0 90)
			(layer "F.Fab")
			(hide yes)
			(effects
				(font
					(size 1.27 1.27)
					(thickness 0.15)
				)
			)
		)
		(property "Description" "Power MOSFET, N Channel, 20 V, 630 mA, 0.3 ohm, SOT-523, Surface Mount"
			(at 0 0 90)
			(layer "F.Fab")
			(hide yes)
			(effects
				(font
					(size 1.27 1.27)
					(thickness 0.15)
				)
			)
		)
		(property "MPN" "DMG1012T-7"
			(at 0 0 270)
			(unlocked yes)
			(layer "F.Fab")
			(hide yes)
			(effects
				(font
					(size 1 1)
					(thickness 0.15)
				)
			)
		)
		(property "Manufacturer" "Diodes Incorporated"
			(at 0 0 270)
			(unlocked yes)
			(layer "F.Fab")
			(hide yes)
			(effects
				(font
					(size 1 1)
					(thickness 0.15)
				)
			)
		)
		(property "Author" "Antmicro"
			(at 0 0 270)
			(unlocked yes)
			(layer "F.Fab")
			(hide yes)
			(effects
				(font
					(size 1 1)
					(thickness 0.15)
				)
			)
		)
		(property "License" "Apache-2.0"
			(at 0 0 270)
			(unlocked yes)
			(layer "F.Fab")
			(hide yes)
			(effects
				(font
					(size 1 1)
					(thickness 0.15)
				)
			)
		)
		(sheetname "/SoM_Power/")
		(sheetfile "som_power.kicad_sch")
		(attr smd)
		(fp_line
			(start -0.927 -0.050999)
			(end -0.927 -0.350999)
			(stroke
				(width 0.15)
				(type solid)
			)
			(layer "F.SilkS")
		)
		(fp_line
			(start -0.927 -0.350999)
			(end -0.725 -0.551)
			(stroke
				(width 0.15)
				(type solid)
			)
			(layer "F.SilkS")
		)
		(fp_line
			(start -0.725 -0.551)
			(end -0.277 -0.551)
			(stroke
				(width 0.15)
				(type solid)
			)
			(layer "F.SilkS")
		)
		(fp_line
			(start -0.277 -0.551)
			(end -0.277 -0.750001)
			(stroke
				(width 0.15)
				(type solid)
			)
			(layer "F.SilkS")
		)
		(fp_circle
			(center -0.9652 0.9652)
			(end -0.915201 0.9652)
			(stroke
				(width 0.15)
				(type solid)
			)
			(fill yes)
			(layer "F.SilkS")
		)
		(fp_line
			(start -1.12 1.15)
			(end 1.1 1.15)
			(stroke
				(width 0.05)
				(type solid)
			)
			(layer "F.CrtYd")
		)
		(fp_line
			(start -1.12 -1.159999)
			(end -1.12 1.15)
			(stroke
				(width 0.05)
				(type solid)
			)
			(layer "F.CrtYd")
		)
		(fp_line
			(start -1.12 -1.159999)
			(end 1.1 -1.159999)
			(stroke
				(width 0.05)
				(type solid)
			)
			(layer "F.CrtYd")
		)
		(fp_line
			(start 1.1 -1.159999)
			(end 1.1 1.15)
			(stroke
				(width 0.05)
				(type solid)
			)
			(layer "F.CrtYd")
		)
		(fp_line
			(start 0.8 0.424)
			(end -0.802 0.424)
			(stroke
				(width 0.15)
				(type solid)
			)
			(layer "F.Fab")
		)
		(fp_line
			(start -0.802 -0.276)
			(end -0.802 0.424)
			(stroke
				(width 0.15)
				(type solid)
			)
			(layer "F.Fab")
		)
		(fp_line
			(start -0.652 -0.425)
			(end -0.802 -0.276)
			(stroke
				(width 0.15)
				(type solid)
			)
			(layer "F.Fab")
		)
		(fp_line
			(start 0.8 -0.425)
			(end 0.8 0.424)
			(stroke
				(width 0.15)
				(type solid)
			)
			(layer "F.Fab")
		)
		(fp_line
			(start 0.8 -0.425)
			(end -0.652 -0.425)
			(stroke
				(width 0.15)
				(type solid)
			)
			(layer "F.Fab")
		)
		(fp_circle
			(center -0.9652 0.9652)
			(end -0.9144 0.9652)
			(stroke
				(width 0.15)
				(type solid)
			)
			(fill no)
			(layer "F.Fab")
		)
		(fp_text user "${REFERENCE}"
			(at -1.12 3.824 90)
			(layer "F.Fab")
			(effects
				(font
					(size 0.7 0.7)
					(thickness 0.15)
				)
				(justify right top)
			)
		)
		(fp_text user "Author: Antmicro"
			(at -1.12 6.224 90)
			(layer "F.Fab")
			(effects
				(font
					(size 0.7 0.7)
					(thickness 0.15)
				)
				(justify right top)
			)
		)
		(fp_text user "License: Apache-2.0"
			(at -1.12 5.024 90)
			(layer "F.Fab")
			(effects
				(font
					(size 0.7 0.7)
					(thickness 0.15)
				)
				(justify right top)
			)
		)
		(pad "1" smd rect
			(at -0.5 0.65 270)
			(size 0.4 0.51)
			(layers "F.Cu" "F.Mask" "F.Paste")
			(net 1285 "/SoM_Power/VIN_PWR_ON")
			(pinfunction "G")
			(pintype "input")
		)
		(pad "2" smd rect
			(at 0.498 0.65 270)
			(size 0.4 0.51)
			(layers "F.Cu" "F.Mask" "F.Paste")
			(net 1 "GND")
			(pinfunction "S")
			(pintype "passive")
		)
		(pad "3" smd rect
			(at 0 -0.652001 270)
			(size 0.4 0.51)
			(layers "F.Cu" "F.Mask" "F.Paste")
			(net 1392 "Net-(Q6-D)")
			(pinfunction "D")
			(pintype "passive")
		)
	)
	(footprint "antmicro-footprints:C_0402_1005Metric"
		(layer "F.Cu")
		(at 218.795 118.9 180)
		(descr "Capacitor SMD 0402")
		(tags "capacitor SMD 0402")
		(property "Reference" "C101"
			(at -1.005 2.4 0)
			(layer "F.SilkS")
			(effects
				(font
					(size 0.7 0.7)
					(thickness 0.15)
				)
				(justify right top)
			)
		)
		(property "Value" "C_100n_0402"
			(at -1.022927 2.155213 0)
			(layer "F.Fab")
			(effects
				(font
					(size 0.7 0.7)
					(thickness 0.15)
				)
				(justify right top)
			)
		)
		(property "Datasheet" "https://www.murata.com/products/productdetail?partno=GRM155R61H104KE14%23"
			(at 0 0 0)
			(layer "F.Fab")
			(hide yes)
			(effects
				(font
					(size 1.27 1.27)
					(thickness 0.15)
				)
			)
		)
		(property "Description" "SMD Multilayer Ceramic Capacitor, 0.1 µF, 50 V, 0402 [1005 Metric], ± 10%, X5R, GRM Series"
			(at 0 0 0)
			(layer "F.Fab")
			(hide yes)
			(effects
				(font
					(size 1.27 1.27)
					(thickness 0.15)
				)
			)
		)
		(property "Manufacturer" "Murata"
			(at 0 0 180)
			(unlocked yes)
			(layer "F.Fab")
			(hide yes)
			(effects
				(font
					(size 1 1)
					(thickness 0.15)
				)
			)
		)
		(property "MPN" "GRM155R61H104KE14D"
			(at 0 0 180)
			(unlocked yes)
			(layer "F.Fab")
			(hide yes)
			(effects
				(font
					(size 1 1)
					(thickness 0.15)
				)
			)
		)
		(property "Val" "100n"
			(at 0 0 180)
			(unlocked yes)
			(layer "F.Fab")
			(hide yes)
			(effects
				(font
					(size 1 1)
					(thickness 0.15)
				)
			)
		)
		(property "License" "Apache-2.0"
			(at 0 0 180)
			(unlocked yes)
			(layer "F.Fab")
			(hide yes)
			(effects
				(font
					(size 1 1)
					(thickness 0.15)
				)
			)
		)
		(property "Author" "Antmicro"
			(at 0 0 180)
			(unlocked yes)
			(layer "F.Fab")
			(hide yes)
			(effects
				(font
					(size 1 1)
					(thickness 0.15)
				)
			)
		)
		(property "Voltage" "50V"
			(at 0 0 180)
			(unlocked yes)
			(layer "F.Fab")
			(hide yes)
			(effects
				(font
					(size 1 1)
					(thickness 0.15)
				)
			)
		)
		(property "Dielectric" "X5R"
			(at 0 0 180)
			(unlocked yes)
			(layer "F.Fab")
			(hide yes)
			(effects
				(font
					(size 1 1)
					(thickness 0.15)
				)
			)
		)
		(sheetname "/USB Hub/")
		(sheetfile "usb_hub.kicad_sch")
		(attr smd)
		(fp_rect
			(start -0.925 -0.47)
			(end 0.925 0.47)
			(stroke
				(width 0.05)
				(type default)
			)
			(fill no)
			(layer "F.CrtYd")
		)
		(fp_line
			(start 0.504 0.248)
			(end -0.494 0.248)
			(stroke
				(width 0.15)
				(type solid)
			)
			(layer "F.Fab")
		)
		(fp_line
			(start 0.504 -0.25)
			(end 0.504 0.248)
			(stroke
				(width 0.15)
				(type solid)
			)
			(layer "F.Fab")
		)
		(fp_line
			(start -0.494 0.248)
			(end -0.494 -0.25)
			(stroke
				(width 0.15)
				(type solid)
			)
			(layer "F.Fab")
		)
		(fp_line
			(start -0.494 -0.25)
			(end 0.504 -0.25)
			(stroke
				(width 0.15)
				(type solid)
			)
			(layer "F.Fab")
		)
		(fp_text user "Author: Antmicro"
			(at -0.939 3.399 0)
			(layer "F.Fab")
			(effects
				(font
					(size 0.7 0.7)
					(thickness 0.15)
				)
				(justify right top)
			)
		)
		(fp_text user "${REFERENCE}"
			(at -0.939 4.599 0)
			(layer "F.Fab")
			(effects
				(font
					(size 0.7 0.7)
					(thickness 0.15)
				)
				(justify right top)
			)
		)
		(fp_text user "License: Apache-2.0"
			(at -0.939 5.799 0)
			(layer "F.Fab")
			(effects
				(font
					(size 0.7 0.7)
					(thickness 0.15)
				)
				(justify right top)
			)
		)
		(pad "1" smd roundrect
			(at -0.48 0 180)
			(size 0.59 0.64)
			(layers "F.Cu" "F.Mask" "F.Paste")
			(roundrect_rratio 0.25)
			(net 95 "/USB Hub/USBC3_CONN_TX1_N")
			(pintype "passive")
		)
		(pad "2" smd roundrect
			(at 0.48 0 180)
			(size 0.59 0.64)
			(layers "F.Cu" "F.Mask" "F.Paste")
			(roundrect_rratio 0.25)
			(net 45 "/USB Hub/USBC3_TX_{1}+")
			(pintype "passive")
		)
	)
	(footprint "antmicro-footprints:R_0402_1005Metric"
		(layer "F.Cu")
		(at 187.25 59.25 90)
		(descr "Resistor SMD 0402")
		(tags "resistor SMD 0402")
		(property "Reference" "R238"
			(at -2.15 -0.55 90)
			(layer "F.SilkS")
			(effects
				(font
					(size 0.7 0.7)
					(thickness 0.15)
				)
				(justify left bottom)
			)
		)
		(property "Value" "R_10k_0402"
			(at -1.011843 1.772046 90)
			(layer "F.Fab")
			(effects
				(font
					(size 0.7 0.7)
					(thickness 0.15)
				)
				(justify left bottom)
			)
		)
		(property "Datasheet" "https://www.bourns.com/docs/product-datasheets/cr.pdf"
			(at 0 0 90)
			(layer "F.Fab")
			(hide yes)
			(effects
				(font
					(size 1.27 1.27)
					(thickness 0.15)
				)
			)
		)
		(property "Description" "SMD Chip Resistor, 10 kohm, ± 1%, 62.5 mW, 0402 [1005 Metric], Thick Film, General Purpose"
			(at 0 0 90)
			(layer "F.Fab")
			(hide yes)
			(effects
				(font
					(size 1.27 1.27)
					(thickness 0.15)
				)
			)
		)
		(property "Manufacturer" "Bourns"
			(at 0 0 90)
			(unlocked yes)
			(layer "F.Fab")
			(hide yes)
			(effects
				(font
					(size 1 1)
					(thickness 0.15)
				)
			)
		)
		(property "MPN" "CR0402-FX-1002GLF"
			(at 0 0 90)
			(unlocked yes)
			(layer "F.Fab")
			(hide yes)
			(effects
				(font
					(size 1 1)
					(thickness 0.15)
				)
			)
		)
		(property "Val" "10k"
			(at 0 0 90)
			(unlocked yes)
			(layer "F.Fab")
			(hide yes)
			(effects
				(font
					(size 1 1)
					(thickness 0.15)
				)
			)
		)
		(property "License" "Apache-2.0"
			(at 0 0 90)
			(unlocked yes)
			(layer "F.Fab")
			(hide yes)
			(effects
				(font
					(size 1 1)
					(thickness 0.15)
				)
			)
		)
		(property "Author" "Antmicro"
			(at 0 0 90)
			(unlocked yes)
			(layer "F.Fab")
			(hide yes)
			(effects
				(font
					(size 1 1)
					(thickness 0.15)
				)
			)
		)
		(property "Tolerance" "1%"
			(at 0 0 90)
			(unlocked yes)
			(layer "F.Fab")
			(hide yes)
			(effects
				(font
					(size 1 1)
					(thickness 0.15)
				)
			)
		)
		(sheetname "/Peripherals/")
		(sheetfile "peripherals.kicad_sch")
		(attr smd)
		(fp_poly
			(pts
				(xy -0.925 -0.47) (xy 0.925 -0.47) (xy 0.925 0.47) (xy -0.925 0.47)
			)
			(stroke
				(width 0.05)
				(type default)
			)
			(fill no)
			(layer "F.CrtYd")
		)
		(fp_poly
			(pts
				(xy -0.5 -0.25) (xy 0.5 -0.25) (xy 0.5 0.25) (xy -0.5 0.25)
			)
			(stroke
				(width 0.15)
				(type solid)
			)
			(fill no)
			(layer "F.Fab")
		)
		(fp_text user "${REFERENCE}"
			(at -0.95 3.168 90)
			(layer "F.Fab")
			(effects
				(font
					(size 0.7 0.7)
					(thickness 0.15)
				)
				(justify left bottom)
			)
		)
		(fp_text user "License: Apache-2.0"
			(at -0.949999 5.169 90)
			(layer "F.Fab")
			(effects
				(font
					(size 0.7 0.7)
					(thickness 0.15)
				)
				(justify left bottom)
			)
		)
		(fp_text user "Author: Antmicro"
			(at -0.95 4.169 90)
			(layer "F.Fab")
			(effects
				(font
					(size 0.7 0.7)
					(thickness 0.15)
				)
				(justify left bottom)
			)
		)
		(pad "1" smd roundrect
			(at -0.48 0 90)
			(size 0.59 0.64)
			(layers "F.Cu" "F.Mask" "F.Paste")
			(roundrect_rratio 0.25)
			(net 356 "/Expansion connector/GPIO.USER_BTN1")
			(pintype "passive")
		)
		(pad "2" smd roundrect
			(at 0.48 0 90)
			(size 0.59 0.64)
			(layers "F.Cu" "F.Mask" "F.Paste")
			(roundrect_rratio 0.25)
			(net 11 "+1V8")
			(pintype "passive")
		)
	)
	(footprint "antmicro-footprints:R_0402_1005Metric"
		(layer "F.Cu")
		(at 62.12 85.93 -90)
		(descr "Resistor SMD 0402")
		(tags "resistor SMD 0402")
		(property "Reference" "R173"
			(at -3.73 0.42 90)
			(layer "F.SilkS")
			(effects
				(font
					(size 0.7 0.7)
					(thickness 0.15)
				)
				(justify right top)
			)
		)
		(property "Value" "R_4k7_0402"
			(at -1.011843 1.772047 90)
			(layer "F.Fab")
			(effects
				(font
					(size 0.7 0.7)
					(thickness 0.15)
				)
				(justify right top)
			)
		)
		(property "Datasheet" "https://www.bourns.com/docs/product-datasheets/cr.pdf"
			(at 0 0 90)
			(layer "F.Fab")
			(hide yes)
			(effects
				(font
					(size 1.27 1.27)
					(thickness 0.15)
				)
			)
		)
		(property "Description" "SMD Chip Resistor, 4.7 kohm, ± 1%, 62.5 mW, 0402 [1005 Metric], Thick Film, General Purpose"
			(at 0 0 90)
			(layer "F.Fab")
			(hide yes)
			(effects
				(font
					(size 1.27 1.27)
					(thickness 0.15)
				)
			)
		)
		(property "Manufacturer" "Bourns"
			(at 0 0 270)
			(unlocked yes)
			(layer "F.Fab")
			(hide yes)
			(effects
				(font
					(size 1 1)
					(thickness 0.15)
				)
			)
		)
		(property "MPN" "CR0402-FX-4701GLF"
			(at 0 0 270)
			(unlocked yes)
			(layer "F.Fab")
			(hide yes)
			(effects
				(font
					(size 1 1)
					(thickness 0.15)
				)
			)
		)
		(property "Val" "4k7"
			(at 0 0 270)
			(unlocked yes)
			(layer "F.Fab")
			(hide yes)
			(effects
				(font
					(size 1 1)
					(thickness 0.15)
				)
			)
		)
		(property "License" "Apache-2.0"
			(at 0 0 270)
			(unlocked yes)
			(layer "F.Fab")
			(hide yes)
			(effects
				(font
					(size 1 1)
					(thickness 0.15)
				)
			)
		)
		(property "Author" "Antmicro"
			(at 0 0 270)
			(unlocked yes)
			(layer "F.Fab")
			(hide yes)
			(effects
				(font
					(size 1 1)
					(thickness 0.15)
				)
			)
		)
		(property "Tolerance" "1%"
			(at 0 0 270)
			(unlocked yes)
			(layer "F.Fab")
			(hide yes)
			(effects
				(font
					(size 1 1)
					(thickness 0.15)
				)
			)
		)
		(sheetname "/CSI/")
		(sheetfile "csi.kicad_sch")
		(attr smd)
		(fp_rect
			(start -0.925 -0.47)
			(end 0.925 0.47)
			(stroke
				(width 0.05)
				(type default)
			)
			(fill no)
			(layer "F.CrtYd")
		)
		(fp_rect
			(start -0.5 -0.25)
			(end 0.5 0.25)
			(stroke
				(width 0.15)
				(type solid)
			)
			(fill no)
			(layer "F.Fab")
		)
		(fp_text user "Author: Antmicro"
			(at -0.95 4.169 90)
			(layer "F.Fab")
			(effects
				(font
					(size 0.7 0.7)
					(thickness 0.15)
				)
				(justify right top)
			)
		)
		(fp_text user "License: Apache-2.0"
			(at -0.95 5.169 90)
			(layer "F.Fab")
			(effects
				(font
					(size 0.7 0.7)
					(thickness 0.15)
				)
				(justify right top)
			)
		)
		(fp_text user "${REFERENCE}"
			(at -0.95 3.168 90)
			(layer "F.Fab")
			(effects
				(font
					(size 0.7 0.7)
					(thickness 0.15)
				)
				(justify right top)
			)
		)
		(pad "1" smd roundrect
			(at -0.48 0 270)
			(size 0.59 0.64)
			(layers "F.Cu" "F.Mask" "F.Paste")
			(roundrect_rratio 0.25)
			(net 1 "GND")
			(pintype "passive")
		)
		(pad "2" smd roundrect
			(at 0.48 0 270)
			(size 0.59 0.64)
			(layers "F.Cu" "F.Mask" "F.Paste")
			(roundrect_rratio 0.25)
			(net 996 "/CSI/CSIA_3V3_ISET")
			(pintype "passive")
		)
	)
	(footprint "antmicro-footprints:R_0402_1005Metric"
		(layer "F.Cu")
		(at 94 64.5 180)
		(descr "Resistor SMD 0402")
		(tags "resistor SMD 0402")
		(property "Reference" "R296"
			(at -9.75 -0.5 0)
			(layer "F.SilkS")
			(effects
				(font
					(size 0.7 0.7)
					(thickness 0.15)
				)
				(justify right top)
			)
		)
		(property "Value" "R_49k9_0402"
			(at -1.011843 1.772046 0)
			(layer "F.Fab")
			(effects
				(font
					(size 0.7 0.7)
					(thickness 0.15)
				)
				(justify right top)
			)
		)
		(property "Datasheet" "https://www.bourns.com/docs/product-datasheets/cr.pdf"
			(at 0 0 0)
			(layer "F.Fab")
			(hide yes)
			(effects
				(font
					(size 1.27 1.27)
					(thickness 0.15)
				)
			)
		)
		(property "Description" "SMD Chip Resistor, 49.9 kohm, ± 1%, 63 mW, 0402 [1005 Metric], Thick Film, General Purpose"
			(at 0 0 0)
			(layer "F.Fab")
			(hide yes)
			(effects
				(font
					(size 1.27 1.27)
					(thickness 0.15)
				)
			)
		)
		(property "MPN" "CR0402-FX-4992GLF"
			(at 0 0 180)
			(unlocked yes)
			(layer "F.Fab")
			(hide yes)
			(effects
				(font
					(size 1 1)
					(thickness 0.15)
				)
			)
		)
		(property "Manufacturer" "Bourns"
			(at 0 0 180)
			(unlocked yes)
			(layer "F.Fab")
			(hide yes)
			(effects
				(font
					(size 1 1)
					(thickness 0.15)
				)
			)
		)
		(property "License" "Apache-2.0"
			(at 0 0 180)
			(unlocked yes)
			(layer "F.Fab")
			(hide yes)
			(effects
				(font
					(size 1 1)
					(thickness 0.15)
				)
			)
		)
		(property "Author" "Antmicro"
			(at 0 0 180)
			(unlocked yes)
			(layer "F.Fab")
			(hide yes)
			(effects
				(font
					(size 1 1)
					(thickness 0.15)
				)
			)
		)
		(property "Val" "49k9"
			(at 0 0 180)
			(unlocked yes)
			(layer "F.Fab")
			(hide yes)
			(effects
				(font
					(size 1 1)
					(thickness 0.15)
				)
			)
		)
		(property "Tolerance" "1%"
			(at 0 0 180)
			(unlocked yes)
			(layer "F.Fab")
			(hide yes)
			(effects
				(font
					(size 1 1)
					(thickness 0.15)
				)
			)
		)
		(property "Current" "1A"
			(at 0 0 180)
			(unlocked yes)
			(layer "F.Fab")
			(hide yes)
			(effects
				(font
					(size 1 1)
					(thickness 0.15)
				)
			)
		)
		(sheetname "/SoM_Power/")
		(sheetfile "som_power.kicad_sch")
		(attr smd)
		(fp_poly
			(pts
				(xy -0.925 -0.47) (xy -0.925 0.47) (xy 0.925 0.47) (xy 0.925 -0.47)
			)
			(stroke
				(width 0.05)
				(type default)
			)
			(fill no)
			(layer "F.CrtYd")
		)
		(fp_poly
			(pts
				(xy -0.5 -0.25) (xy -0.5 0.25) (xy 0.5 0.25) (xy 0.5 -0.25)
			)
			(stroke
				(width 0.15)
				(type solid)
			)
			(fill no)
			(layer "F.Fab")
		)
		(fp_text user "Author: Antmicro"
			(at -0.95 4.169 0)
			(layer "F.Fab")
			(effects
				(font
					(size 0.7 0.7)
					(thickness 0.15)
				)
				(justify right top)
			)
		)
		(fp_text user "License: Apache-2.0"
			(at -0.949999 5.169 0)
			(layer "F.Fab")
			(effects
				(font
					(size 0.7 0.7)
					(thickness 0.15)
				)
				(justify right top)
			)
		)
		(fp_text user "${REFERENCE}"
			(at -0.95 3.168 0)
			(layer "F.Fab")
			(effects
				(font
					(size 0.7 0.7)
					(thickness 0.15)
				)
				(justify right top)
			)
		)
		(pad "1" smd roundrect
			(at -0.48 0 180)
			(size 0.59 0.64)
			(layers "F.Cu" "F.Mask" "F.Paste")
			(roundrect_rratio 0.25)
			(net 1285 "/SoM_Power/VIN_PWR_ON")
			(pintype "passive")
		)
		(pad "2" smd roundrect
			(at 0.48 0 180)
			(size 0.59 0.64)
			(layers "F.Cu" "F.Mask" "F.Paste")
			(roundrect_rratio 0.25)
			(net 4 "+3V3_AON")
			(pintype "passive")
		)
	)
	(footprint "antmicro-footprints:SOD-523"
		(layer "F.Cu")
		(at 186.22 123.499)
		(property "Reference" "D15"
			(at -1.42 1.54 0)
			(layer "F.SilkS")
			(effects
				(font
					(size 0.7 0.7)
					(thickness 0.15)
				)
				(justify left bottom)
			)
		)
		(property "Value" "RB521S30T1G"
			(at 0 1.499 0)
			(layer "F.Fab")
			(effects
				(font
					(size 0.7 0.7)
					(thickness 0.15)
				)
				(justify left bottom)
			)
		)
		(property "Datasheet" "https://www.onsemi.com/pdf/datasheet/rb521s30t1-d.pdf"
			(at 0 0 0)
			(layer "F.Fab")
			(hide yes)
			(effects
				(font
					(size 1.27 1.27)
					(thickness 0.15)
				)
			)
		)
		(property "Description" "Small Signal Schottky Diode, Single, 30 V, 200 mA, 500 mV, 1 A, 125 °C"
			(at 0 0 0)
			(layer "F.Fab")
			(hide yes)
			(effects
				(font
					(size 1.27 1.27)
					(thickness 0.15)
				)
			)
		)
		(property "MPN" "RB521S30T1G"
			(at 0 0 0)
			(unlocked yes)
			(layer "F.Fab")
			(hide yes)
			(effects
				(font
					(size 1 1)
					(thickness 0.15)
				)
			)
		)
		(property "Manufacturer" "ON Semiconductor"
			(at 0 0 0)
			(unlocked yes)
			(layer "F.Fab")
			(hide yes)
			(effects
				(font
					(size 1 1)
					(thickness 0.15)
				)
			)
		)
		(property "Author" "Antmicro"
			(at 0 0 0)
			(unlocked yes)
			(layer "F.Fab")
			(hide yes)
			(effects
				(font
					(size 1 1)
					(thickness 0.15)
				)
			)
		)
		(property "License" "Apache-2.0"
			(at 0 0 0)
			(unlocked yes)
			(layer "F.Fab")
			(hide yes)
			(effects
				(font
					(size 1 1)
					(thickness 0.15)
				)
			)
		)
		(sheetname "/USB Hub/")
		(sheetfile "usb_hub.kicad_sch")
		(attr smd)
		(fp_line
			(start -0.35 -0.5)
			(end -0.35 0.5)
			(stroke
				(width 0.15)
				(type solid)
			)
			(layer "F.SilkS")
		)
		(fp_poly
			(pts
				(xy -1 -0.6) (xy 1 -0.6) (xy 1 0.6) (xy -1 0.6)
			)
			(stroke
				(width 0.05)
				(type solid)
			)
			(fill no)
			(layer "F.CrtYd")
		)
		(fp_line
			(start -0.652 -0.425)
			(end 0.65 -0.425)
			(stroke
				(width 0.15)
				(type solid)
			)
			(layer "F.Fab")
		)
		(fp_line
			(start -0.652 0.423)
			(end -0.652 -0.425)
			(stroke
				(width 0.15)
				(type solid)
			)
			(layer "F.Fab")
		)
		(fp_line
			(start -0.652 0.423)
			(end 0.65 0.423)
			(stroke
				(width 0.15)
				(type solid)
			)
			(layer "F.Fab")
		)
		(fp_line
			(start -0.35 -0.4)
			(end -0.35 0.4)
			(stroke
				(width 0.15)
				(type solid)
			)
			(layer "F.Fab")
		)
		(fp_line
			(start 0.65 -0.425)
			(end 0.65 0.423)
			(stroke
				(width 0.15)
				(type solid)
			)
			(layer "F.Fab")
		)
		(fp_text user "${REFERENCE}"
			(at -1.276 3.499 0)
			(layer "F.Fab")
			(effects
				(font
					(size 0.7 0.7)
					(thickness 0.15)
				)
				(justify left bottom)
			)
		)
		(fp_text user "Author: Antmicro"
			(at -1.276 4.7 0)
			(layer "F.Fab")
			(effects
				(font
					(size 0.7 0.7)
					(thickness 0.15)
				)
				(justify left bottom)
			)
		)
		(fp_text user "License: Apache-2.0"
			(at -1.276 5.9 0)
			(layer "F.Fab")
			(effects
				(font
					(size 0.7 0.7)
					(thickness 0.15)
				)
				(justify left bottom)
			)
		)
		(pad "1" smd roundrect
			(at -0.701 0)
			(size 0.5 0.6)
			(layers "F.Cu" "F.Mask" "F.Paste")
			(roundrect_rratio 0.25)
			(net 271 "FLASH_PWR")
			(pinfunction "C")
			(pintype "passive")
		)
		(pad "2" smd roundrect
			(at 0.699001 0)
			(size 0.5 0.6)
			(layers "F.Cu" "F.Mask" "F.Paste")
			(roundrect_rratio 0.25)
			(net 2 "+3V3")
			(pinfunction "A")
			(pintype "passive")
		)
	)
	(footprint "antmicro-footprints:Molex_Mini-Fit_2x3_50362462"
		(locked yes)
		(layer "F.Cu")
		(at 228.031 59.49 -90)
		(property "Reference" "J2"
			(at -3.89 -10.74 0)
			(layer "F.SilkS")
			(effects
				(font
					(size 0.7 0.7)
					(thickness 0.15)
				)
				(justify right top)
			)
		)
		(property "Value" "Molex_Mini-Fit_2x3_50362462"
			(at -3.85 8.2 90)
			(layer "F.Fab")
			(effects
				(font
					(size 0.7 0.7)
					(thickness 0.15)
				)
				(justify right top)
			)
		)
		(property "Datasheet" "https://www.molex.com/content/dam/molex/molex-dot-com/products/automated/en-us/salesdrawingpdf/556/5569/050362462_sd.pdf?inline"
			(at 0 0 90)
			(layer "F.Fab")
			(effects
				(font
					(size 0.7 0.7)
					(thickness 0.15)
				)
				(justify right top)
			)
		)
		(property "Description" "Pin Header, Wire-to-Board, 2 Rows, 6 Contacts, Through Hole Right-Angle, Mini-Fit, 13A/pin, 600V, 4.2mm"
			(at 0 0 90)
			(layer "F.Fab")
			(effects
				(font
					(size 0.7 0.7)
					(thickness 0.15)
				)
				(justify right top)
			)
		)
		(property "MPN" "50362462"
			(at 0 0 270)
			(unlocked yes)
			(layer "F.Fab")
			(hide yes)
			(effects
				(font
					(size 1 1)
					(thickness 0.15)
				)
			)
		)
		(property "Manufacturer" "Molex"
			(at 0 0 270)
			(unlocked yes)
			(layer "F.Fab")
			(hide yes)
			(effects
				(font
					(size 1 1)
					(thickness 0.15)
				)
			)
		)
		(property "Author" "Antmicro"
			(at 0 0 270)
			(unlocked yes)
			(layer "F.Fab")
			(hide yes)
			(effects
				(font
					(size 1 1)
					(thickness 0.15)
				)
			)
		)
		(property "License" "Apache-2.0"
			(at 0 0 270)
			(unlocked yes)
			(layer "F.Fab")
			(hide yes)
			(effects
				(font
					(size 1 1)
					(thickness 0.15)
				)
			)
		)
		(sheetname "/Power/")
		(sheetfile "power.kicad_sch")
		(attr through_hole)
		(fp_line
			(start -2.7 -1)
			(end -1.4 -1)
			(stroke
				(width 0.15)
				(type solid)
			)
			(layer "F.SilkS")
		)
		(fp_line
			(start -2.7 -1)
			(end -2.7 -13.9)
			(stroke
				(width 0.15)
				(type solid)
			)
			(layer "F.SilkS")
		)
		(fp_line
			(start 9.8 -1)
			(end 11.1 -1)
			(stroke
				(width 0.15)
				(type solid)
			)
			(layer "F.SilkS")
		)
		(fp_line
			(start -2.7 -13.9)
			(end 11.1 -13.9)
			(stroke
				(width 0.15)
				(type solid)
			)
			(layer "F.SilkS")
		)
		(fp_line
			(start 11.1 -13.9)
			(end 11.1 -1)
			(stroke
				(width 0.15)
				(type solid)
			)
			(layer "F.SilkS")
		)
		(fp_circle
			(center -1.5 0)
			(end -1.45 0)
			(stroke
				(width 0.15)
				(type solid)
			)
			(fill yes)
			(layer "F.SilkS")
		)
		(fp_rect
			(start -3.5 -14.3)
			(end 11.5 7.1)
			(stroke
				(width 0.05)
				(type solid)
			)
			(fill no)
			(layer "F.CrtYd")
		)
		(fp_line
			(start -2.7 6.4)
			(end -2.7 -13.9)
			(stroke
				(width 0.15)
				(type solid)
			)
			(layer "F.Fab")
		)
		(fp_line
			(start 11.1 6.4)
			(end -2.7 6.4)
			(stroke
				(width 0.15)
				(type solid)
			)
			(layer "F.Fab")
		)
		(fp_line
			(start -2.7 -13.9)
			(end 11.1 -13.9)
			(stroke
				(width 0.15)
				(type solid)
			)
			(layer "F.Fab")
		)
		(fp_line
			(start 11.1 -13.9)
			(end 11.1 6.4)
			(stroke
				(width 0.15)
				(type solid)
			)
			(layer "F.Fab")
		)
		(fp_text user "Author: Antmicro"
			(at -3.85 10.6 90)
			(layer "F.Fab")
			(effects
				(font
					(size 0.7 0.7)
					(thickness 0.15)
				)
				(justify right top)
			)
		)
		(fp_text user "License: Apache-2.0"
			(at -3.85 9.4 90)
			(layer "F.Fab")
			(effects
				(font
					(size 0.7 0.7)
					(thickness 0.15)
				)
				(justify right top)
			)
		)
		(fp_text user "${REFERENCE}"
			(at -3.85 11.8 90)
			(layer "F.Fab")
			(effects
				(font
					(size 0.7 0.7)
					(thickness 0.15)
				)
				(justify right top)
			)
		)
		(pad "" np_thru_hole circle
			(at 0 -7.3 90)
			(size 3.05 3.05)
			(drill 3)
			(layers "*.Cu" "*.Mask")
		)
		(pad "" np_thru_hole circle
			(at 8.4 -7.3 90)
			(size 3.05 3.05)
			(drill 3)
			(layers "*.Cu" "*.Mask")
		)
		(pad "1" thru_hole rect
			(at 0 0 90)
			(size 2.4 2.4)
			(drill 1.8)
			(layers "*.Cu" "*.Mask")
			(remove_unused_layers no)
			(net 3 "VCC_IN")
			(pinfunction "1")
			(pintype "input")
		)
		(pad "2" thru_hole circle
			(at 4.2 0 90)
			(size 2.4 2.4)
			(drill 1.8)
			(layers "*.Cu" "*.Mask")
			(remove_unused_layers no)
			(net 3 "VCC_IN")
			(pinfunction "2")
			(pintype "input")
		)
		(pad "3" thru_hole circle
			(at 8.4 0 90)
			(size 2.4 2.4)
			(drill 1.8)
			(layers "*.Cu" "*.Mask")
			(remove_unused_layers no)
			(net 3 "VCC_IN")
			(pinfunction "3")
			(pintype "input")
		)
		(pad "4" thru_hole circle
			(at 0 5.5 90)
			(size 2.4 2.4)
			(drill 1.8)
			(layers "*.Cu" "*.Mask")
			(remove_unused_layers no)
			(net 1 "GND")
			(pinfunction "4")
			(pintype "input")
		)
		(pad "5" thru_hole circle
			(at 4.2 5.5 90)
			(size 2.4 2.4)
			(drill 1.8)
			(layers "*.Cu" "*.Mask")
			(remove_unused_layers no)
			(net 1 "GND")
			(pinfunction "5")
			(pintype "input")
		)
		(pad "6" thru_hole circle
			(at 8.4 5.5 90)
			(size 2.4 2.4)
			(drill 1.8)
			(layers "*.Cu" "*.Mask")
			(remove_unused_layers no)
			(net 1 "GND")
			(pinfunction "6")
			(pintype "input")
		)
	)
	(footprint "antmicro-footprints:R_0402_1005Metric"
		(layer "F.Cu")
		(at 67.8 85.88 90)
		(descr "Resistor SMD 0402")
		(tags "resistor SMD 0402")
		(property "Reference" "R165"
			(at 0.86 0.4 90)
			(layer "F.SilkS")
			(effects
				(font
					(size 0.7 0.7)
					(thickness 0.15)
				)
				(justify left bottom)
			)
		)
		(property "Value" "R_10k_0402"
			(at -1.011843 1.772047 90)
			(layer "F.Fab")
			(effects
				(font
					(size 0.7 0.7)
					(thickness 0.15)
				)
				(justify left bottom)
			)
		)
		(property "Datasheet" "https://www.bourns.com/docs/product-datasheets/cr.pdf"
			(at 0 0 90)
			(layer "F.Fab")
			(hide yes)
			(effects
				(font
					(size 1.27 1.27)
					(thickness 0.15)
				)
			)
		)
		(property "Description" "SMD Chip Resistor, 10 kohm, ± 1%, 62.5 mW, 0402 [1005 Metric], Thick Film, General Purpose"
			(at 0 0 90)
			(layer "F.Fab")
			(hide yes)
			(effects
				(font
					(size 1.27 1.27)
					(thickness 0.15)
				)
			)
		)
		(property "Manufacturer" "Bourns"
			(at 0 0 90)
			(unlocked yes)
			(layer "F.Fab")
			(hide yes)
			(effects
				(font
					(size 1 1)
					(thickness 0.15)
				)
			)
		)
		(property "MPN" "CR0402-FX-1002GLF"
			(at 0 0 90)
			(unlocked yes)
			(layer "F.Fab")
			(hide yes)
			(effects
				(font
					(size 1 1)
					(thickness 0.15)
				)
			)
		)
		(property "Val" "10k"
			(at 0 0 90)
			(unlocked yes)
			(layer "F.Fab")
			(hide yes)
			(effects
				(font
					(size 1 1)
					(thickness 0.15)
				)
			)
		)
		(property "License" "Apache-2.0"
			(at 0 0 90)
			(unlocked yes)
			(layer "F.Fab")
			(hide yes)
			(effects
				(font
					(size 1 1)
					(thickness 0.15)
				)
			)
		)
		(property "Author" "Antmicro"
			(at 0 0 90)
			(unlocked yes)
			(layer "F.Fab")
			(hide yes)
			(effects
				(font
					(size 1 1)
					(thickness 0.15)
				)
			)
		)
		(property "Tolerance" "1%"
			(at 0 0 90)
			(unlocked yes)
			(layer "F.Fab")
			(hide yes)
			(effects
				(font
					(size 1 1)
					(thickness 0.15)
				)
			)
		)
		(sheetname "/CSI/")
		(sheetfile "csi.kicad_sch")
		(attr smd exclude_from_pos_files exclude_from_bom dnp)
		(fp_rect
			(start -0.925 -0.47)
			(end 0.925 0.47)
			(stroke
				(width 0.05)
				(type default)
			)
			(fill no)
			(layer "F.CrtYd")
		)
		(fp_rect
			(start -0.5 -0.25)
			(end 0.5 0.25)
			(stroke
				(width 0.15)
				(type solid)
			)
			(fill no)
			(layer "F.Fab")
		)
		(fp_text user "${REFERENCE}"
			(at -0.95 3.168 90)
			(layer "F.Fab")
			(effects
				(font
					(size 0.7 0.7)
					(thickness 0.15)
				)
				(justify left bottom)
			)
		)
		(fp_text user "Author: Antmicro"
			(at -0.95 4.169 90)
			(layer "F.Fab")
			(effects
				(font
					(size 0.7 0.7)
					(thickness 0.15)
				)
				(justify left bottom)
			)
		)
		(fp_text user "License: Apache-2.0"
			(at -0.95 5.169 90)
			(layer "F.Fab")
			(effects
				(font
					(size 0.7 0.7)
					(thickness 0.15)
				)
				(justify left bottom)
			)
		)
		(pad "1" smd roundrect
			(at -0.48 0 90)
			(size 0.59 0.64)
			(layers "F.Cu" "F.Mask" "F.Paste")
			(roundrect_rratio 0.25)
			(net 74 "/CSI/CAM_CTRL.CSIA_PEN")
			(pintype "passive")
		)
		(pad "2" smd roundrect
			(at 0.48 0 90)
			(size 0.59 0.64)
			(layers "F.Cu" "F.Mask" "F.Paste")
			(roundrect_rratio 0.25)
			(net 2 "+3V3")
			(pintype "passive")
		)
	)
	(footprint "antmicro-footprints:R_0805_2012Metric"
		(layer "F.Cu")
		(at 172.4 115.966 180)
		(property "Reference" "R77"
			(at 2.12 0.366 0)
			(layer "F.SilkS")
			(effects
				(font
					(size 0.7 0.7)
					(thickness 0.15)
				)
				(justify right top)
			)
		)
		(property "Value" "R_0R001_0805"
			(at 0 1.8 0)
			(layer "F.Fab")
			(effects
				(font
					(size 0.7 0.7)
					(thickness 0.15)
				)
				(justify right top)
			)
		)
		(property "Datasheet" "https://www.eaton.com/content/dam/eaton/products/electronic-components/resources/data-sheet/eaton-msma-automotive-smd-current-sense-resistor-metal-strip-data-sheet-elx1179.pdf"
			(at 0 0 0)
			(layer "F.Fab")
			(hide yes)
			(effects
				(font
					(size 1.27 1.27)
					(thickness 0.15)
				)
			)
		)
		(property "Description" "Current Sense Resistors - SMD MSMA, 0805 SIZE, 1/2 Watt, 1 mohm, 50 TCR MnCu Metal AEC-Q"
			(at 0 0 0)
			(layer "F.Fab")
			(hide yes)
			(effects
				(font
					(size 1.27 1.27)
					(thickness 0.15)
				)
			)
		)
		(property "MPN" "MSMA0805R0010FSM"
			(at 0 0 180)
			(unlocked yes)
			(layer "F.Fab")
			(hide yes)
			(effects
				(font
					(size 1 1)
					(thickness 0.15)
				)
			)
		)
		(property "Manufacturer" "Eaton"
			(at 0 0 180)
			(unlocked yes)
			(layer "F.Fab")
			(hide yes)
			(effects
				(font
					(size 1 1)
					(thickness 0.15)
				)
			)
		)
		(property "License" "Apache-2.0"
			(at 0 0 180)
			(unlocked yes)
			(layer "F.Fab")
			(hide yes)
			(effects
				(font
					(size 1 1)
					(thickness 0.15)
				)
			)
		)
		(property "Author" "Antmicro"
			(at 0 0 180)
			(unlocked yes)
			(layer "F.Fab")
			(hide yes)
			(effects
				(font
					(size 1 1)
					(thickness 0.15)
				)
			)
		)
		(property "Val" "0R001"
			(at 0 0 180)
			(unlocked yes)
			(layer "F.Fab")
			(hide yes)
			(effects
				(font
					(size 1 1)
					(thickness 0.15)
				)
			)
		)
		(property "Tolerance" "1%"
			(at 0 0 180)
			(unlocked yes)
			(layer "F.Fab")
			(hide yes)
			(effects
				(font
					(size 1 1)
					(thickness 0.15)
				)
			)
		)
		(property "Public" "False"
			(at 0 0 180)
			(unlocked yes)
			(layer "F.Fab")
			(hide yes)
			(effects
				(font
					(size 1 1)
					(thickness 0.15)
				)
			)
		)
		(sheetname "/DCDC/")
		(sheetfile "dcdc.kicad_sch")
		(attr smd)
		(fp_line
			(start -0.3 -0.701)
			(end 0.298 -0.701)
			(stroke
				(width 0.15)
				(type solid)
			)
			(layer "F.SilkS")
		)
		(fp_line
			(start -0.32 0.699)
			(end 0.28 0.699)
			(stroke
				(width 0.15)
				(type solid)
			)
			(layer "F.SilkS")
		)
		(fp_rect
			(start 1.95 -0.9)
			(end -1.95 0.9)
			(stroke
				(width 0.05)
				(type default)
			)
			(fill no)
			(layer "F.CrtYd")
		)
		(fp_line
			(start 0.949 -0.677)
			(end 0.949 0.675)
			(stroke
				(width 0.15)
				(type solid)
			)
			(layer "F.Fab")
		)
		(fp_line
			(start -0.951 0.68)
			(end 0.949 0.68)
			(stroke
				(width 0.15)
				(type solid)
			)
			(layer "F.Fab")
		)
		(fp_line
			(start -0.951 -0.677)
			(end -0.951 0.675)
			(stroke
				(width 0.15)
				(type solid)
			)
			(layer "F.Fab")
		)
		(fp_line
			(start -0.951 -0.682)
			(end 0.949 -0.682)
			(stroke
				(width 0.15)
				(type solid)
			)
			(layer "F.Fab")
		)
		(fp_text user "Author: Antmicro"
			(at -1.9 4.4 0)
			(layer "F.Fab")
			(effects
				(font
					(size 0.7 0.7)
					(thickness 0.15)
				)
				(justify right top)
			)
		)
		(fp_text user "License: Apache-2.0"
			(at -1.9 5.75 0)
			(layer "F.Fab")
			(effects
				(font
					(size 0.7 0.7)
					(thickness 0.15)
				)
				(justify right top)
			)
		)
		(fp_text user "${REFERENCE}"
			(at -1.9 3.1 0)
			(layer "F.Fab")
			(effects
				(font
					(size 0.7 0.7)
					(thickness 0.15)
				)
				(justify right top)
			)
		)
		(pad "1" smd roundrect
			(at -1.1 0 180)
			(size 1.2 1.3)
			(layers "F.Cu" "F.Mask" "F.Paste")
			(roundrect_rratio 0.25)
			(net 253 "/DCDC/5V_OUT")
			(pintype "passive")
		)
		(pad "2" smd roundrect
			(at 1.1 0 180)
			(size 1.2 1.3)
			(layers "F.Cu" "F.Mask" "F.Paste")
			(roundrect_rratio 0.25)
			(net 5 "+5V")
			(pintype "passive")
		)
	)
	(footprint "antmicro-footprints:C_0402_1005Metric"
		(layer "F.Cu")
		(at 212.912407 98.212991 90)
		(descr "Capacitor SMD 0402")
		(tags "capacitor SMD 0402")
		(property "Reference" "C231"
			(at -1.787009 -2.612407 90)
			(layer "F.SilkS")
			(effects
				(font
					(size 0.7 0.7)
					(thickness 0.15)
				)
				(justify left bottom)
			)
		)
		(property "Value" "C_10u_0402"
			(at -1.022927 2.155213 90)
			(layer "F.Fab")
			(effects
				(font
					(size 0.7 0.7)
					(thickness 0.15)
				)
				(justify left bottom)
			)
		)
		(property "Datasheet" "https://www.yageo.com/en/Chart/Download/pdf/CC0402MRX5R5BB106"
			(at 0 0 90)
			(layer "F.Fab")
			(hide yes)
			(effects
				(font
					(size 1.27 1.27)
					(thickness 0.15)
				)
			)
		)
		(property "Description" "SMD Multilayer Ceramic Capacitor, 10 µF, 6.3 V, 0402 [1005 Metric], ± 20%, X5R, CC Series"
			(at 0 0 90)
			(layer "F.Fab")
			(hide yes)
			(effects
				(font
					(size 1.27 1.27)
					(thickness 0.15)
				)
			)
		)
		(property "Manufacturer" "YAGEO"
			(at 0 0 270)
			(unlocked yes)
			(layer "F.Fab")
			(hide yes)
			(effects
				(font
					(size 1 1)
					(thickness 0.15)
				)
			)
		)
		(property "MPN" "CC0402MRX5R5BB106"
			(at 0 0 270)
			(unlocked yes)
			(layer "F.Fab")
			(hide yes)
			(effects
				(font
					(size 1 1)
					(thickness 0.15)
				)
			)
		)
		(property "Val" "10u"
			(at 0 0 270)
			(unlocked yes)
			(layer "F.Fab")
			(hide yes)
			(effects
				(font
					(size 1 1)
					(thickness 0.15)
				)
			)
		)
		(property "License" "Apache-2.0"
			(at 0 0 270)
			(unlocked yes)
			(layer "F.Fab")
			(hide yes)
			(effects
				(font
					(size 1 1)
					(thickness 0.15)
				)
			)
		)
		(property "Author" "Antmicro"
			(at 0 0 270)
			(unlocked yes)
			(layer "F.Fab")
			(hide yes)
			(effects
				(font
					(size 1 1)
					(thickness 0.15)
				)
			)
		)
		(property "Voltage" ""
			(at 0 0 270)
			(unlocked yes)
			(layer "F.Fab")
			(hide yes)
			(effects
				(font
					(size 1 1)
					(thickness 0.15)
				)
			)
		)
		(property "Dielectric" "template_dielectric"
			(at 0 0 270)
			(unlocked yes)
			(layer "F.Fab")
			(hide yes)
			(effects
				(font
					(size 1 1)
					(thickness 0.15)
				)
			)
		)
		(sheetname "/Recovery USB/")
		(sheetfile "recovery_usb.kicad_sch")
		(attr smd)
		(fp_poly
			(pts
				(xy -0.925 -0.47) (xy 0.925 -0.47) (xy 0.925 0.47) (xy -0.925 0.47)
			)
			(stroke
				(width 0.05)
				(type default)
			)
			(fill no)
			(layer "F.CrtYd")
		)
		(fp_line
			(start 0.504 -0.25)
			(end 0.504 0.248)
			(stroke
				(width 0.15)
				(type solid)
			)
			(layer "F.Fab")
		)
		(fp_line
			(start -0.494 -0.25)
			(end 0.504 -0.25)
			(stroke
				(width 0.15)
				(type solid)
			)
			(layer "F.Fab")
		)
		(fp_line
			(start 0.504 0.248)
			(end -0.494 0.248)
			(stroke
				(width 0.15)
				(type solid)
			)
			(layer "F.Fab")
		)
		(fp_line
			(start -0.494 0.248)
			(end -0.494 -0.25)
			(stroke
				(width 0.15)
				(type solid)
			)
			(layer "F.Fab")
		)
		(fp_text user "License: Apache-2.0"
			(at -0.939 5.799 90)
			(layer "F.Fab")
			(effects
				(font
					(size 0.7 0.7)
					(thickness 0.15)
				)
				(justify left bottom)
			)
		)
		(fp_text user "${REFERENCE}"
			(at -0.939 4.599 90)
			(layer "F.Fab")
			(effects
				(font
					(size 0.7 0.7)
					(thickness 0.15)
				)
				(justify left bottom)
			)
		)
		(fp_text user "Author: Antmicro"
			(at -0.939 3.399 90)
			(layer "F.Fab")
			(effects
				(font
					(size 0.7 0.7)
					(thickness 0.15)
				)
				(justify left bottom)
			)
		)
		(pad "1" smd roundrect
			(at -0.48 0 90)
			(size 0.59 0.64)
			(layers "F.Cu" "F.Mask" "F.Paste")
			(roundrect_rratio 0.25)
			(net 5 "+5V")
			(pintype "passive")
		)
		(pad "2" smd roundrect
			(at 0.48 0 90)
			(size 0.59 0.64)
			(layers "F.Cu" "F.Mask" "F.Paste")
			(roundrect_rratio 0.25)
			(net 1 "GND")
			(pintype "passive")
		)
	)
	(footprint "antmicro-footprints:C_0402_1005Metric"
		(layer "F.Cu")
		(at 162.228936 99.57)
		(descr "Capacitor SMD 0402")
		(tags "capacitor SMD 0402")
		(property "Reference" "C385"
			(at -5.828936 0.43 0)
			(layer "F.SilkS")
			(effects
				(font
					(size 0.7 0.7)
					(thickness 0.15)
				)
				(justify left bottom)
			)
		)
		(property "Value" "C_100n_0402"
			(at -1.022927 2.155213 0)
			(layer "F.Fab")
			(effects
				(font
					(size 0.7 0.7)
					(thickness 0.15)
				)
				(justify left bottom)
			)
		)
		(property "Datasheet" "https://www.murata.com/products/productdetail?partno=GRM155R61H104KE14%23"
			(at 0 0 0)
			(layer "F.Fab")
			(hide yes)
			(effects
				(font
					(size 1.27 1.27)
					(thickness 0.15)
				)
			)
		)
		(property "Description" "SMD Multilayer Ceramic Capacitor, 0.1 µF, 50 V, 0402 [1005 Metric], ± 10%, X5R, GRM Series"
			(at 0 0 0)
			(layer "F.Fab")
			(hide yes)
			(effects
				(font
					(size 1.27 1.27)
					(thickness 0.15)
				)
			)
		)
		(property "Manufacturer" "Murata"
			(at 0 0 0)
			(unlocked yes)
			(layer "F.Fab")
			(hide yes)
			(effects
				(font
					(size 1 1)
					(thickness 0.15)
				)
			)
		)
		(property "MPN" "GRM155R61H104KE14D"
			(at 0 0 0)
			(unlocked yes)
			(layer "F.Fab")
			(hide yes)
			(effects
				(font
					(size 1 1)
					(thickness 0.15)
				)
			)
		)
		(property "Val" "100n"
			(at 0 0 0)
			(unlocked yes)
			(layer "F.Fab")
			(hide yes)
			(effects
				(font
					(size 1 1)
					(thickness 0.15)
				)
			)
		)
		(property "License" "Apache-2.0"
			(at 0 0 0)
			(unlocked yes)
			(layer "F.Fab")
			(hide yes)
			(effects
				(font
					(size 1 1)
					(thickness 0.15)
				)
			)
		)
		(property "Author" "Antmicro"
			(at 0 0 0)
			(unlocked yes)
			(layer "F.Fab")
			(hide yes)
			(effects
				(font
					(size 1 1)
					(thickness 0.15)
				)
			)
		)
		(property "Voltage" "50V"
			(at 0 0 0)
			(unlocked yes)
			(layer "F.Fab")
			(hide yes)
			(effects
				(font
					(size 1 1)
					(thickness 0.15)
				)
			)
		)
		(property "Dielectric" "X5R"
			(at 0 0 0)
			(unlocked yes)
			(layer "F.Fab")
			(hide yes)
			(effects
				(font
					(size 1 1)
					(thickness 0.15)
				)
			)
		)
		(component_classes
			(class "DCDC_SOM")
		)
		(sheetname "/DCDC/")
		(sheetfile "dcdc.kicad_sch")
		(attr smd)
		(fp_rect
			(start -0.925 -0.47)
			(end 0.925 0.47)
			(stroke
				(width 0.05)
				(type default)
			)
			(fill no)
			(layer "F.CrtYd")
		)
		(fp_line
			(start -0.494 -0.25)
			(end 0.504 -0.25)
			(stroke
				(width 0.15)
				(type solid)
			)
			(layer "F.Fab")
		)
		(fp_line
			(start -0.494 0.248)
			(end -0.494 -0.25)
			(stroke
				(width 0.15)
				(type solid)
			)
			(layer "F.Fab")
		)
		(fp_line
			(start 0.504 -0.25)
			(end 0.504 0.248)
			(stroke
				(width 0.15)
				(type solid)
			)
			(layer "F.Fab")
		)
		(fp_line
			(start 0.504 0.248)
			(end -0.494 0.248)
			(stroke
				(width 0.15)
				(type solid)
			)
			(layer "F.Fab")
		)
		(fp_text user "License: Apache-2.0"
			(at -0.939 5.799 0)
			(layer "F.Fab")
			(effects
				(font
					(size 0.7 0.7)
					(thickness 0.15)
				)
				(justify left bottom)
			)
		)
		(fp_text user "Author: Antmicro"
			(at -0.939 3.399 0)
			(layer "F.Fab")
			(effects
				(font
					(size 0.7 0.7)
					(thickness 0.15)
				)
				(justify left bottom)
			)
		)
		(fp_text user "${REFERENCE}"
			(at -0.939 4.599 0)
			(layer "F.Fab")
			(effects
				(font
					(size 0.7 0.7)
					(thickness 0.15)
				)
				(justify left bottom)
			)
		)
		(pad "1" smd roundrect
			(at -0.48 0)
			(size 0.59 0.64)
			(layers "F.Cu" "F.Mask" "F.Paste")
			(roundrect_rratio 0.25)
			(net 1187 "Net-(U22-IN-)")
			(pintype "passive")
		)
		(pad "2" smd roundrect
			(at 0.48 0)
			(size 0.59 0.64)
			(layers "F.Cu" "F.Mask" "F.Paste")
			(roundrect_rratio 0.25)
			(net 1283 "Net-(U22-IN+)")
			(pintype "passive")
		)
	)
	(footprint "antmicro-footprints:TP_SMD_0.75mm"
		(layer "F.Cu")
		(at 166.25 57.12)
		(property "Reference" "TP41"
			(at -0.831064 2.21 90)
			(layer "F.SilkS")
			(hide yes)
			(effects
				(font
					(size 0.7 0.7)
					(thickness 0.15)
				)
				(justify left bottom)
			)
		)
		(property "Value" "TP_0.75mm_SMD"
			(at 0 1.2 0)
			(layer "F.Fab")
			(effects
				(font
					(size 0.7 0.7)
					(thickness 0.15)
				)
				(justify left bottom)
			)
		)
		(property "Description" "SMT test point"
			(at 0 0 0)
			(layer "F.Fab")
			(hide yes)
			(effects
				(font
					(size 1.27 1.27)
					(thickness 0.15)
				)
			)
		)
		(property "MPN" ""
			(at 0 0 0)
			(unlocked yes)
			(layer "F.Fab")
			(hide yes)
			(effects
				(font
					(size 1 1)
					(thickness 0.15)
				)
			)
		)
		(property "Manufacturer" ""
			(at 0 0 0)
			(unlocked yes)
			(layer "F.Fab")
			(hide yes)
			(effects
				(font
					(size 1 1)
					(thickness 0.15)
				)
			)
		)
		(property "Author" "Antmicro"
			(at 0 0 0)
			(unlocked yes)
			(layer "F.Fab")
			(hide yes)
			(effects
				(font
					(size 1 1)
					(thickness 0.15)
				)
			)
		)
		(property "License" "Apache-2.0"
			(at 0 0 0)
			(unlocked yes)
			(layer "F.Fab")
			(hide yes)
			(effects
				(font
					(size 1 1)
					(thickness 0.15)
				)
			)
		)
		(sheetname "/Power/")
		(sheetfile "power.kicad_sch")
		(attr exclude_from_pos_files exclude_from_bom)
		(fp_circle
			(center 0 0)
			(end 0.475 0)
			(stroke
				(width 0.05)
				(type default)
			)
			(fill no)
			(layer "F.CrtYd")
		)
		(fp_text user "${REFERENCE}"
			(at -0.4 2.7 0)
			(layer "F.Fab")
			(effects
				(font
					(size 0.7 0.7)
					(thickness 0.15)
				)
				(justify left bottom)
			)
		)
		(fp_text user "License: Apache-2.0"
			(at -0.4 5.101 0)
			(layer "F.Fab")
			(effects
				(font
					(size 0.7 0.7)
					(thickness 0.15)
				)
				(justify left bottom)
			)
		)
		(fp_text user "Author: Antmicro"
			(at -0.4 3.901 0)
			(layer "F.Fab")
			(effects
				(font
					(size 0.7 0.7)
					(thickness 0.15)
				)
				(justify left bottom)
			)
		)
		(pad "1" smd circle
			(at 0 0)
			(size 0.75 0.75)
			(layers "F.Cu" "F.Mask")
			(net 2 "+3V3")
			(pinfunction "1")
			(pintype "passive")
		)
	)
	(footprint "antmicro-footprints:Vishay_PowerPAK_1212-8_Single"
		(layer "F.Cu")
		(at 211.214 68.81 180)
		(descr "PowerPAK 1212-8 Single")
		(tags "Vishay PowerPAK 1212-8 Single")
		(property "Reference" "Q42"
			(at 2.914 1.81 90)
			(layer "F.SilkS")
			(effects
				(font
					(size 0.7 0.7)
					(thickness 0.15)
				)
				(justify right top)
			)
		)
		(property "Value" "SISS05DN-T1-GE3"
			(at 0 2.7 0)
			(layer "F.Fab")
			(effects
				(font
					(size 0.7 0.7)
					(thickness 0.15)
				)
				(justify right top)
			)
		)
		(property "Datasheet" "https://www.vishay.com/docs/77029/siss05dn.pdf"
			(at 0 0 0)
			(layer "F.Fab")
			(hide yes)
			(effects
				(font
					(size 1.27 1.27)
					(thickness 0.15)
				)
			)
		)
		(property "Description" "Power MOSFET, P Channel, 30 V, 108 A, 0.0035 ohm, PowerPAK 1212, Surface Mount"
			(at 0 0 0)
			(layer "F.Fab")
			(hide yes)
			(effects
				(font
					(size 1.27 1.27)
					(thickness 0.15)
				)
			)
		)
		(property "MPN" "SISS05DN-T1-GE3"
			(at 0 0 180)
			(unlocked yes)
			(layer "F.Fab")
			(hide yes)
			(effects
				(font
					(size 1 1)
					(thickness 0.15)
				)
			)
		)
		(property "Manufacturer" "Vishay"
			(at 0 0 180)
			(unlocked yes)
			(layer "F.Fab")
			(hide yes)
			(effects
				(font
					(size 1 1)
					(thickness 0.15)
				)
			)
		)
		(property "Author" "Antmicro"
			(at 0 0 180)
			(unlocked yes)
			(layer "F.Fab")
			(hide yes)
			(effects
				(font
					(size 1 1)
					(thickness 0.15)
				)
			)
		)
		(property "License" "Apache-2.0"
			(at 0 0 180)
			(unlocked yes)
			(layer "F.Fab")
			(hide yes)
			(effects
				(font
					(size 1 1)
					(thickness 0.15)
				)
			)
		)
		(sheetname "/Power/")
		(sheetfile "power.kicad_sch")
		(attr smd)
		(fp_line
			(start 1.648 -1.651)
			(end 1.648 -1.317)
			(stroke
				(width 0.15)
				(type solid)
			)
			(layer "F.SilkS")
		)
		(fp_line
			(start 1.634 1.3)
			(end 1.634 1.634)
			(stroke
				(width 0.15)
				(type solid)
			)
			(layer "F.SilkS")
		)
		(fp_line
			(start -1.635 1.634)
			(end 1.634 1.634)
			(stroke
				(width 0.15)
				(type solid)
			)
			(layer "F.SilkS")
		)
		(fp_line
			(start -1.635 1.3)
			(end -1.635 1.634)
			(stroke
				(width 0.15)
				(type solid)
			)
			(layer "F.SilkS")
		)
		(fp_line
			(start -1.651 -1.651)
			(end 1.648 -1.651)
			(stroke
				(width 0.15)
				(type solid)
			)
			(layer "F.SilkS")
		)
		(fp_line
			(start -1.651 -1.651)
			(end -1.651 -1.317)
			(stroke
				(width 0.15)
				(type solid)
			)
			(layer "F.SilkS")
		)
		(fp_circle
			(center -1.9 -1.4)
			(end -1.85 -1.4)
			(stroke
				(width 0.15)
				(type solid)
			)
			(fill yes)
			(layer "F.SilkS")
		)
		(fp_rect
			(start -2 -1.8)
			(end 2 1.798)
			(stroke
				(width 0.05)
				(type solid)
			)
			(fill no)
			(layer "F.CrtYd")
		)
		(fp_line
			(start -1.6425 -1.4175)
			(end -1.4175 -1.6425)
			(stroke
				(width 0.15)
				(type solid)
			)
			(layer "F.Fab")
		)
		(fp_rect
			(start -1.651 -1.651)
			(end 1.648 1.648)
			(stroke
				(width 0.15)
				(type solid)
			)
			(fill no)
			(layer "F.Fab")
		)
		(fp_text user "Author: Antmicro"
			(at -8 5.9 0)
			(layer "F.Fab")
			(effects
				(font
					(size 0.7 0.7)
					(thickness 0.15)
				)
				(justify right top)
			)
		)
		(fp_text user "License: Apache-2.0"
			(at -8 7.1 0)
			(layer "F.Fab")
			(effects
				(font
					(size 0.7 0.7)
					(thickness 0.15)
				)
				(justify right top)
			)
		)
		(fp_text user "${REFERENCE}"
			(at -8 4.7 0)
			(layer "F.Fab")
			(effects
				(font
					(size 0.7 0.7)
					(thickness 0.15)
				)
				(justify right top)
			)
		)
		(pad "1" smd rect
			(at -1.436 -0.99 180)
			(size 0.99 0.405)
			(layers "F.Cu" "F.Mask" "F.Paste")
			(net 1383 "VCC_NO_OVP")
			(pinfunction "S")
			(pintype "passive")
		)
		(pad "2" smd rect
			(at -1.436 -0.332 180)
			(size 0.99 0.405)
			(layers "F.Cu" "F.Mask" "F.Paste")
			(net 1383 "VCC_NO_OVP")
			(pinfunction "S")
			(pintype "passive")
		)
		(pad "3" smd rect
			(at -1.436 0.33 180)
			(size 0.99 0.405)
			(layers "F.Cu" "F.Mask" "F.Paste")
			(net 1383 "VCC_NO_OVP")
			(pinfunction "S")
			(pintype "passive")
		)
		(pad "4" smd rect
			(at -1.436 0.988 180)
			(size 0.99 0.405)
			(layers "F.Cu" "F.Mask" "F.Paste")
			(net 1385 "Net-(Q41-G)")
			(pinfunction "G")
			(pintype "input")
		)
		(pad "5" smd custom
			(at 0.557 0 180)
			(size 1.725 2.235)
			(layers "F.Cu" "F.Mask" "F.Paste")
			(net 13 "VCC")
			(pinfunction "D")
			(pintype "passive")
			(zone_connect 2)
			(options
				(clearance outline)
				(anchor rect)
			)
			(primitives
				(gr_poly
					(pts
						(xy 0.8625 0.1275) (xy 0.8625 -0.1275) (xy 1.3725 -0.1275) (xy 1.3725 -0.5325) (xy 0.8625 -0.5325)
						(xy 0.8625 -0.7875) (xy 1.3725 -0.7875) (xy 1.3725 -1.195) (xy 0.6125 -1.195) (xy 0.6125 1.195)
						(xy 1.3725 1.195) (xy 1.3725 0.7875) (xy 0.8625 0.7875) (xy 0.8625 0.5325) (xy 1.3725 0.5325)
						(xy 1.3725 0.1275)
					)
					(width 0)
					(fill yes)
				)
			)
		)
	)
	(footprint "antmicro-footprints:C_0402_1005Metric"
		(layer "F.Cu")
		(at 211.2 81.3 180)
		(descr "Capacitor SMD 0402")
		(tags "capacitor SMD 0402")
		(property "Reference" "C233"
			(at -0.7 -0.6 0)
			(layer "F.SilkS")
			(effects
				(font
					(size 0.7 0.7)
					(thickness 0.15)
				)
				(justify right top)
			)
		)
		(property "Value" "C_100n_0402"
			(at -1.022927 2.155213 0)
			(layer "F.Fab")
			(effects
				(font
					(size 0.7 0.7)
					(thickness 0.15)
				)
				(justify right top)
			)
		)
		(property "Datasheet" "https://www.murata.com/products/productdetail?partno=GRM155R61H104KE14%23"
			(at 0 0 0)
			(layer "F.Fab")
			(hide yes)
			(effects
				(font
					(size 1.27 1.27)
					(thickness 0.15)
				)
			)
		)
		(property "Description" "SMD Multilayer Ceramic Capacitor, 0.1 µF, 50 V, 0402 [1005 Metric], ± 10%, X5R, GRM Series"
			(at 0 0 0)
			(layer "F.Fab")
			(hide yes)
			(effects
				(font
					(size 1.27 1.27)
					(thickness 0.15)
				)
			)
		)
		(property "MPN" "GRM155R61H104KE14D"
			(at 0 0 180)
			(unlocked yes)
			(layer "F.Fab")
			(hide yes)
			(effects
				(font
					(size 1 1)
					(thickness 0.15)
				)
			)
		)
		(property "Manufacturer" "Murata"
			(at 0 0 180)
			(unlocked yes)
			(layer "F.Fab")
			(hide yes)
			(effects
				(font
					(size 1 1)
					(thickness 0.15)
				)
			)
		)
		(property "Val" "100n"
			(at 0 0 180)
			(unlocked yes)
			(layer "F.Fab")
			(hide yes)
			(effects
				(font
					(size 1 1)
					(thickness 0.15)
				)
			)
		)
		(property "License" "Apache-2.0"
			(at 0 0 180)
			(unlocked yes)
			(layer "F.Fab")
			(hide yes)
			(effects
				(font
					(size 1 1)
					(thickness 0.15)
				)
			)
		)
		(property "Author" "Antmicro"
			(at 0 0 180)
			(unlocked yes)
			(layer "F.Fab")
			(hide yes)
			(effects
				(font
					(size 1 1)
					(thickness 0.15)
				)
			)
		)
		(property "Voltage" "50V"
			(at 0 0 180)
			(unlocked yes)
			(layer "F.Fab")
			(hide yes)
			(effects
				(font
					(size 1 1)
					(thickness 0.15)
				)
			)
		)
		(property "Dielectric" "X5R"
			(at 0 0 180)
			(unlocked yes)
			(layer "F.Fab")
			(hide yes)
			(effects
				(font
					(size 1 1)
					(thickness 0.15)
				)
			)
		)
		(sheetname "/USB Debug, PD/")
		(sheetfile "usb_debug_pd.kicad_sch")
		(attr smd)
		(fp_rect
			(start -0.925 -0.47)
			(end 0.925 0.47)
			(stroke
				(width 0.05)
				(type default)
			)
			(fill no)
			(layer "F.CrtYd")
		)
		(fp_line
			(start 0.504 0.248)
			(end -0.494 0.248)
			(stroke
				(width 0.15)
				(type solid)
			)
			(layer "F.Fab")
		)
		(fp_line
			(start 0.504 -0.25)
			(end 0.504 0.248)
			(stroke
				(width 0.15)
				(type solid)
			)
			(layer "F.Fab")
		)
		(fp_line
			(start -0.494 0.248)
			(end -0.494 -0.25)
			(stroke
				(width 0.15)
				(type solid)
			)
			(layer "F.Fab")
		)
		(fp_line
			(start -0.494 -0.25)
			(end 0.504 -0.25)
			(stroke
				(width 0.15)
				(type solid)
			)
			(layer "F.Fab")
		)
		(fp_text user "License: Apache-2.0"
			(at -0.939 5.799 0)
			(layer "F.Fab")
			(effects
				(font
					(size 0.7 0.7)
					(thickness 0.15)
				)
				(justify right top)
			)
		)
		(fp_text user "Author: Antmicro"
			(at -0.939 3.399 0)
			(layer "F.Fab")
			(effects
				(font
					(size 0.7 0.7)
					(thickness 0.15)
				)
				(justify right top)
			)
		)
		(fp_text user "${REFERENCE}"
			(at -0.939 4.599 0)
			(layer "F.Fab")
			(effects
				(font
					(size 0.7 0.7)
					(thickness 0.15)
				)
				(justify right top)
			)
		)
		(pad "1" smd roundrect
			(at -0.48 0 180)
			(size 0.59 0.64)
			(layers "F.Cu" "F.Mask" "F.Paste")
			(roundrect_rratio 0.25)
			(net 334 "/USB Debug, PD/FTDI_3V3")
			(pintype "passive")
		)
		(pad "2" smd roundrect
			(at 0.48 0 180)
			(size 0.59 0.64)
			(layers "F.Cu" "F.Mask" "F.Paste")
			(roundrect_rratio 0.25)
			(net 1 "GND")
			(pintype "passive")
		)
	)
	(footprint "antmicro-footprints:R_0402_1005Metric"
		(layer "F.Cu")
		(at 189.3 122.6 90)
		(descr "Resistor SMD 0402")
		(tags "resistor SMD 0402")
		(property "Reference" "R379"
			(at 7.1 -2.4 90)
			(layer "F.SilkS")
			(effects
				(font
					(size 0.7 0.7)
					(thickness 0.15)
				)
				(justify left bottom)
			)
		)
		(property "Value" "R_0R_0402"
			(at -1.011843 1.772047 90)
			(layer "F.Fab")
			(effects
				(font
					(size 0.7 0.7)
					(thickness 0.15)
				)
				(justify left bottom)
			)
		)
		(property "Datasheet" "https://industrial.panasonic.com/cdbs/www-data/pdf/RDA0000/AOA0000C301.pdf"
			(at 0 0 90)
			(layer "F.Fab")
			(hide yes)
			(effects
				(font
					(size 1.27 1.27)
					(thickness 0.15)
				)
			)
		)
		(property "Description" "SMD Chip Resistor, Jumper, 0 ohm, 100 mW, 0402 [1005 Metric], Thick Film, General Purpose"
			(at 0 0 90)
			(layer "F.Fab")
			(hide yes)
			(effects
				(font
					(size 1.27 1.27)
					(thickness 0.15)
				)
			)
		)
		(property "MPN" "ERJ2GE0R00X"
			(at 0 0 90)
			(unlocked yes)
			(layer "F.Fab")
			(hide yes)
			(effects
				(font
					(size 1 1)
					(thickness 0.15)
				)
			)
		)
		(property "Manufacturer" "Panasonic"
			(at 0 0 90)
			(unlocked yes)
			(layer "F.Fab")
			(hide yes)
			(effects
				(font
					(size 1 1)
					(thickness 0.15)
				)
			)
		)
		(property "License" "Apache-2.0"
			(at 0 0 90)
			(unlocked yes)
			(layer "F.Fab")
			(hide yes)
			(effects
				(font
					(size 1 1)
					(thickness 0.15)
				)
			)
		)
		(property "Author" "Antmicro"
			(at 0 0 90)
			(unlocked yes)
			(layer "F.Fab")
			(hide yes)
			(effects
				(font
					(size 1 1)
					(thickness 0.15)
				)
			)
		)
		(property "Val" "0R"
			(at 0 0 90)
			(unlocked yes)
			(layer "F.Fab")
			(hide yes)
			(effects
				(font
					(size 1 1)
					(thickness 0.15)
				)
			)
		)
		(property "Tolerance" "~"
			(at 0 0 90)
			(unlocked yes)
			(layer "F.Fab")
			(hide yes)
			(effects
				(font
					(size 1 1)
					(thickness 0.15)
				)
			)
		)
		(property "Current" "1A"
			(at 0 0 90)
			(unlocked yes)
			(layer "F.Fab")
			(hide yes)
			(effects
				(font
					(size 1 1)
					(thickness 0.15)
				)
			)
		)
		(sheetname "/USB Hub/")
		(sheetfile "usb_hub.kicad_sch")
		(attr smd exclude_from_pos_files exclude_from_bom dnp)
		(fp_rect
			(start -0.925 -0.47)
			(end 0.925 0.47)
			(stroke
				(width 0.05)
				(type default)
			)
			(fill no)
			(layer "F.CrtYd")
		)
		(fp_rect
			(start -0.5 -0.25)
			(end 0.5 0.25)
			(stroke
				(width 0.15)
				(type solid)
			)
			(fill no)
			(layer "F.Fab")
		)
		(fp_text user "${REFERENCE}"
			(at -0.95 3.168 90)
			(layer "F.Fab")
			(effects
				(font
					(size 0.7 0.7)
					(thickness 0.15)
				)
				(justify left bottom)
			)
		)
		(fp_text user "Author: Antmicro"
			(at -0.95 4.169 90)
			(layer "F.Fab")
			(effects
				(font
					(size 0.7 0.7)
					(thickness 0.15)
				)
				(justify left bottom)
			)
		)
		(fp_text user "License: Apache-2.0"
			(at -0.95 5.169 90)
			(layer "F.Fab")
			(effects
				(font
					(size 0.7 0.7)
					(thickness 0.15)
				)
				(justify left bottom)
			)
		)
		(pad "1" smd roundrect
			(at -0.48 0 90)
			(size 0.59 0.64)
			(layers "F.Cu" "F.Mask" "F.Paste")
			(roundrect_rratio 0.25)
			(net 921 "/USB Hub/HUB_SPI_D2")
			(pintype "passive")
		)
		(pad "2" smd roundrect
			(at 0.48 0 90)
			(size 0.59 0.64)
			(layers "F.Cu" "F.Mask" "F.Paste")
			(roundrect_rratio 0.25)
			(net 1166 "/USB Hub/HUB_~{WP}")
			(pintype "passive")
		)
	)
	(footprint "antmicro-footprints:Spacer_Drill4.45mm_H4mm_9774040960R"
		(locked yes)
		(layer "F.Cu")
		(at 155.930532 149.71 90)
		(property "Reference" "H8"
			(at -3.47 -3.58 90)
			(layer "F.SilkS")
			(effects
				(font
					(size 0.7 0.7)
					(thickness 0.15)
				)
				(justify left bottom)
			)
		)
		(property "Value" "Spacer_Drill4.45mm_H4mm_9774040960R"
			(at -3.95 5.05 90)
			(layer "F.Fab")
			(effects
				(font
					(size 0.7 0.7)
					(thickness 0.15)
				)
				(justify left bottom)
			)
		)
		(property "Datasheet" "https://www.we-online.com/components/products/datasheet/9774040960R.pdf"
			(at 0 0 90)
			(layer "F.Fab")
			(effects
				(font
					(size 0.7 0.7)
					(thickness 0.15)
				)
				(justify left bottom)
			)
		)
		(property "Description" "Spacer, SMT, Non Stop, Steel, Swage Round, 6 mm x 4 mm, 3.3 mm Internal, WA-SMST Series"
			(at 0 0 90)
			(layer "F.Fab")
			(effects
				(font
					(size 0.7 0.7)
					(thickness 0.15)
				)
				(justify left bottom)
			)
		)
		(property "Manufacturer" "Würth Elektronik"
			(at 0 0 90)
			(unlocked yes)
			(layer "F.Fab")
			(hide yes)
			(effects
				(font
					(size 1 1)
					(thickness 0.15)
				)
			)
		)
		(property "MPN" "9774040960R"
			(at 0 0 90)
			(unlocked yes)
			(layer "F.Fab")
			(hide yes)
			(effects
				(font
					(size 1 1)
					(thickness 0.15)
				)
			)
		)
		(property "Author" "Antmicro"
			(at 0 0 90)
			(unlocked yes)
			(layer "F.Fab")
			(hide yes)
			(effects
				(font
					(size 1 1)
					(thickness 0.15)
				)
			)
		)
		(property "License" "Apache-2.0"
			(at 0 0 90)
			(unlocked yes)
			(layer "F.Fab")
			(hide yes)
			(effects
				(font
					(size 1 1)
					(thickness 0.15)
				)
			)
		)
		(sheetname "/SoM_Power/")
		(sheetfile "som_power.kicad_sch")
		(attr smd)
		(fp_rect
			(start -3.95 -3.95)
			(end 3.95 3.95)
			(stroke
				(width 0.05)
				(type solid)
			)
			(fill no)
			(layer "F.CrtYd")
		)
		(fp_circle
			(center 0 0)
			(end 3.25 0)
			(stroke
				(width 0.05)
				(type solid)
			)
			(fill no)
			(layer "F.CrtYd")
		)
		(fp_circle
			(center 0 0)
			(end 2.564 0)
			(stroke
				(width 0.15)
				(type solid)
			)
			(fill no)
			(layer "F.Fab")
		)
		(fp_text user "Author: Antmicro"
			(at -3.95 8.65 90)
			(layer "F.Fab")
			(effects
				(font
					(size 0.7 0.7)
					(thickness 0.15)
				)
				(justify left bottom)
			)
		)
		(fp_text user "${REFERENCE}"
			(at -3.95 7.45 90)
			(layer "F.Fab")
			(effects
				(font
					(size 0.7 0.7)
					(thickness 0.15)
				)
				(justify left bottom)
			)
		)
		(fp_text user "License: Apache-2.0"
			(at -3.95 6.25 90)
			(layer "F.Fab")
			(effects
				(font
					(size 0.7 0.7)
					(thickness 0.15)
				)
				(justify left bottom)
			)
		)
		(pad "" smd custom
			(at -2.55 -0.55 212.5)
			(size 0.1 0.1)
			(layers "F.Paste")
			(options
				(clearance outline)
				(anchor circle)
			)
			(primitives
				(gr_arc
					(start 0 0)
					(mid 0.704278 1.28373)
					(end 0.608513 2.744826)
					(width 0.7)
				)
			)
		)
		(pad "" smd custom
			(at -0.55 2.55 302.5)
			(size 0.1 0.1)
			(layers "F.Paste")
			(options
				(clearance outline)
				(anchor circle)
			)
			(primitives
				(gr_arc
					(start 0 0)
					(mid 0.704278 1.28373)
					(end 0.608513 2.744826)
					(width 0.7)
				)
			)
		)
		(pad "" smd custom
			(at 0.55 -2.55 122.5)
			(size 0.1 0.1)
			(layers "F.Paste")
			(options
				(clearance outline)
				(anchor circle)
			)
			(primitives
				(gr_arc
					(start 0 0)
					(mid 0.704278 1.28373)
					(end 0.608513 2.744826)
					(width 0.7)
				)
			)
		)
		(pad "" smd custom
			(at 2.55 0.55 32.5)
			(size 0.1 0.1)
			(layers "F.Paste")
			(options
				(clearance outline)
				(anchor circle)
			)
			(primitives
				(gr_arc
					(start 0 0)
					(mid 0.704278 1.28373)
					(end 0.608513 2.744826)
					(width 0.7)
				)
			)
		)
		(pad "1" thru_hole circle
			(at 0 0 90)
			(size 7.4 7.4)
			(drill 4.45)
			(layers "*.Cu" "*.Mask")
			(remove_unused_layers no)
			(net 1 "GND")
			(pintype "passive")
		)
	)
	(footprint "antmicro-footprints:R_0402_1005Metric"
		(layer "F.Cu")
		(at 156.6 118.4 180)
		(descr "Resistor SMD 0402")
		(tags "resistor SMD 0402")
		(property "Reference" "R359"
			(at -3.6 0.4 0)
			(layer "F.SilkS")
			(effects
				(font
					(size 0.7 0.7)
					(thickness 0.15)
				)
				(justify right top)
			)
		)
		(property "Value" "R_2k2_0402"
			(at -1.011843 1.772047 0)
			(layer "F.Fab")
			(effects
				(font
					(size 0.7 0.7)
					(thickness 0.15)
				)
				(justify right top)
			)
		)
		(property "Datasheet" "https://www.bourns.com/docs/product-datasheets/cr.pdf"
			(at 0 0 0)
			(layer "F.Fab")
			(hide yes)
			(effects
				(font
					(size 1.27 1.27)
					(thickness 0.15)
				)
			)
		)
		(property "Description" "SMD Chip Resistor, 2.2 kohm, ± 1%, 62.5 mW, 0402 [1005 Metric], Thick Film, General Purpose"
			(at 0 0 0)
			(layer "F.Fab")
			(hide yes)
			(effects
				(font
					(size 1.27 1.27)
					(thickness 0.15)
				)
			)
		)
		(property "MPN" "CR0402-FX-2201GLF"
			(at 0 0 180)
			(unlocked yes)
			(layer "F.Fab")
			(hide yes)
			(effects
				(font
					(size 1 1)
					(thickness 0.15)
				)
			)
		)
		(property "Manufacturer" "Bourns"
			(at 0 0 180)
			(unlocked yes)
			(layer "F.Fab")
			(hide yes)
			(effects
				(font
					(size 1 1)
					(thickness 0.15)
				)
			)
		)
		(property "License" "Apache-2.0"
			(at 0 0 180)
			(unlocked yes)
			(layer "F.Fab")
			(hide yes)
			(effects
				(font
					(size 1 1)
					(thickness 0.15)
				)
			)
		)
		(property "Author" "Antmicro"
			(at 0 0 180)
			(unlocked yes)
			(layer "F.Fab")
			(hide yes)
			(effects
				(font
					(size 1 1)
					(thickness 0.15)
				)
			)
		)
		(property "Val" "2k2"
			(at 0 0 180)
			(unlocked yes)
			(layer "F.Fab")
			(hide yes)
			(effects
				(font
					(size 1 1)
					(thickness 0.15)
				)
			)
		)
		(property "Tolerance" "1%"
			(at 0 0 180)
			(unlocked yes)
			(layer "F.Fab")
			(hide yes)
			(effects
				(font
					(size 1 1)
					(thickness 0.15)
				)
			)
		)
		(sheetname "/SoM_IO/")
		(sheetfile "som_io.kicad_sch")
		(attr smd exclude_from_pos_files exclude_from_bom dnp)
		(fp_rect
			(start -0.925 -0.47)
			(end 0.925 0.47)
			(stroke
				(width 0.05)
				(type default)
			)
			(fill no)
			(layer "F.CrtYd")
		)
		(fp_rect
			(start -0.5 -0.25)
			(end 0.5 0.25)
			(stroke
				(width 0.15)
				(type solid)
			)
			(fill no)
			(layer "F.Fab")
		)
		(fp_text user "Author: Antmicro"
			(at -0.95 4.169 0)
			(layer "F.Fab")
			(effects
				(font
					(size 0.7 0.7)
					(thickness 0.15)
				)
				(justify right top)
			)
		)
		(fp_text user "License: Apache-2.0"
			(at -0.95 5.169 0)
			(layer "F.Fab")
			(effects
				(font
					(size 0.7 0.7)
					(thickness 0.15)
				)
				(justify right top)
			)
		)
		(fp_text user "${REFERENCE}"
			(at -0.95 3.168 0)
			(layer "F.Fab")
			(effects
				(font
					(size 0.7 0.7)
					(thickness 0.15)
				)
				(justify right top)
			)
		)
		(pad "1" smd roundrect
			(at -0.48 0 180)
			(size 0.59 0.64)
			(layers "F.Cu" "F.Mask" "F.Paste")
			(roundrect_rratio 0.25)
			(net 11 "+1V8")
			(pintype "passive")
		)
		(pad "2" smd roundrect
			(at 0.48 0 180)
			(size 0.59 0.64)
			(layers "F.Cu" "F.Mask" "F.Paste")
			(roundrect_rratio 0.25)
			(net 60 "/SoM_IO/I2C3_SCL_1V8")
			(pintype "passive")
		)
	)
	(footprint "antmicro-footprints:C_0402_1005Metric"
		(layer "F.Cu")
		(at 94 57.5 180)
		(descr "Capacitor SMD 0402")
		(tags "capacitor SMD 0402")
		(property "Reference" "C223"
			(at -9.75 -0.95 0)
			(layer "F.SilkS")
			(effects
				(font
					(size 0.7 0.7)
					(thickness 0.15)
				)
				(justify right top)
			)
		)
		(property "Value" "C_100n_0402"
			(at -1.022927 2.155213 0)
			(layer "F.Fab")
			(effects
				(font
					(size 0.7 0.7)
					(thickness 0.15)
				)
				(justify right top)
			)
		)
		(property "Datasheet" "https://www.murata.com/products/productdetail?partno=GRM155R61H104KE14%23"
			(at 0 0 0)
			(layer "F.Fab")
			(hide yes)
			(effects
				(font
					(size 1.27 1.27)
					(thickness 0.15)
				)
			)
		)
		(property "Description" "SMD Multilayer Ceramic Capacitor, 0.1 µF, 50 V, 0402 [1005 Metric], ± 10%, X5R, GRM Series"
			(at 0 0 0)
			(layer "F.Fab")
			(hide yes)
			(effects
				(font
					(size 1.27 1.27)
					(thickness 0.15)
				)
			)
		)
		(property "MPN" "GRM155R61H104KE14D"
			(at 0 0 180)
			(unlocked yes)
			(layer "F.Fab")
			(hide yes)
			(effects
				(font
					(size 1 1)
					(thickness 0.15)
				)
			)
		)
		(property "Val" "100n"
			(at 0 0 180)
			(unlocked yes)
			(layer "F.Fab")
			(hide yes)
			(effects
				(font
					(size 1 1)
					(thickness 0.15)
				)
			)
		)
		(property "Voltage" "50V"
			(at 0 0 180)
			(unlocked yes)
			(layer "F.Fab")
			(hide yes)
			(effects
				(font
					(size 1 1)
					(thickness 0.15)
				)
			)
		)
		(property "Dielectric" "X5R"
			(at 0 0 180)
			(unlocked yes)
			(layer "F.Fab")
			(hide yes)
			(effects
				(font
					(size 1 1)
					(thickness 0.15)
				)
			)
		)
		(property "Manufacturer" "Murata"
			(at 0 0 180)
			(unlocked yes)
			(layer "F.Fab")
			(hide yes)
			(effects
				(font
					(size 1 1)
					(thickness 0.15)
				)
			)
		)
		(property "License" "Apache-2.0"
			(at 0 0 180)
			(unlocked yes)
			(layer "F.Fab")
			(hide yes)
			(effects
				(font
					(size 1 1)
					(thickness 0.15)
				)
			)
		)
		(property "Author" "Antmicro"
			(at 0 0 180)
			(unlocked yes)
			(layer "F.Fab")
			(hide yes)
			(effects
				(font
					(size 1 1)
					(thickness 0.15)
				)
			)
		)
		(sheetname "/SoM_Power/")
		(sheetfile "som_power.kicad_sch")
		(attr smd)
		(fp_poly
			(pts
				(xy -0.925 -0.47) (xy -0.925 0.47) (xy 0.925 0.47) (xy 0.925 -0.47)
			)
			(stroke
				(width 0.05)
				(type default)
			)
			(fill no)
			(layer "F.CrtYd")
		)
		(fp_line
			(start 0.504 0.248)
			(end -0.494 0.248)
			(stroke
				(width 0.15)
				(type solid)
			)
			(layer "F.Fab")
		)
		(fp_line
			(start 0.504 -0.25)
			(end 0.504 0.248)
			(stroke
				(width 0.15)
				(type solid)
			)
			(layer "F.Fab")
		)
		(fp_line
			(start -0.494 0.248)
			(end -0.494 -0.25)
			(stroke
				(width 0.15)
				(type solid)
			)
			(layer "F.Fab")
		)
		(fp_line
			(start -0.494 -0.25)
			(end 0.504 -0.25)
			(stroke
				(width 0.15)
				(type solid)
			)
			(layer "F.Fab")
		)
		(fp_text user "License: Apache-2.0"
			(at -0.939 5.799 0)
			(layer "F.Fab")
			(effects
				(font
					(size 0.7 0.7)
					(thickness 0.15)
				)
				(justify right top)
			)
		)
		(fp_text user "${REFERENCE}"
			(at -0.939 4.599 0)
			(layer "F.Fab")
			(effects
				(font
					(size 0.7 0.7)
					(thickness 0.15)
				)
				(justify right top)
			)
		)
		(fp_text user "Author: Antmicro"
			(at -0.939 3.399 0)
			(layer "F.Fab")
			(effects
				(font
					(size 0.7 0.7)
					(thickness 0.15)
				)
				(justify right top)
			)
		)
		(pad "1" smd roundrect
			(at -0.48 0 180)
			(size 0.59 0.64)
			(layers "F.Cu" "F.Mask" "F.Paste")
			(roundrect_rratio 0.25)
			(net 1 "GND")
			(pintype "passive")
		)
		(pad "2" smd roundrect
			(at 0.48 0 180)
			(size 0.59 0.64)
			(layers "F.Cu" "F.Mask" "F.Paste")
			(roundrect_rratio 0.25)
			(net 491 "+5V_AON")
			(pintype "passive")
		)
	)
	(footprint "antmicro-footprints:C_0805_2012Metric"
		(layer "F.Cu")
		(at 173.19 79.81 90)
		(descr "Capacitor SMD 0805")
		(tags "capacitor SMD 0805")
		(property "Reference" "C296"
			(at -4.67 0.31 90)
			(layer "F.SilkS")
			(effects
				(font
					(size 0.7 0.7)
					(thickness 0.15)
				)
				(justify left bottom)
			)
		)
		(property "Value" "C_22u_25V_0805"
			(at -2.055717 1.963152 90)
			(layer "F.Fab")
			(effects
				(font
					(size 0.7 0.7)
					(thickness 0.15)
				)
				(justify left bottom)
			)
		)
		(property "Datasheet" "https://product.samsungsem.com/mlcc/CL21A226MAYNNN.do"
			(at 0 0 90)
			(layer "F.Fab")
			(hide yes)
			(effects
				(font
					(size 1.27 1.27)
					(thickness 0.15)
				)
			)
		)
		(property "Description" "SMT Multilayer Ceramic Capacitor, 22uF, +/-20%, 25V, X5R, 0805 [2012 Metric]"
			(at 0 0 90)
			(layer "F.Fab")
			(hide yes)
			(effects
				(font
					(size 1.27 1.27)
					(thickness 0.15)
				)
			)
		)
		(property "MPN" "CL21A226MAYNNNE"
			(at 0 0 90)
			(unlocked yes)
			(layer "F.Fab")
			(hide yes)
			(effects
				(font
					(size 1 1)
					(thickness 0.15)
				)
			)
		)
		(property "Manufacturer" "Samsung Electro-Mechanics"
			(at 0 0 90)
			(unlocked yes)
			(layer "F.Fab")
			(hide yes)
			(effects
				(font
					(size 1 1)
					(thickness 0.15)
				)
			)
		)
		(property "License" "Apache-2.0"
			(at 0 0 90)
			(unlocked yes)
			(layer "F.Fab")
			(hide yes)
			(effects
				(font
					(size 1 1)
					(thickness 0.15)
				)
			)
		)
		(property "Author" "Antmicro"
			(at 0 0 90)
			(unlocked yes)
			(layer "F.Fab")
			(hide yes)
			(effects
				(font
					(size 1 1)
					(thickness 0.15)
				)
			)
		)
		(property "Val" "22u"
			(at 0 0 90)
			(unlocked yes)
			(layer "F.Fab")
			(hide yes)
			(effects
				(font
					(size 1 1)
					(thickness 0.15)
				)
			)
		)
		(property "Voltage" "25V"
			(at 0 0 90)
			(unlocked yes)
			(layer "F.Fab")
			(hide yes)
			(effects
				(font
					(size 1 1)
					(thickness 0.15)
				)
			)
		)
		(property "Dielectric" "X5R"
			(at 0 0 90)
			(unlocked yes)
			(layer "F.Fab")
			(hide yes)
			(effects
				(font
					(size 1 1)
					(thickness 0.15)
				)
			)
		)
		(property "Public" "False"
			(at 0 0 90)
			(unlocked yes)
			(layer "F.Fab")
			(hide yes)
			(effects
				(font
					(size 1 1)
					(thickness 0.15)
				)
			)
		)
		(component_classes
			(class "DCDC_20V")
		)
		(sheetname "/DCDC/")
		(sheetfile "dcdc.kicad_sch")
		(attr smd)
		(fp_line
			(start -0.3 -0.7)
			(end 0.3 -0.7)
			(stroke
				(width 0.15)
				(type solid)
			)
			(layer "F.SilkS")
		)
		(fp_line
			(start -0.3 0.7)
			(end 0.3 0.7)
			(stroke
				(width 0.15)
				(type solid)
			)
			(layer "F.SilkS")
		)
		(fp_rect
			(start 1.95 -0.9)
			(end -1.95 0.9)
			(stroke
				(width 0.05)
				(type default)
			)
			(fill no)
			(layer "F.CrtYd")
		)
		(fp_rect
			(start -0.95 -0.675)
			(end 0.95 0.675)
			(stroke
				(width 0.15)
				(type solid)
			)
			(fill no)
			(layer "F.Fab")
		)
		(fp_text user "${REFERENCE}"
			(at -1.9 3.947 90)
			(layer "F.Fab")
			(effects
				(font
					(size 0.7 0.7)
					(thickness 0.15)
				)
				(justify left bottom)
			)
		)
		(fp_text user "License: Apache-2.0"
			(at -1.9 4.947 90)
			(layer "F.Fab")
			(effects
				(font
					(size 0.7 0.7)
					(thickness 0.15)
				)
				(justify left bottom)
			)
		)
		(fp_text user "Author: Antmicro"
			(at -1.9 5.947 90)
			(layer "F.Fab")
			(effects
				(font
					(size 0.7 0.7)
					(thickness 0.15)
				)
				(justify left bottom)
			)
		)
		(pad "1" smd roundrect
			(at -1.1 0 90)
			(size 1.2 1.3)
			(layers "F.Cu" "F.Mask" "F.Paste")
			(roundrect_rratio 0.25)
			(net 1 "GND")
			(pintype "passive")
		)
		(pad "2" smd roundrect
			(at 1.1 0 90)
			(size 1.2 1.3)
			(layers "F.Cu" "F.Mask" "F.Paste")
			(roundrect_rratio 0.25)
			(net 1105 "/DCDC/20V_OUT")
			(pintype "passive")
		)
	)
	(footprint "antmicro-footprints:R_0402_1005Metric"
		(layer "F.Cu")
		(at 198.25 84 90)
		(descr "Resistor SMD 0402")
		(tags "resistor SMD 0402")
		(property "Reference" "R93"
			(at -0.9 -0.55 90)
			(layer "F.SilkS")
			(effects
				(font
					(size 0.7 0.7)
					(thickness 0.15)
				)
				(justify left bottom)
			)
		)
		(property "Value" "R_0R_0402"
			(at -1.011843 1.772047 90)
			(layer "F.Fab")
			(effects
				(font
					(size 0.7 0.7)
					(thickness 0.15)
				)
				(justify left bottom)
			)
		)
		(property "Datasheet" "https://industrial.panasonic.com/cdbs/www-data/pdf/RDA0000/AOA0000C301.pdf"
			(at 0 0 90)
			(layer "F.Fab")
			(hide yes)
			(effects
				(font
					(size 1.27 1.27)
					(thickness 0.15)
				)
			)
		)
		(property "Description" "SMD Chip Resistor, Jumper, 0 ohm, 100 mW, 0402 [1005 Metric], Thick Film, General Purpose"
			(at 0 0 90)
			(layer "F.Fab")
			(hide yes)
			(effects
				(font
					(size 1.27 1.27)
					(thickness 0.15)
				)
			)
		)
		(property "Manufacturer" "Panasonic"
			(at 0 0 90)
			(unlocked yes)
			(layer "F.Fab")
			(hide yes)
			(effects
				(font
					(size 1 1)
					(thickness 0.15)
				)
			)
		)
		(property "MPN" "ERJ2GE0R00X"
			(at 0 0 90)
			(unlocked yes)
			(layer "F.Fab")
			(hide yes)
			(effects
				(font
					(size 1 1)
					(thickness 0.15)
				)
			)
		)
		(property "Val" "0R"
			(at 0 0 90)
			(unlocked yes)
			(layer "F.Fab")
			(hide yes)
			(effects
				(font
					(size 1 1)
					(thickness 0.15)
				)
			)
		)
		(property "License" "Apache-2.0"
			(at 0 0 90)
			(unlocked yes)
			(layer "F.Fab")
			(hide yes)
			(effects
				(font
					(size 1 1)
					(thickness 0.15)
				)
			)
		)
		(property "Author" "Antmicro"
			(at 0 0 90)
			(unlocked yes)
			(layer "F.Fab")
			(hide yes)
			(effects
				(font
					(size 1 1)
					(thickness 0.15)
				)
			)
		)
		(property "Tolerance" "~"
			(at 0 0 90)
			(unlocked yes)
			(layer "F.Fab")
			(hide yes)
			(effects
				(font
					(size 1 1)
					(thickness 0.15)
				)
			)
		)
		(property "Current" "1A"
			(at 0 0 90)
			(unlocked yes)
			(layer "F.Fab")
			(hide yes)
			(effects
				(font
					(size 1 1)
					(thickness 0.15)
				)
			)
		)
		(sheetname "/USB Debug, PD/")
		(sheetfile "usb_debug_pd.kicad_sch")
		(attr smd)
		(fp_rect
			(start -0.925 -0.47)
			(end 0.925 0.47)
			(stroke
				(width 0.05)
				(type default)
			)
			(fill no)
			(layer "F.CrtYd")
		)
		(fp_rect
			(start -0.5 -0.25)
			(end 0.5 0.25)
			(stroke
				(width 0.15)
				(type solid)
			)
			(fill no)
			(layer "F.Fab")
		)
		(fp_text user "License: Apache-2.0"
			(at -0.95 5.169 90)
			(layer "F.Fab")
			(effects
				(font
					(size 0.7 0.7)
					(thickness 0.15)
				)
				(justify left bottom)
			)
		)
		(fp_text user "Author: Antmicro"
			(at -0.95 4.169 90)
			(layer "F.Fab")
			(effects
				(font
					(size 0.7 0.7)
					(thickness 0.15)
				)
				(justify left bottom)
			)
		)
		(fp_text user "${REFERENCE}"
			(at -0.95 3.168 90)
			(layer "F.Fab")
			(effects
				(font
					(size 0.7 0.7)
					(thickness 0.15)
				)
				(justify left bottom)
			)
		)
		(pad "1" smd roundrect
			(at -0.48 0 90)
			(size 0.59 0.64)
			(layers "F.Cu" "F.Mask" "F.Paste")
			(roundrect_rratio 0.25)
			(net 1 "GND")
			(pintype "passive")
		)
		(pad "2" smd roundrect
			(at 0.48 0 90)
			(size 0.59 0.64)
			(layers "F.Cu" "F.Mask" "F.Paste")
			(roundrect_rratio 0.25)
			(net 933 "/USB Debug, PD/PDC_RESET")
			(pintype "passive")
		)
	)
	(footprint "antmicro-footprints:R_0603_1608Metric"
		(layer "F.Cu")
		(at 79.2 132)
		(descr "Resistor SMD 0603")
		(tags "resistor SMD 0603")
		(property "Reference" "R248"
			(at 1.3 0.3 0)
			(layer "F.SilkS")
			(effects
				(font
					(size 0.7 0.7)
					(thickness 0.15)
				)
				(justify left bottom)
			)
		)
		(property "Value" "R_0R_22.4A_0603"
			(at 0 1.6 0)
			(layer "F.Fab")
			(effects
				(font
					(size 0.7 0.7)
					(thickness 0.15)
				)
				(justify left bottom)
			)
		)
		(property "Datasheet" "https://fscdn.rohm.com/en/products/databook/datasheet/passive/resistor/chip_resistor/pmr-jpw-e.pdf"
			(at 0 0 0)
			(layer "F.Fab")
			(hide yes)
			(effects
				(font
					(size 1.27 1.27)
					(thickness 0.15)
				)
			)
		)
		(property "Description" "SMD Chip Resistor"
			(at 0 0 0)
			(layer "F.Fab")
			(hide yes)
			(effects
				(font
					(size 1.27 1.27)
					(thickness 0.15)
				)
			)
		)
		(property "MPN" "PMR03EZPJ000"
			(at 0 0 0)
			(unlocked yes)
			(layer "F.Fab")
			(hide yes)
			(effects
				(font
					(size 1 1)
					(thickness 0.15)
				)
			)
		)
		(property "Manufacturer" "ROHM Semiconductor"
			(at 0 0 0)
			(unlocked yes)
			(layer "F.Fab")
			(hide yes)
			(effects
				(font
					(size 1 1)
					(thickness 0.15)
				)
			)
		)
		(property "Val" "0R"
			(at 0 0 0)
			(unlocked yes)
			(layer "F.Fab")
			(hide yes)
			(effects
				(font
					(size 1 1)
					(thickness 0.15)
				)
			)
		)
		(property "Max. Curr." "22.4A"
			(at 0 0 0)
			(unlocked yes)
			(layer "F.Fab")
			(hide yes)
			(effects
				(font
					(size 1 1)
					(thickness 0.15)
				)
			)
		)
		(property "Author" "Antmicro"
			(at 0 0 0)
			(unlocked yes)
			(layer "F.Fab")
			(hide yes)
			(effects
				(font
					(size 1 1)
					(thickness 0.15)
				)
			)
		)
		(property "License" "Apache-2.0"
			(at 0 0 0)
			(unlocked yes)
			(layer "F.Fab")
			(hide yes)
			(effects
				(font
					(size 1 1)
					(thickness 0.15)
				)
			)
		)
		(property "Tolerance" "template_tolerance"
			(at 0 0 0)
			(unlocked yes)
			(layer "F.Fab")
			(hide yes)
			(effects
				(font
					(size 1 1)
					(thickness 0.15)
				)
			)
		)
		(sheetname "/Expansion connector/")
		(sheetfile "expansion_connector.kicad_sch")
		(attr smd exclude_from_pos_files exclude_from_bom dnp)
		(fp_line
			(start -0.15 -0.4)
			(end 0.15 -0.4)
			(stroke
				(width 0.15)
				(type solid)
			)
			(layer "F.SilkS")
		)
		(fp_line
			(start -0.15 0.4)
			(end 0.15 0.4)
			(stroke
				(width 0.15)
				(type solid)
			)
			(layer "F.SilkS")
		)
		(fp_poly
			(pts
				(xy -1.25 -0.65) (xy -1.25 0.65) (xy 1.25 0.65) (xy 1.25 -0.65)
			)
			(stroke
				(width 0.05)
				(type solid)
			)
			(fill no)
			(layer "F.CrtYd")
		)
		(fp_poly
			(pts
				(xy -0.8 -0.4) (xy -0.8 0.4) (xy 0.8 0.4) (xy 0.8 -0.4)
			)
			(stroke
				(width 0.15)
				(type solid)
			)
			(fill no)
			(layer "F.Fab")
		)
		(fp_text user "${REFERENCE}"
			(at -1.25 3.898 0)
			(layer "F.Fab")
			(effects
				(font
					(size 0.7 0.7)
					(thickness 0.15)
				)
				(justify left bottom)
			)
		)
		(fp_text user "Author: Antmicro"
			(at -1.25 4.9 0)
			(layer "F.Fab")
			(effects
				(font
					(size 0.7 0.7)
					(thickness 0.15)
				)
				(justify left bottom)
			)
		)
		(fp_text user "License: Apache-2.0"
			(at -1.249999 5.9 0)
			(layer "F.Fab")
			(effects
				(font
					(size 0.7 0.7)
					(thickness 0.15)
				)
				(justify left bottom)
			)
		)
		(pad "1" smd roundrect
			(at -0.7 0)
			(size 0.8 1)
			(layers "F.Cu" "F.Mask" "F.Paste")
			(roundrect_rratio 0.2)
			(net 295 "/Expansion connector/+V_{ADJ}")
			(pintype "passive")
		)
		(pad "2" smd roundrect
			(at 0.7 0)
			(size 0.8 1)
			(layers "F.Cu" "F.Mask" "F.Paste")
			(roundrect_rratio 0.2)
			(net 11 "+1V8")
			(pintype "passive")
		)
	)
	(footprint "antmicro-footprints:R_0402_1005Metric"
		(layer "F.Cu")
		(at 214.8 120.1 -90)
		(descr "Resistor SMD 0402")
		(tags "resistor SMD 0402")
		(property "Reference" "R80"
			(at -3.055 0.38 90)
			(layer "F.SilkS")
			(effects
				(font
					(size 0.7 0.7)
					(thickness 0.15)
				)
				(justify right top)
			)
		)
		(property "Value" "R_200k_0402"
			(at -1.011843 1.772046 90)
			(layer "F.Fab")
			(effects
				(font
					(size 0.7 0.7)
					(thickness 0.15)
				)
				(justify right top)
			)
		)
		(property "Datasheet" "https://www.bourns.com/docs/product-datasheets/cr.pdf"
			(at 0 0 90)
			(layer "F.Fab")
			(hide yes)
			(effects
				(font
					(size 1.27 1.27)
					(thickness 0.15)
				)
			)
		)
		(property "Description" "SMD Chip Resistor, 200 kohm, ± 1%, 62.5 mW, 0402 [1005 Metric], Thick Film, General Purpose"
			(at 0 0 90)
			(layer "F.Fab")
			(hide yes)
			(effects
				(font
					(size 1.27 1.27)
					(thickness 0.15)
				)
			)
		)
		(property "MPN" "CR0402-FX-2003GLF"
			(at 0 0 270)
			(unlocked yes)
			(layer "F.Fab")
			(hide yes)
			(effects
				(font
					(size 1 1)
					(thickness 0.15)
				)
			)
		)
		(property "Manufacturer" "Bourns"
			(at 0 0 270)
			(unlocked yes)
			(layer "F.Fab")
			(hide yes)
			(effects
				(font
					(size 1 1)
					(thickness 0.15)
				)
			)
		)
		(property "License" "Apache-2.0"
			(at 0 0 270)
			(unlocked yes)
			(layer "F.Fab")
			(hide yes)
			(effects
				(font
					(size 1 1)
					(thickness 0.15)
				)
			)
		)
		(property "Author" "Antmicro"
			(at 0 0 270)
			(unlocked yes)
			(layer "F.Fab")
			(hide yes)
			(effects
				(font
					(size 1 1)
					(thickness 0.15)
				)
			)
		)
		(property "Val" "200k"
			(at 0 0 270)
			(unlocked yes)
			(layer "F.Fab")
			(hide yes)
			(effects
				(font
					(size 1 1)
					(thickness 0.15)
				)
			)
		)
		(property "Tolerance" "1%"
			(at 0 0 270)
			(unlocked yes)
			(layer "F.Fab")
			(hide yes)
			(effects
				(font
					(size 1 1)
					(thickness 0.15)
				)
			)
		)
		(sheetname "/USB Hub/")
		(sheetfile "usb_hub.kicad_sch")
		(attr smd)
		(fp_poly
			(pts
				(xy -0.925 -0.47) (xy 0.925 -0.47) (xy 0.925 0.47) (xy -0.925 0.47)
			)
			(stroke
				(width 0.05)
				(type default)
			)
			(fill no)
			(layer "F.CrtYd")
		)
		(fp_poly
			(pts
				(xy -0.5 -0.25) (xy 0.5 -0.25) (xy 0.5 0.25) (xy -0.5 0.25)
			)
			(stroke
				(width 0.15)
				(type solid)
			)
			(fill no)
			(layer "F.Fab")
		)
		(fp_text user "License: Apache-2.0"
			(at -0.949999 5.169 90)
			(layer "F.Fab")
			(effects
				(font
					(size 0.7 0.7)
					(thickness 0.15)
				)
				(justify right top)
			)
		)
		(fp_text user "Author: Antmicro"
			(at -0.95 4.169 90)
			(layer "F.Fab")
			(effects
				(font
					(size 0.7 0.7)
					(thickness 0.15)
				)
				(justify right top)
			)
		)
		(fp_text user "${REFERENCE}"
			(at -0.95 3.168 90)
			(layer "F.Fab")
			(effects
				(font
					(size 0.7 0.7)
					(thickness 0.15)
				)
				(justify right top)
			)
		)
		(pad "1" smd roundrect
			(at -0.48 0 270)
			(size 0.59 0.64)
			(layers "F.Cu" "F.Mask" "F.Paste")
			(roundrect_rratio 0.25)
			(net 1 "GND")
			(pintype "passive")
		)
		(pad "2" smd roundrect
			(at 0.48 0 270)
			(size 0.59 0.64)
			(layers "F.Cu" "F.Mask" "F.Paste")
			(roundrect_rratio 0.25)
			(net 915 "/USB Hub/CFG_STRAP2")
			(pintype "passive")
		)
	)
	(footprint "antmicro-footprints:C_0805_2012Metric"
		(layer "F.Cu")
		(at 164.09 99.81 90)
		(descr "Capacitor SMD 0805")
		(tags "capacitor SMD 0805")
		(property "Reference" "C258"
			(at -4.595 0.345 90)
			(layer "F.SilkS")
			(effects
				(font
					(size 0.7 0.7)
					(thickness 0.15)
				)
				(justify left bottom)
			)
		)
		(property "Value" "C_22u_25V_0805"
			(at -2.055717 1.963152 90)
			(layer "F.Fab")
			(effects
				(font
					(size 0.7 0.7)
					(thickness 0.15)
				)
				(justify left bottom)
			)
		)
		(property "Datasheet" "https://product.samsungsem.com/mlcc/CL21A226MAYNNN.do"
			(at 0 0 90)
			(layer "F.Fab")
			(hide yes)
			(effects
				(font
					(size 1.27 1.27)
					(thickness 0.15)
				)
			)
		)
		(property "Description" "SMT Multilayer Ceramic Capacitor, 22uF, +/-20%, 25V, X5R, 0805 [2012 Metric]"
			(at 0 0 90)
			(layer "F.Fab")
			(hide yes)
			(effects
				(font
					(size 1.27 1.27)
					(thickness 0.15)
				)
			)
		)
		(property "MPN" "CL21A226MAYNNNE"
			(at 0 0 90)
			(unlocked yes)
			(layer "F.Fab")
			(hide yes)
			(effects
				(font
					(size 1 1)
					(thickness 0.15)
				)
			)
		)
		(property "Manufacturer" "Samsung Electro-Mechanics"
			(at 0 0 90)
			(unlocked yes)
			(layer "F.Fab")
			(hide yes)
			(effects
				(font
					(size 1 1)
					(thickness 0.15)
				)
			)
		)
		(property "License" "Apache-2.0"
			(at 0 0 90)
			(unlocked yes)
			(layer "F.Fab")
			(hide yes)
			(effects
				(font
					(size 1 1)
					(thickness 0.15)
				)
			)
		)
		(property "Author" "Antmicro"
			(at 0 0 90)
			(unlocked yes)
			(layer "F.Fab")
			(hide yes)
			(effects
				(font
					(size 1 1)
					(thickness 0.15)
				)
			)
		)
		(property "Val" "22u"
			(at 0 0 90)
			(unlocked yes)
			(layer "F.Fab")
			(hide yes)
			(effects
				(font
					(size 1 1)
					(thickness 0.15)
				)
			)
		)
		(property "Voltage" "25V"
			(at 0 0 90)
			(unlocked yes)
			(layer "F.Fab")
			(hide yes)
			(effects
				(font
					(size 1 1)
					(thickness 0.15)
				)
			)
		)
		(property "Dielectric" "X5R"
			(at 0 0 90)
			(unlocked yes)
			(layer "F.Fab")
			(hide yes)
			(effects
				(font
					(size 1 1)
					(thickness 0.15)
				)
			)
		)
		(property "Public" "False"
			(at 0 0 90)
			(unlocked yes)
			(layer "F.Fab")
			(hide yes)
			(effects
				(font
					(size 1 1)
					(thickness 0.15)
				)
			)
		)
		(component_classes
			(class "DCDC_SOM")
		)
		(sheetname "/DCDC/")
		(sheetfile "dcdc.kicad_sch")
		(attr smd)
		(fp_line
			(start -0.3 -0.7)
			(end 0.3 -0.7)
			(stroke
				(width 0.15)
				(type solid)
			)
			(layer "F.SilkS")
		)
		(fp_line
			(start -0.3 0.7)
			(end 0.3 0.7)
			(stroke
				(width 0.15)
				(type solid)
			)
			(layer "F.SilkS")
		)
		(fp_rect
			(start 1.95 -0.9)
			(end -1.95 0.9)
			(stroke
				(width 0.05)
				(type default)
			)
			(fill no)
			(layer "F.CrtYd")
		)
		(fp_rect
			(start -0.95 -0.675)
			(end 0.95 0.675)
			(stroke
				(width 0.15)
				(type solid)
			)
			(fill no)
			(layer "F.Fab")
		)
		(fp_text user "License: Apache-2.0"
			(at -1.9 4.947 90)
			(layer "F.Fab")
			(effects
				(font
					(size 0.7 0.7)
					(thickness 0.15)
				)
				(justify left bottom)
			)
		)
		(fp_text user "Author: Antmicro"
			(at -1.9 5.947 90)
			(layer "F.Fab")
			(effects
				(font
					(size 0.7 0.7)
					(thickness 0.15)
				)
				(justify left bottom)
			)
		)
		(fp_text user "${REFERENCE}"
			(at -1.9 3.947 90)
			(layer "F.Fab")
			(effects
				(font
					(size 0.7 0.7)
					(thickness 0.15)
				)
				(justify left bottom)
			)
		)
		(pad "1" smd roundrect
			(at -1.1 0 90)
			(size 1.2 1.3)
			(layers "F.Cu" "F.Mask" "F.Paste")
			(roundrect_rratio 0.25)
			(net 1 "GND")
			(pintype "passive")
		)
		(pad "2" smd roundrect
			(at 1.1 0 90)
			(size 1.2 1.3)
			(layers "F.Cu" "F.Mask" "F.Paste")
			(roundrect_rratio 0.25)
			(net 903 "/DCDC/16V_OUT")
			(pintype "passive")
		)
	)
	(footprint "antmicro-footprints:C_0402_1005Metric"
		(layer "F.Cu")
		(at 184.019468 142.19 -90)
		(descr "Capacitor SMD 0402")
		(tags "capacitor SMD 0402")
		(property "Reference" "C54"
			(at -1.29 -0.680532 90)
			(layer "F.SilkS")
			(effects
				(font
					(size 0.7 0.7)
					(thickness 0.15)
				)
				(justify right top)
			)
		)
		(property "Value" "C_1u_0402"
			(at -1.022927 2.155213 90)
			(layer "F.Fab")
			(effects
				(font
					(size 0.7 0.7)
					(thickness 0.15)
				)
				(justify right top)
			)
		)
		(property "Datasheet" "https://product.tdk.com/en/search/capacitor/ceramic/mlcc/info?part_no=C1005X6S1A105K050BC"
			(at 0 0 90)
			(layer "F.Fab")
			(hide yes)
			(effects
				(font
					(size 1.27 1.27)
					(thickness 0.15)
				)
			)
		)
		(property "Description" "SMD Multilayer Ceramic Capacitor, 1 µF, 10 V, 0402 [1005 Metric], ± 10%, X6S, C"
			(at 0 0 90)
			(layer "F.Fab")
			(hide yes)
			(effects
				(font
					(size 1.27 1.27)
					(thickness 0.15)
				)
			)
		)
		(property "Manufacturer" "TDK"
			(at 0 0 270)
			(unlocked yes)
			(layer "F.Fab")
			(hide yes)
			(effects
				(font
					(size 1 1)
					(thickness 0.15)
				)
			)
		)
		(property "MPN" "C1005X6S1A105K050BC"
			(at 0 0 270)
			(unlocked yes)
			(layer "F.Fab")
			(hide yes)
			(effects
				(font
					(size 1 1)
					(thickness 0.15)
				)
			)
		)
		(property "Val" "1u"
			(at 0 0 270)
			(unlocked yes)
			(layer "F.Fab")
			(hide yes)
			(effects
				(font
					(size 1 1)
					(thickness 0.15)
				)
			)
		)
		(property "License" "Apache-2.0"
			(at 0 0 270)
			(unlocked yes)
			(layer "F.Fab")
			(hide yes)
			(effects
				(font
					(size 1 1)
					(thickness 0.15)
				)
			)
		)
		(property "Author" "Antmicro"
			(at 0 0 270)
			(unlocked yes)
			(layer "F.Fab")
			(hide yes)
			(effects
				(font
					(size 1 1)
					(thickness 0.15)
				)
			)
		)
		(property "Voltage" ""
			(at 0 0 270)
			(unlocked yes)
			(layer "F.Fab")
			(hide yes)
			(effects
				(font
					(size 1 1)
					(thickness 0.15)
				)
			)
		)
		(property "Dielectric" ""
			(at 0 0 270)
			(unlocked yes)
			(layer "F.Fab")
			(hide yes)
			(effects
				(font
					(size 1 1)
					(thickness 0.15)
				)
			)
		)
		(sheetname "/DCDC/")
		(sheetfile "dcdc.kicad_sch")
		(attr smd)
		(fp_rect
			(start -0.925 -0.47)
			(end 0.925 0.47)
			(stroke
				(width 0.05)
				(type default)
			)
			(fill no)
			(layer "F.CrtYd")
		)
		(fp_line
			(start -0.494 0.248)
			(end -0.494 -0.25)
			(stroke
				(width 0.15)
				(type solid)
			)
			(layer "F.Fab")
		)
		(fp_line
			(start 0.504 0.248)
			(end -0.494 0.248)
			(stroke
				(width 0.15)
				(type solid)
			)
			(layer "F.Fab")
		)
		(fp_line
			(start -0.494 -0.25)
			(end 0.504 -0.25)
			(stroke
				(width 0.15)
				(type solid)
			)
			(layer "F.Fab")
		)
		(fp_line
			(start 0.504 -0.25)
			(end 0.504 0.248)
			(stroke
				(width 0.15)
				(type solid)
			)
			(layer "F.Fab")
		)
		(fp_text user "${REFERENCE}"
			(at -0.939 4.599 90)
			(layer "F.Fab")
			(effects
				(font
					(size 0.7 0.7)
					(thickness 0.15)
				)
				(justify right top)
			)
		)
		(fp_text user "Author: Antmicro"
			(at -0.939 3.399 90)
			(layer "F.Fab")
			(effects
				(font
					(size 0.7 0.7)
					(thickness 0.15)
				)
				(justify right top)
			)
		)
		(fp_text user "License: Apache-2.0"
			(at -0.939 5.799 90)
			(layer "F.Fab")
			(effects
				(font
					(size 0.7 0.7)
					(thickness 0.15)
				)
				(justify right top)
			)
		)
		(pad "1" smd roundrect
			(at -0.48 0 270)
			(size 0.59 0.64)
			(layers "F.Cu" "F.Mask" "F.Paste")
			(roundrect_rratio 0.25)
			(net 1 "GND")
			(pintype "passive")
		)
		(pad "2" smd roundrect
			(at 0.48 0 270)
			(size 0.59 0.64)
			(layers "F.Cu" "F.Mask" "F.Paste")
			(roundrect_rratio 0.25)
			(net 20 "/DCDC/12V_VDD")
			(pintype "passive")
		)
	)
	(footprint "antmicro-footprints:R_0402_1005Metric"
		(layer "F.Cu")
		(at 190.3 122.6 90)
		(descr "Resistor SMD 0402")
		(tags "resistor SMD 0402")
		(property "Reference" "R378"
			(at 7.1 -2.4 90)
			(layer "F.SilkS")
			(effects
				(font
					(size 0.7 0.7)
					(thickness 0.15)
				)
				(justify left bottom)
			)
		)
		(property "Value" "R_0R_0402"
			(at -1.011843 1.772047 90)
			(layer "F.Fab")
			(effects
				(font
					(size 0.7 0.7)
					(thickness 0.15)
				)
				(justify left bottom)
			)
		)
		(property "Datasheet" "https://industrial.panasonic.com/cdbs/www-data/pdf/RDA0000/AOA0000C301.pdf"
			(at 0 0 90)
			(layer "F.Fab")
			(hide yes)
			(effects
				(font
					(size 1.27 1.27)
					(thickness 0.15)
				)
			)
		)
		(property "Description" "SMD Chip Resistor, Jumper, 0 ohm, 100 mW, 0402 [1005 Metric], Thick Film, General Purpose"
			(at 0 0 90)
			(layer "F.Fab")
			(hide yes)
			(effects
				(font
					(size 1.27 1.27)
					(thickness 0.15)
				)
			)
		)
		(property "MPN" "ERJ2GE0R00X"
			(at 0 0 90)
			(unlocked yes)
			(layer "F.Fab")
			(hide yes)
			(effects
				(font
					(size 1 1)
					(thickness 0.15)
				)
			)
		)
		(property "Manufacturer" "Panasonic"
			(at 0 0 90)
			(unlocked yes)
			(layer "F.Fab")
			(hide yes)
			(effects
				(font
					(size 1 1)
					(thickness 0.15)
				)
			)
		)
		(property "License" "Apache-2.0"
			(at 0 0 90)
			(unlocked yes)
			(layer "F.Fab")
			(hide yes)
			(effects
				(font
					(size 1 1)
					(thickness 0.15)
				)
			)
		)
		(property "Author" "Antmicro"
			(at 0 0 90)
			(unlocked yes)
			(layer "F.Fab")
			(hide yes)
			(effects
				(font
					(size 1 1)
					(thickness 0.15)
				)
			)
		)
		(property "Val" "0R"
			(at 0 0 90)
			(unlocked yes)
			(layer "F.Fab")
			(hide yes)
			(effects
				(font
					(size 1 1)
					(thickness 0.15)
				)
			)
		)
		(property "Tolerance" "~"
			(at 0 0 90)
			(unlocked yes)
			(layer "F.Fab")
			(hide yes)
			(effects
				(font
					(size 1 1)
					(thickness 0.15)
				)
			)
		)
		(property "Current" "1A"
			(at 0 0 90)
			(unlocked yes)
			(layer "F.Fab")
			(hide yes)
			(effects
				(font
					(size 1 1)
					(thickness 0.15)
				)
			)
		)
		(sheetname "/USB Hub/")
		(sheetfile "usb_hub.kicad_sch")
		(attr smd exclude_from_pos_files exclude_from_bom dnp)
		(fp_rect
			(start -0.925 -0.47)
			(end 0.925 0.47)
			(stroke
				(width 0.05)
				(type default)
			)
			(fill no)
			(layer "F.CrtYd")
		)
		(fp_rect
			(start -0.5 -0.25)
			(end 0.5 0.25)
			(stroke
				(width 0.15)
				(type solid)
			)
			(fill no)
			(layer "F.Fab")
		)
		(fp_text user "Author: Antmicro"
			(at -0.95 4.169 90)
			(layer "F.Fab")
			(effects
				(font
					(size 0.7 0.7)
					(thickness 0.15)
				)
				(justify left bottom)
			)
		)
		(fp_text user "License: Apache-2.0"
			(at -0.95 5.169 90)
			(layer "F.Fab")
			(effects
				(font
					(size 0.7 0.7)
					(thickness 0.15)
				)
				(justify left bottom)
			)
		)
		(fp_text user "${REFERENCE}"
			(at -0.95 3.168 90)
			(layer "F.Fab")
			(effects
				(font
					(size 0.7 0.7)
					(thickness 0.15)
				)
				(justify left bottom)
			)
		)
		(pad "1" smd roundrect
			(at -0.48 0 90)
			(size 0.59 0.64)
			(layers "F.Cu" "F.Mask" "F.Paste")
			(roundrect_rratio 0.25)
			(net 922 "/USB Hub/HUB_SPI_D1")
			(pintype "passive")
		)
		(pad "2" smd roundrect
			(at 0.48 0 90)
			(size 0.59 0.64)
			(layers "F.Cu" "F.Mask" "F.Paste")
			(roundrect_rratio 0.25)
			(net 926 "/USB Debug, PD/SPI_{HUB_DEBUG}.MOSI")
			(pintype "passive")
		)
	)
	(footprint "antmicro-footprints:R_0402_1005Metric"
		(layer "F.Cu")
		(at 88 60.5 180)
		(descr "Resistor SMD 0402")
		(tags "resistor SMD 0402")
		(property "Reference" "R289"
			(at 16.3 -8.8 0)
			(layer "F.SilkS")
			(effects
				(font
					(size 0.7 0.7)
					(thickness 0.15)
				)
				(justify right top)
			)
		)
		(property "Value" "R_10k_0402"
			(at -1.011843 1.772047 0)
			(layer "F.Fab")
			(effects
				(font
					(size 0.7 0.7)
					(thickness 0.15)
				)
				(justify right top)
			)
		)
		(property "Datasheet" "https://www.bourns.com/docs/product-datasheets/cr.pdf"
			(at 0 0 0)
			(layer "F.Fab")
			(hide yes)
			(effects
				(font
					(size 1.27 1.27)
					(thickness 0.15)
				)
			)
		)
		(property "Description" "SMD Chip Resistor, 10 kohm, ± 1%, 62.5 mW, 0402 [1005 Metric], Thick Film, General Purpose"
			(at 0 0 0)
			(layer "F.Fab")
			(hide yes)
			(effects
				(font
					(size 1.27 1.27)
					(thickness 0.15)
				)
			)
		)
		(property "MPN" "CR0402-FX-1002GLF"
			(at 0 0 180)
			(unlocked yes)
			(layer "F.Fab")
			(hide yes)
			(effects
				(font
					(size 1 1)
					(thickness 0.15)
				)
			)
		)
		(property "Manufacturer" "Bourns"
			(at 0 0 180)
			(unlocked yes)
			(layer "F.Fab")
			(hide yes)
			(effects
				(font
					(size 1 1)
					(thickness 0.15)
				)
			)
		)
		(property "License" "Apache-2.0"
			(at 0 0 180)
			(unlocked yes)
			(layer "F.Fab")
			(hide yes)
			(effects
				(font
					(size 1 1)
					(thickness 0.15)
				)
			)
		)
		(property "Author" "Antmicro"
			(at 0 0 180)
			(unlocked yes)
			(layer "F.Fab")
			(hide yes)
			(effects
				(font
					(size 1 1)
					(thickness 0.15)
				)
			)
		)
		(property "Val" "10k"
			(at 0 0 180)
			(unlocked yes)
			(layer "F.Fab")
			(hide yes)
			(effects
				(font
					(size 1 1)
					(thickness 0.15)
				)
			)
		)
		(property "Tolerance" "1%"
			(at 0 0 180)
			(unlocked yes)
			(layer "F.Fab")
			(hide yes)
			(effects
				(font
					(size 1 1)
					(thickness 0.15)
				)
			)
		)
		(property "Current" "1A"
			(at 0 0 180)
			(unlocked yes)
			(layer "F.Fab")
			(hide yes)
			(effects
				(font
					(size 1 1)
					(thickness 0.15)
				)
			)
		)
		(sheetname "/SoM_Power/")
		(sheetfile "som_power.kicad_sch")
		(attr smd exclude_from_pos_files exclude_from_bom dnp)
		(fp_rect
			(start -0.925 -0.47)
			(end 0.925 0.47)
			(stroke
				(width 0.05)
				(type default)
			)
			(fill no)
			(layer "F.CrtYd")
		)
		(fp_rect
			(start -0.5 -0.25)
			(end 0.5 0.25)
			(stroke
				(width 0.15)
				(type solid)
			)
			(fill no)
			(layer "F.Fab")
		)
		(fp_text user "License: Apache-2.0"
			(at -0.95 5.169 0)
			(layer "F.Fab")
			(effects
				(font
					(size 0.7 0.7)
					(thickness 0.15)
				)
				(justify right top)
			)
		)
		(fp_text user "${REFERENCE}"
			(at -0.95 3.168 0)
			(layer "F.Fab")
			(effects
				(font
					(size 0.7 0.7)
					(thickness 0.15)
				)
				(justify right top)
			)
		)
		(fp_text user "Author: Antmicro"
			(at -0.95 4.169 0)
			(layer "F.Fab")
			(effects
				(font
					(size 0.7 0.7)
					(thickness 0.15)
				)
				(justify right top)
			)
		)
		(pad "1" smd roundrect
			(at -0.48 0 180)
			(size 0.59 0.64)
			(layers "F.Cu" "F.Mask" "F.Paste")
			(roundrect_rratio 0.25)
			(net 1027 "Net-(U70-~{CLR})")
			(pintype "passive")
		)
		(pad "2" smd roundrect
			(at 0.48 0 180)
			(size 0.59 0.64)
			(layers "F.Cu" "F.Mask" "F.Paste")
			(roundrect_rratio 0.25)
			(net 491 "+5V_AON")
			(pintype "passive")
		)
	)
	(footprint "antmicro-footprints:C_0603_1608Metric_EIA"
		(layer "F.Cu")
		(at 173.5 130.18 -90)
		(descr "Capacitor SMD 0603, IPC-7351 Density Level A")
		(tags "Capacitor 0603")
		(property "Reference" "C67"
			(at -4.28 9 90)
			(layer "F.SilkS")
			(effects
				(font
					(size 0.7 0.7)
					(thickness 0.15)
				)
				(justify right top)
			)
		)
		(property "Value" "C_22u_16V_0603"
			(at -1.42757 1.770288 90)
			(layer "F.Fab")
			(effects
				(font
					(size 0.7 0.7)
					(thickness 0.15)
				)
				(justify right top)
			)
		)
		(property "Datasheet" "https://product.samsungsem.com/mlcc/CL10A226MO7JZN.do"
			(at 0 0 90)
			(layer "F.Fab")
			(hide yes)
			(effects
				(font
					(size 1.27 1.27)
					(thickness 0.15)
				)
			)
		)
		(property "Description" "SMD Multilayer Ceramic Capacitor"
			(at 0 0 90)
			(layer "F.Fab")
			(hide yes)
			(effects
				(font
					(size 1.27 1.27)
					(thickness 0.15)
				)
			)
		)
		(property "Manufacturer" "Samsung Electro-Mechanics"
			(at 0 0 270)
			(unlocked yes)
			(layer "F.Fab")
			(hide yes)
			(effects
				(font
					(size 1 1)
					(thickness 0.15)
				)
			)
		)
		(property "MPN" "CL10A226MO7JZNC"
			(at 0 0 270)
			(unlocked yes)
			(layer "F.Fab")
			(hide yes)
			(effects
				(font
					(size 1 1)
					(thickness 0.15)
				)
			)
		)
		(property "Val" "22u"
			(at 0 0 270)
			(unlocked yes)
			(layer "F.Fab")
			(hide yes)
			(effects
				(font
					(size 1 1)
					(thickness 0.15)
				)
			)
		)
		(property "License" "Apache-2.0"
			(at 0 0 270)
			(unlocked yes)
			(layer "F.Fab")
			(hide yes)
			(effects
				(font
					(size 1 1)
					(thickness 0.15)
				)
			)
		)
		(property "Author" "Antmicro"
			(at 0 0 270)
			(unlocked yes)
			(layer "F.Fab")
			(hide yes)
			(effects
				(font
					(size 1 1)
					(thickness 0.15)
				)
			)
		)
		(property "Voltage" "16V"
			(at 0 0 270)
			(unlocked yes)
			(layer "F.Fab")
			(hide yes)
			(effects
				(font
					(size 1 1)
					(thickness 0.15)
				)
			)
		)
		(property "Dielectric" ""
			(at 0 0 270)
			(unlocked yes)
			(layer "F.Fab")
			(hide yes)
			(effects
				(font
					(size 1 1)
					(thickness 0.15)
				)
			)
		)
		(sheetname "/DCDC/")
		(sheetfile "dcdc.kicad_sch")
		(attr smd)
		(fp_line
			(start -0.15 0.55)
			(end 0.15 0.55)
			(stroke
				(width 0.15)
				(type solid)
			)
			(layer "F.SilkS")
		)
		(fp_line
			(start -0.15 -0.55)
			(end 0.15 -0.55)
			(stroke
				(width 0.15)
				(type solid)
			)
			(layer "F.SilkS")
		)
		(fp_rect
			(start -1.25 -0.65)
			(end 1.25 0.65)
			(stroke
				(width 0.05)
				(type solid)
			)
			(fill no)
			(layer "F.CrtYd")
		)
		(fp_rect
			(start -0.8 -0.45)
			(end 0.8 0.45)
			(stroke
				(width 0.15)
				(type solid)
			)
			(fill no)
			(layer "F.Fab")
		)
		(fp_text user "License: Apache-2.0"
			(at -1.682 5.895 90)
			(layer "F.Fab")
			(effects
				(font
					(size 0.7 0.7)
					(thickness 0.15)
				)
				(justify right top)
			)
		)
		(fp_text user "Author: Antmicro"
			(at -1.682 4.894 90)
			(layer "F.Fab")
			(effects
				(font
					(size 0.7 0.7)
					(thickness 0.15)
				)
				(justify right top)
			)
		)
		(fp_text user "${REFERENCE}"
			(at -1.682 3.895 90)
			(layer "F.Fab")
			(effects
				(font
					(size 0.7 0.7)
					(thickness 0.15)
				)
				(justify right top)
			)
		)
		(pad "1" smd roundrect
			(at -0.7 0 270)
			(size 0.8 1.1)
			(layers "F.Cu" "F.Mask" "F.Paste")
			(roundrect_rratio 0.2)
			(net 1 "GND")
			(pintype "passive")
		)
		(pad "2" smd roundrect
			(at 0.7 0 270)
			(size 0.8 1.1)
			(layers "F.Cu" "F.Mask" "F.Paste")
			(roundrect_rratio 0.2)
			(net 567 "/DCDC/3V3_OUT")
			(pintype "passive")
		)
	)
	(footprint "antmicro-footprints:Fiducial_1mm_Mask3mm"
		(layer "F.Cu")
		(at 211.23 58.44)
		(descr "Circular Fiducial, 1.5mm bare copper, 3mm soldermask opening")
		(tags "fiducial")
		(property "Reference" "FD4"
			(at -3.06 1.65 0)
			(layer "F.SilkS")
			(effects
				(font
					(size 0.7 0.7)
					(thickness 0.15)
				)
				(justify left bottom)
			)
		)
		(property "Value" "Fiducial_1mm_Mask3mm"
			(at 0 2.603 0)
			(layer "F.Fab")
			(effects
				(font
					(size 0.7 0.7)
					(thickness 0.15)
				)
				(justify left bottom)
			)
		)
		(property "Description" "Fiducial mask"
			(at 0 0 0)
			(layer "F.Fab")
			(hide yes)
			(effects
				(font
					(size 1.27 1.27)
					(thickness 0.15)
				)
			)
		)
		(property "Author" "Antmicro"
			(at 0 0 0)
			(unlocked yes)
			(layer "F.Fab")
			(hide yes)
			(effects
				(font
					(size 1 1)
					(thickness 0.15)
				)
			)
		)
		(property "License" "Apache-2.0"
			(at 0 0 0)
			(unlocked yes)
			(layer "F.Fab")
			(hide yes)
			(effects
				(font
					(size 1 1)
					(thickness 0.15)
				)
			)
		)
		(sheetname "/")
		(sheetfile "jetson-agx-thor-baseboard.kicad_sch")
		(attr exclude_from_pos_files exclude_from_bom)
		(fp_circle
			(center 0 0)
			(end 1.5 0)
			(stroke
				(width 0.05)
				(type solid)
			)
			(fill no)
			(layer "F.CrtYd")
		)
		(fp_circle
			(center 0 0)
			(end 1.5 0)
			(stroke
				(width 0.15)
				(type solid)
			)
			(fill no)
			(layer "F.Fab")
		)
		(fp_text user "Author: Antmicro"
			(at -1.25 5.803 0)
			(layer "F.Fab")
			(effects
				(font
					(size 0.7 0.7)
					(thickness 0.15)
				)
				(justify left bottom)
			)
		)
		(fp_text user "License: Apache-2.0"
			(at -1.25 7.003 0)
			(layer "F.Fab")
			(effects
				(font
					(size 0.7 0.7)
					(thickness 0.15)
				)
				(justify left bottom)
			)
		)
		(fp_text user "${REFERENCE}"
			(at -1.25 4.603 0)
			(layer "F.Fab")
			(effects
				(font
					(size 0.7 0.7)
					(thickness 0.15)
				)
				(justify left bottom)
			)
		)
		(pad "" smd circle
			(at 0 0)
			(size 1 1)
			(layers "F.Cu" "F.Mask")
			(solder_mask_margin 1)
			(clearance 1)
		)
	)
	(footprint "antmicro-footprints:R_0402_1005Metric"
		(layer "F.Cu")
		(at 170.304468 133.12 90)
		(descr "Resistor SMD 0402")
		(tags "resistor SMD 0402")
		(property "Reference" "R369"
			(at -1.28 3.495532 90)
			(layer "F.SilkS")
			(effects
				(font
					(size 0.7 0.7)
					(thickness 0.15)
				)
				(justify left bottom)
			)
		)
		(property "Value" "R_27R_0402"
			(at -1.011843 1.772047 90)
			(layer "F.Fab")
			(effects
				(font
					(size 0.7 0.7)
					(thickness 0.15)
				)
				(justify left bottom)
			)
		)
		(property "Datasheet" "https://www.bourns.com/docs/product-datasheets/cr.pdf"
			(at 0 0 90)
			(layer "F.Fab")
			(hide yes)
			(effects
				(font
					(size 1.27 1.27)
					(thickness 0.15)
				)
			)
		)
		(property "Description" "SMD Chip Resistor, 27 ohm, ± 1%, 63 mW, 0402 [1005 Metric], Thick Film, General Purpose"
			(at 0 0 90)
			(layer "F.Fab")
			(hide yes)
			(effects
				(font
					(size 1.27 1.27)
					(thickness 0.15)
				)
			)
		)
		(property "Manufacturer" "Bourns"
			(at 0 0 90)
			(unlocked yes)
			(layer "F.Fab")
			(hide yes)
			(effects
				(font
					(size 1 1)
					(thickness 0.15)
				)
			)
		)
		(property "MPN" "CR0402-FX-27R0GLF"
			(at 0 0 90)
			(unlocked yes)
			(layer "F.Fab")
			(hide yes)
			(effects
				(font
					(size 1 1)
					(thickness 0.15)
				)
			)
		)
		(property "Val" "27R"
			(at 0 0 90)
			(unlocked yes)
			(layer "F.Fab")
			(hide yes)
			(effects
				(font
					(size 1 1)
					(thickness 0.15)
				)
			)
		)
		(property "License" "Apache-2.0"
			(at 0 0 90)
			(unlocked yes)
			(layer "F.Fab")
			(hide yes)
			(effects
				(font
					(size 1 1)
					(thickness 0.15)
				)
			)
		)
		(property "Author" "Antmicro"
			(at 0 0 90)
			(unlocked yes)
			(layer "F.Fab")
			(hide yes)
			(effects
				(font
					(size 1 1)
					(thickness 0.15)
				)
			)
		)
		(property "Tolerance" "1%"
			(at 0 0 90)
			(unlocked yes)
			(layer "F.Fab")
			(hide yes)
			(effects
				(font
					(size 1 1)
					(thickness 0.15)
				)
			)
		)
		(sheetname "/DCDC/")
		(sheetfile "dcdc.kicad_sch")
		(attr smd)
		(fp_rect
			(start -0.925 -0.47)
			(end 0.925 0.47)
			(stroke
				(width 0.05)
				(type default)
			)
			(fill no)
			(layer "F.CrtYd")
		)
		(fp_rect
			(start -0.5 -0.25)
			(end 0.5 0.25)
			(stroke
				(width 0.15)
				(type solid)
			)
			(fill no)
			(layer "F.Fab")
		)
		(fp_text user "License: Apache-2.0"
			(at -0.95 5.169 90)
			(layer "F.Fab")
			(effects
				(font
					(size 0.7 0.7)
					(thickness 0.15)
				)
				(justify left bottom)
			)
		)
		(fp_text user "Author: Antmicro"
			(at -0.95 4.169 90)
			(layer "F.Fab")
			(effects
				(font
					(size 0.7 0.7)
					(thickness 0.15)
				)
				(justify left bottom)
			)
		)
		(fp_text user "${REFERENCE}"
			(at -0.95 3.168 90)
			(layer "F.Fab")
			(effects
				(font
					(size 0.7 0.7)
					(thickness 0.15)
				)
				(justify left bottom)
			)
		)
		(pad "1" smd roundrect
			(at -0.48 0 90)
			(size 0.59 0.64)
			(layers "F.Cu" "F.Mask" "F.Paste")
			(roundrect_rratio 0.25)
			(net 1162 "Net-(U60-IN-)")
			(pintype "passive")
		)
		(pad "2" smd roundrect
			(at 0.48 0 90)
			(size 0.59 0.64)
			(layers "F.Cu" "F.Mask" "F.Paste")
			(roundrect_rratio 0.25)
			(net 2 "+3V3")
			(pintype "passive")
		)
	)
	(footprint "antmicro-footprints:R_0402_1005Metric"
		(layer "F.Cu")
		(at 183.2 107)
		(descr "Resistor SMD 0402")
		(tags "resistor SMD 0402")
		(property "Reference" "R53"
			(at 0.92 0.48 0)
			(layer "F.SilkS")
			(effects
				(font
					(size 0.7 0.7)
					(thickness 0.15)
				)
				(justify left bottom)
			)
		)
		(property "Value" "R_10k_0402"
			(at -1.011843 1.772047 0)
			(layer "F.Fab")
			(effects
				(font
					(size 0.7 0.7)
					(thickness 0.15)
				)
				(justify left bottom)
			)
		)
		(property "Datasheet" "https://www.bourns.com/docs/product-datasheets/cr.pdf"
			(at 0 0 0)
			(layer "F.Fab")
			(hide yes)
			(effects
				(font
					(size 1.27 1.27)
					(thickness 0.15)
				)
			)
		)
		(property "Description" "SMD Chip Resistor, 10 kohm, ± 1%, 62.5 mW, 0402 [1005 Metric], Thick Film, General Purpose"
			(at 0 0 0)
			(layer "F.Fab")
			(hide yes)
			(effects
				(font
					(size 1.27 1.27)
					(thickness 0.15)
				)
			)
		)
		(property "MPN" "CR0402-FX-1002GLF"
			(at 0 0 0)
			(unlocked yes)
			(layer "F.Fab")
			(hide yes)
			(effects
				(font
					(size 1 1)
					(thickness 0.15)
				)
			)
		)
		(property "Manufacturer" "Bourns"
			(at 0 0 0)
			(unlocked yes)
			(layer "F.Fab")
			(hide yes)
			(effects
				(font
					(size 1 1)
					(thickness 0.15)
				)
			)
		)
		(property "License" "Apache-2.0"
			(at 0 0 0)
			(unlocked yes)
			(layer "F.Fab")
			(hide yes)
			(effects
				(font
					(size 1 1)
					(thickness 0.15)
				)
			)
		)
		(property "Author" "Antmicro"
			(at 0 0 0)
			(unlocked yes)
			(layer "F.Fab")
			(hide yes)
			(effects
				(font
					(size 1 1)
					(thickness 0.15)
				)
			)
		)
		(property "Val" "10k"
			(at 0 0 0)
			(unlocked yes)
			(layer "F.Fab")
			(hide yes)
			(effects
				(font
					(size 1 1)
					(thickness 0.15)
				)
			)
		)
		(property "Tolerance" "1%"
			(at 0 0 0)
			(unlocked yes)
			(layer "F.Fab")
			(hide yes)
			(effects
				(font
					(size 1 1)
					(thickness 0.15)
				)
			)
		)
		(sheetname "/DCDC/")
		(sheetfile "dcdc.kicad_sch")
		(attr smd)
		(fp_rect
			(start -0.925 -0.47)
			(end 0.925 0.47)
			(stroke
				(width 0.05)
				(type default)
			)
			(fill no)
			(layer "F.CrtYd")
		)
		(fp_rect
			(start -0.5 -0.25)
			(end 0.5 0.25)
			(stroke
				(width 0.15)
				(type solid)
			)
			(fill no)
			(layer "F.Fab")
		)
		(fp_text user "Author: Antmicro"
			(at -0.95 4.169 0)
			(layer "F.Fab")
			(effects
				(font
					(size 0.7 0.7)
					(thickness 0.15)
				)
				(justify left bottom)
			)
		)
		(fp_text user "License: Apache-2.0"
			(at -0.95 5.169 0)
			(layer "F.Fab")
			(effects
				(font
					(size 0.7 0.7)
					(thickness 0.15)
				)
				(justify left bottom)
			)
		)
		(fp_text user "${REFERENCE}"
			(at -0.95 3.168 0)
			(layer "F.Fab")
			(effects
				(font
					(size 0.7 0.7)
					(thickness 0.15)
				)
				(justify left bottom)
			)
		)
		(pad "1" smd roundrect
			(at -0.48 0)
			(size 0.59 0.64)
			(layers "F.Cu" "F.Mask" "F.Paste")
			(roundrect_rratio 0.25)
			(net 1 "GND")
			(pintype "passive")
		)
		(pad "2" smd roundrect
			(at 0.48 0)
			(size 0.59 0.64)
			(layers "F.Cu" "F.Mask" "F.Paste")
			(roundrect_rratio 0.25)
			(net 1217 "/DCDC/5V_FB")
			(pintype "passive")
		)
	)
	(footprint "antmicro-footprints:C_0805_2012Metric"
		(layer "F.Cu")
		(at 171.35 89.11 90)
		(descr "Capacitor SMD 0805")
		(tags "capacitor SMD 0805")
		(property "Reference" "C241"
			(at -1.69 -4.74 90)
			(layer "F.SilkS")
			(effects
				(font
					(size 0.7 0.7)
					(thickness 0.15)
				)
				(justify left bottom)
			)
		)
		(property "Value" "C_22u_25V_0805"
			(at -2.055717 1.963152 90)
			(layer "F.Fab")
			(effects
				(font
					(size 0.7 0.7)
					(thickness 0.15)
				)
				(justify left bottom)
			)
		)
		(property "Datasheet" "https://product.samsungsem.com/mlcc/CL21A226MAYNNN.do"
			(at 0 0 90)
			(layer "F.Fab")
			(hide yes)
			(effects
				(font
					(size 1.27 1.27)
					(thickness 0.15)
				)
			)
		)
		(property "Description" "SMT Multilayer Ceramic Capacitor, 22uF, +/-20%, 25V, X5R, 0805 [2012 Metric]"
			(at 0 0 90)
			(layer "F.Fab")
			(hide yes)
			(effects
				(font
					(size 1.27 1.27)
					(thickness 0.15)
				)
			)
		)
		(property "MPN" "CL21A226MAYNNNE"
			(at 0 0 90)
			(unlocked yes)
			(layer "F.Fab")
			(hide yes)
			(effects
				(font
					(size 1 1)
					(thickness 0.15)
				)
			)
		)
		(property "Manufacturer" "Samsung Electro-Mechanics"
			(at 0 0 90)
			(unlocked yes)
			(layer "F.Fab")
			(hide yes)
			(effects
				(font
					(size 1 1)
					(thickness 0.15)
				)
			)
		)
		(property "License" "Apache-2.0"
			(at 0 0 90)
			(unlocked yes)
			(layer "F.Fab")
			(hide yes)
			(effects
				(font
					(size 1 1)
					(thickness 0.15)
				)
			)
		)
		(property "Author" "Antmicro"
			(at 0 0 90)
			(unlocked yes)
			(layer "F.Fab")
			(hide yes)
			(effects
				(font
					(size 1 1)
					(thickness 0.15)
				)
			)
		)
		(property "Val" "22u"
			(at 0 0 90)
			(unlocked yes)
			(layer "F.Fab")
			(hide yes)
			(effects
				(font
					(size 1 1)
					(thickness 0.15)
				)
			)
		)
		(property "Voltage" "25V"
			(at 0 0 90)
			(unlocked yes)
			(layer "F.Fab")
			(hide yes)
			(effects
				(font
					(size 1 1)
					(thickness 0.15)
				)
			)
		)
		(property "Dielectric" "X5R"
			(at 0 0 90)
			(unlocked yes)
			(layer "F.Fab")
			(hide yes)
			(effects
				(font
					(size 1 1)
					(thickness 0.15)
				)
			)
		)
		(property "Public" "False"
			(at 0 0 90)
			(unlocked yes)
			(layer "F.Fab")
			(hide yes)
			(effects
				(font
					(size 1 1)
					(thickness 0.15)
				)
			)
		)
		(component_classes
			(class "DCDC_SOM")
		)
		(sheetname "/DCDC/")
		(sheetfile "dcdc.kicad_sch")
		(attr smd)
		(fp_line
			(start -0.3 -0.7)
			(end 0.3 -0.7)
			(stroke
				(width 0.15)
				(type solid)
			)
			(layer "F.SilkS")
		)
		(fp_line
			(start -0.3 0.7)
			(end 0.3 0.7)
			(stroke
				(width 0.15)
				(type solid)
			)
			(layer "F.SilkS")
		)
		(fp_rect
			(start 1.95 -0.9)
			(end -1.95 0.9)
			(stroke
				(width 0.05)
				(type default)
			)
			(fill no)
			(layer "F.CrtYd")
		)
		(fp_rect
			(start -0.95 -0.675)
			(end 0.95 0.675)
			(stroke
				(width 0.15)
				(type solid)
			)
			(fill no)
			(layer "F.Fab")
		)
		(fp_text user "Author: Antmicro"
			(at -1.9 5.947 90)
			(layer "F.Fab")
			(effects
				(font
					(size 0.7 0.7)
					(thickness 0.15)
				)
				(justify left bottom)
			)
		)
		(fp_text user "License: Apache-2.0"
			(at -1.9 4.947 90)
			(layer "F.Fab")
			(effects
				(font
					(size 0.7 0.7)
					(thickness 0.15)
				)
				(justify left bottom)
			)
		)
		(fp_text user "${REFERENCE}"
			(at -1.9 3.947 90)
			(layer "F.Fab")
			(effects
				(font
					(size 0.7 0.7)
					(thickness 0.15)
				)
				(justify left bottom)
			)
		)
		(pad "1" smd roundrect
			(at -1.1 0 90)
			(size 1.2 1.3)
			(layers "F.Cu" "F.Mask" "F.Paste")
			(roundrect_rratio 0.25)
			(net 1 "GND")
			(pintype "passive")
		)
		(pad "2" smd roundrect
			(at 1.1 0 90)
			(size 1.2 1.3)
			(layers "F.Cu" "F.Mask" "F.Paste")
			(roundrect_rratio 0.25)
			(net 13 "VCC")
			(pintype "passive")
		)
	)
	(footprint "antmicro-footprints:C_0402_1005Metric"
		(layer "F.Cu")
		(at 176.63 70.39 -90)
		(descr "Capacitor SMD 0402")
		(tags "capacitor SMD 0402")
		(property "Reference" "C278"
			(at -3.64 0.35 90)
			(layer "F.SilkS")
			(effects
				(font
					(size 0.7 0.7)
					(thickness 0.15)
				)
				(justify right top)
			)
		)
		(property "Value" "C_100n_0402"
			(at -1.022927 2.155213 90)
			(layer "F.Fab")
			(effects
				(font
					(size 0.7 0.7)
					(thickness 0.15)
				)
				(justify right top)
			)
		)
		(property "Datasheet" "https://www.murata.com/products/productdetail?partno=GRM155R61H104KE14%23"
			(at 0 0 90)
			(layer "F.Fab")
			(hide yes)
			(effects
				(font
					(size 1.27 1.27)
					(thickness 0.15)
				)
			)
		)
		(property "Description" "SMD Multilayer Ceramic Capacitor, 0.1 µF, 50 V, 0402 [1005 Metric], ± 10%, X5R, GRM Series"
			(at 0 0 90)
			(layer "F.Fab")
			(hide yes)
			(effects
				(font
					(size 1.27 1.27)
					(thickness 0.15)
				)
			)
		)
		(property "Manufacturer" "Murata"
			(at 0 0 270)
			(unlocked yes)
			(layer "F.Fab")
			(hide yes)
			(effects
				(font
					(size 1 1)
					(thickness 0.15)
				)
			)
		)
		(property "MPN" "GRM155R61H104KE14D"
			(at 0 0 270)
			(unlocked yes)
			(layer "F.Fab")
			(hide yes)
			(effects
				(font
					(size 1 1)
					(thickness 0.15)
				)
			)
		)
		(property "Val" "100n"
			(at 0 0 270)
			(unlocked yes)
			(layer "F.Fab")
			(hide yes)
			(effects
				(font
					(size 1 1)
					(thickness 0.15)
				)
			)
		)
		(property "License" "Apache-2.0"
			(at 0 0 270)
			(unlocked yes)
			(layer "F.Fab")
			(hide yes)
			(effects
				(font
					(size 1 1)
					(thickness 0.15)
				)
			)
		)
		(property "Author" "Antmicro"
			(at 0 0 270)
			(unlocked yes)
			(layer "F.Fab")
			(hide yes)
			(effects
				(font
					(size 1 1)
					(thickness 0.15)
				)
			)
		)
		(property "Voltage" "50V"
			(at 0 0 270)
			(unlocked yes)
			(layer "F.Fab")
			(hide yes)
			(effects
				(font
					(size 1 1)
					(thickness 0.15)
				)
			)
		)
		(property "Dielectric" "X5R"
			(at 0 0 270)
			(unlocked yes)
			(layer "F.Fab")
			(hide yes)
			(effects
				(font
					(size 1 1)
					(thickness 0.15)
				)
			)
		)
		(component_classes
			(class "DCDC_20V")
		)
		(sheetname "/DCDC/")
		(sheetfile "dcdc.kicad_sch")
		(attr smd)
		(fp_rect
			(start -0.925 -0.47)
			(end 0.925 0.47)
			(stroke
				(width 0.05)
				(type default)
			)
			(fill no)
			(layer "F.CrtYd")
		)
		(fp_line
			(start -0.494 0.248)
			(end -0.494 -0.25)
			(stroke
				(width 0.15)
				(type solid)
			)
			(layer "F.Fab")
		)
		(fp_line
			(start 0.504 0.248)
			(end -0.494 0.248)
			(stroke
				(width 0.15)
				(type solid)
			)
			(layer "F.Fab")
		)
		(fp_line
			(start -0.494 -0.25)
			(end 0.504 -0.25)
			(stroke
				(width 0.15)
				(type solid)
			)
			(layer "F.Fab")
		)
		(fp_line
			(start 0.504 -0.25)
			(end 0.504 0.248)
			(stroke
				(width 0.15)
				(type solid)
			)
			(layer "F.Fab")
		)
		(fp_text user "Author: Antmicro"
			(at -0.939 3.399 90)
			(layer "F.Fab")
			(effects
				(font
					(size 0.7 0.7)
					(thickness 0.15)
				)
				(justify right top)
			)
		)
		(fp_text user "${REFERENCE}"
			(at -0.939 4.599 90)
			(layer "F.Fab")
			(effects
				(font
					(size 0.7 0.7)
					(thickness 0.15)
				)
				(justify right top)
			)
		)
		(fp_text user "License: Apache-2.0"
			(at -0.939 5.799 90)
			(layer "F.Fab")
			(effects
				(font
					(size 0.7 0.7)
					(thickness 0.15)
				)
				(justify right top)
			)
		)
		(pad "1" smd roundrect
			(at -0.48 0 270)
			(size 0.59 0.64)
			(layers "F.Cu" "F.Mask" "F.Paste")
			(roundrect_rratio 0.25)
			(net 13 "VCC")
			(pintype "passive")
		)
		(pad "2" smd roundrect
			(at 0.48 0 270)
			(size 0.59 0.64)
			(layers "F.Cu" "F.Mask" "F.Paste")
			(roundrect_rratio 0.25)
			(net 1 "GND")
			(pintype "passive")
		)
	)
	(footprint "antmicro-footprints:R_0402_1005Metric"
		(layer "F.Cu")
		(at 213.805 95.4 -90)
		(descr "Resistor SMD 0402")
		(tags "resistor SMD 0402")
		(property "Reference" "R116"
			(at -1.6 -1.595 90)
			(layer "F.SilkS")
			(effects
				(font
					(size 0.7 0.7)
					(thickness 0.15)
				)
				(justify right top)
			)
		)
		(property "Value" "R_100k_0402"
			(at -1.011843 1.772047 90)
			(layer "F.Fab")
			(effects
				(font
					(size 0.7 0.7)
					(thickness 0.15)
				)
				(justify right top)
			)
		)
		(property "Datasheet" "https://www.bourns.com/docs/product-datasheets/cr.pdf"
			(at 0 0 90)
			(layer "F.Fab")
			(hide yes)
			(effects
				(font
					(size 1.27 1.27)
					(thickness 0.15)
				)
			)
		)
		(property "Description" "SMD Chip Resistor, 100 kohm, ± 1%, 62.5 mW, 0402 [1005 Metric], Thick Film, General Purpose"
			(at 0 0 90)
			(layer "F.Fab")
			(hide yes)
			(effects
				(font
					(size 1.27 1.27)
					(thickness 0.15)
				)
			)
		)
		(property "Manufacturer" "Bourns"
			(at 0 0 270)
			(unlocked yes)
			(layer "F.Fab")
			(hide yes)
			(effects
				(font
					(size 1 1)
					(thickness 0.15)
				)
			)
		)
		(property "MPN" "CR0402-FX-1003GLF"
			(at 0 0 270)
			(unlocked yes)
			(layer "F.Fab")
			(hide yes)
			(effects
				(font
					(size 1 1)
					(thickness 0.15)
				)
			)
		)
		(property "Val" "100k"
			(at 0 0 270)
			(unlocked yes)
			(layer "F.Fab")
			(hide yes)
			(effects
				(font
					(size 1 1)
					(thickness 0.15)
				)
			)
		)
		(property "License" "Apache-2.0"
			(at 0 0 270)
			(unlocked yes)
			(layer "F.Fab")
			(hide yes)
			(effects
				(font
					(size 1 1)
					(thickness 0.15)
				)
			)
		)
		(property "Author" "Antmicro"
			(at 0 0 270)
			(unlocked yes)
			(layer "F.Fab")
			(hide yes)
			(effects
				(font
					(size 1 1)
					(thickness 0.15)
				)
			)
		)
		(property "Tolerance" "1%"
			(at 0 0 270)
			(unlocked yes)
			(layer "F.Fab")
			(hide yes)
			(effects
				(font
					(size 1 1)
					(thickness 0.15)
				)
			)
		)
		(sheetname "/USB DP Alt mode/")
		(sheetfile "usb_dp.kicad_sch")
		(attr smd)
		(fp_rect
			(start -0.925 -0.47)
			(end 0.925 0.47)
			(stroke
				(width 0.05)
				(type default)
			)
			(fill no)
			(layer "F.CrtYd")
		)
		(fp_rect
			(start -0.5 -0.25)
			(end 0.5 0.25)
			(stroke
				(width 0.15)
				(type solid)
			)
			(fill no)
			(layer "F.Fab")
		)
		(fp_text user "License: Apache-2.0"
			(at -0.95 5.169 90)
			(layer "F.Fab")
			(effects
				(font
					(size 0.7 0.7)
					(thickness 0.15)
				)
				(justify right top)
			)
		)
		(fp_text user "${REFERENCE}"
			(at -0.95 3.168 90)
			(layer "F.Fab")
			(effects
				(font
					(size 0.7 0.7)
					(thickness 0.15)
				)
				(justify right top)
			)
		)
		(fp_text user "Author: Antmicro"
			(at -0.95 4.169 90)
			(layer "F.Fab")
			(effects
				(font
					(size 0.7 0.7)
					(thickness 0.15)
				)
				(justify right top)
			)
		)
		(pad "1" smd roundrect
			(at -0.48 0 270)
			(size 0.59 0.64)
			(layers "F.Cu" "F.Mask" "F.Paste")
			(roundrect_rratio 0.25)
			(net 607 "/SoM_IO2/DP0.AUX-")
			(pintype "passive")
		)
		(pad "2" smd roundrect
			(at 0.48 0 270)
			(size 0.59 0.64)
			(layers "F.Cu" "F.Mask" "F.Paste")
			(roundrect_rratio 0.25)
			(net 2 "+3V3")
			(pintype "passive")
		)
	)
	(footprint "antmicro-footprints:R_0402_1005Metric"
		(layer "F.Cu")
		(at 216.2 78)
		(descr "Resistor SMD 0402")
		(tags "resistor SMD 0402")
		(property "Reference" "R124"
			(at 1.3 0.6 180)
			(layer "F.SilkS")
			(effects
				(font
					(size 0.7 0.7)
					(thickness 0.15)
				)
				(justify right top)
			)
		)
		(property "Value" "R_0R_0402"
			(at -1.011843 1.772047 180)
			(layer "F.Fab")
			(effects
				(font
					(size 0.7 0.7)
					(thickness 0.15)
				)
				(justify right top)
			)
		)
		(property "Datasheet" "https://industrial.panasonic.com/cdbs/www-data/pdf/RDA0000/AOA0000C301.pdf"
			(at 0 0 180)
			(layer "F.Fab")
			(hide yes)
			(effects
				(font
					(size 1.27 1.27)
					(thickness 0.15)
				)
			)
		)
		(property "Description" "SMD Chip Resistor, Jumper, 0 ohm, 100 mW, 0402 [1005 Metric], Thick Film, General Purpose"
			(at 0 0 180)
			(layer "F.Fab")
			(hide yes)
			(effects
				(font
					(size 1.27 1.27)
					(thickness 0.15)
				)
			)
		)
		(property "Manufacturer" "Panasonic"
			(at 0 0 0)
			(unlocked yes)
			(layer "F.Fab")
			(hide yes)
			(effects
				(font
					(size 1 1)
					(thickness 0.15)
				)
			)
		)
		(property "MPN" "ERJ2GE0R00X"
			(at 0 0 0)
			(unlocked yes)
			(layer "F.Fab")
			(hide yes)
			(effects
				(font
					(size 1 1)
					(thickness 0.15)
				)
			)
		)
		(property "Val" "0R"
			(at 0 0 0)
			(unlocked yes)
			(layer "F.Fab")
			(hide yes)
			(effects
				(font
					(size 1 1)
					(thickness 0.15)
				)
			)
		)
		(property "License" "Apache-2.0"
			(at 0 0 0)
			(unlocked yes)
			(layer "F.Fab")
			(hide yes)
			(effects
				(font
					(size 1 1)
					(thickness 0.15)
				)
			)
		)
		(property "Author" "Antmicro"
			(at 0 0 0)
			(unlocked yes)
			(layer "F.Fab")
			(hide yes)
			(effects
				(font
					(size 1 1)
					(thickness 0.15)
				)
			)
		)
		(property "Tolerance" "~"
			(at 0 0 0)
			(unlocked yes)
			(layer "F.Fab")
			(hide yes)
			(effects
				(font
					(size 1 1)
					(thickness 0.15)
				)
			)
		)
		(property "Current" "1A"
			(at 0 0 0)
			(unlocked yes)
			(layer "F.Fab")
			(hide yes)
			(effects
				(font
					(size 1 1)
					(thickness 0.15)
				)
			)
		)
		(sheetname "/USB Debug, PD/")
		(sheetfile "usb_debug_pd.kicad_sch")
		(attr smd)
		(fp_rect
			(start -0.925 -0.47)
			(end 0.925 0.47)
			(stroke
				(width 0.05)
				(type default)
			)
			(fill no)
			(layer "F.CrtYd")
		)
		(fp_rect
			(start -0.5 -0.25)
			(end 0.5 0.25)
			(stroke
				(width 0.15)
				(type solid)
			)
			(fill no)
			(layer "F.Fab")
		)
		(fp_text user "${REFERENCE}"
			(at -0.95 3.168 180)
			(layer "F.Fab")
			(effects
				(font
					(size 0.7 0.7)
					(thickness 0.15)
				)
				(justify right top)
			)
		)
		(fp_text user "Author: Antmicro"
			(at -0.95 4.169 180)
			(layer "F.Fab")
			(effects
				(font
					(size 0.7 0.7)
					(thickness 0.15)
				)
				(justify right top)
			)
		)
		(fp_text user "License: Apache-2.0"
			(at -0.95 5.169 180)
			(layer "F.Fab")
			(effects
				(font
					(size 0.7 0.7)
					(thickness 0.15)
				)
				(justify right top)
			)
		)
		(pad "1" smd roundrect
			(at -0.48 0)
			(size 0.59 0.64)
			(layers "F.Cu" "F.Mask" "F.Paste")
			(roundrect_rratio 0.25)
			(net 960 "/SoM_IO/UART3_DEBUG.RX")
			(pintype "passive")
		)
		(pad "2" smd roundrect
			(at 0.48 0)
			(size 0.59 0.64)
			(layers "F.Cu" "F.Mask" "F.Paste")
			(roundrect_rratio 0.25)
			(net 958 "Net-(U34-TXD)")
			(pintype "passive")
		)
	)
	(footprint "antmicro-footprints:R_0402_1005Metric"
		(layer "F.Cu")
		(at 139.7 111.72 -90)
		(descr "Resistor SMD 0402")
		(tags "resistor SMD 0402")
		(property "Reference" "R404"
			(at 0.78 0.4 90)
			(layer "F.SilkS")
			(effects
				(font
					(size 0.7 0.7)
					(thickness 0.15)
				)
				(justify right top)
			)
		)
		(property "Value" "R_0R_0402"
			(at -1.011843 1.772047 90)
			(layer "F.Fab")
			(effects
				(font
					(size 0.7 0.7)
					(thickness 0.15)
				)
				(justify right top)
			)
		)
		(property "Datasheet" "https://industrial.panasonic.com/cdbs/www-data/pdf/RDA0000/AOA0000C301.pdf"
			(at 0 0 90)
			(layer "F.Fab")
			(hide yes)
			(effects
				(font
					(size 1.27 1.27)
					(thickness 0.15)
				)
			)
		)
		(property "Description" "SMD Chip Resistor, Jumper, 0 ohm, 100 mW, 0402 [1005 Metric], Thick Film, General Purpose"
			(at 0 0 90)
			(layer "F.Fab")
			(hide yes)
			(effects
				(font
					(size 1.27 1.27)
					(thickness 0.15)
				)
			)
		)
		(property "MPN" "ERJ2GE0R00X"
			(at 0 0 270)
			(unlocked yes)
			(layer "F.Fab")
			(hide yes)
			(effects
				(font
					(size 1 1)
					(thickness 0.15)
				)
			)
		)
		(property "Manufacturer" "Panasonic"
			(at 0 0 270)
			(unlocked yes)
			(layer "F.Fab")
			(hide yes)
			(effects
				(font
					(size 1 1)
					(thickness 0.15)
				)
			)
		)
		(property "License" "Apache-2.0"
			(at 0 0 270)
			(unlocked yes)
			(layer "F.Fab")
			(hide yes)
			(effects
				(font
					(size 1 1)
					(thickness 0.15)
				)
			)
		)
		(property "Author" "Antmicro"
			(at 0 0 270)
			(unlocked yes)
			(layer "F.Fab")
			(hide yes)
			(effects
				(font
					(size 1 1)
					(thickness 0.15)
				)
			)
		)
		(property "Val" "0R"
			(at 0 0 270)
			(unlocked yes)
			(layer "F.Fab")
			(hide yes)
			(effects
				(font
					(size 1 1)
					(thickness 0.15)
				)
			)
		)
		(property "Tolerance" "~"
			(at 0 0 270)
			(unlocked yes)
			(layer "F.Fab")
			(hide yes)
			(effects
				(font
					(size 1 1)
					(thickness 0.15)
				)
			)
		)
		(property "Current" "1A"
			(at 0 0 270)
			(unlocked yes)
			(layer "F.Fab")
			(hide yes)
			(effects
				(font
					(size 1 1)
					(thickness 0.15)
				)
			)
		)
		(sheetname "/Peripherals/")
		(sheetfile "peripherals.kicad_sch")
		(attr smd)
		(fp_rect
			(start -0.925 -0.47)
			(end 0.925 0.47)
			(stroke
				(width 0.05)
				(type default)
			)
			(fill no)
			(layer "F.CrtYd")
		)
		(fp_rect
			(start -0.5 -0.25)
			(end 0.5 0.25)
			(stroke
				(width 0.15)
				(type solid)
			)
			(fill no)
			(layer "F.Fab")
		)
		(fp_text user "Author: Antmicro"
			(at -0.95 4.169 90)
			(layer "F.Fab")
			(effects
				(font
					(size 0.7 0.7)
					(thickness 0.15)
				)
				(justify right top)
			)
		)
		(fp_text user "${REFERENCE}"
			(at -0.95 3.168 90)
			(layer "F.Fab")
			(effects
				(font
					(size 0.7 0.7)
					(thickness 0.15)
				)
				(justify right top)
			)
		)
		(fp_text user "License: Apache-2.0"
			(at -0.95 5.169 90)
			(layer "F.Fab")
			(effects
				(font
					(size 0.7 0.7)
					(thickness 0.15)
				)
				(justify right top)
			)
		)
		(pad "1" smd roundrect
			(at -0.48 0 270)
			(size 0.59 0.64)
			(layers "F.Cu" "F.Mask" "F.Paste")
			(roundrect_rratio 0.25)
			(net 1317 "/Peripherals/GPIOEX_P0_5")
			(pintype "passive")
		)
		(pad "2" smd roundrect
			(at 0.48 0 270)
			(size 0.59 0.64)
			(layers "F.Cu" "F.Mask" "F.Paste")
			(roundrect_rratio 0.25)
			(net 149 "/Peripherals/TPM_IRQ")
			(pintype "passive")
		)
	)
	(footprint "antmicro-footprints:C_0402_1005Metric"
		(layer "F.Cu")
		(at 193.126 142.275 180)
		(descr "Capacitor SMD 0402")
		(tags "capacitor SMD 0402")
		(property "Reference" "C65"
			(at 3.226 -0.325 180)
			(layer "F.SilkS")
			(effects
				(font
					(size 0.7 0.7)
					(thickness 0.15)
				)
				(justify left bottom)
			)
		)
		(property "Value" "C_100n_0402"
			(at -1.022927 2.155213 180)
			(layer "F.Fab")
			(effects
				(font
					(size 0.7 0.7)
					(thickness 0.15)
				)
				(justify left bottom)
			)
		)
		(property "Datasheet" "https://www.murata.com/products/productdetail?partno=GRM155R61H104KE14%23"
			(at 0 0 180)
			(layer "F.Fab")
			(hide yes)
			(effects
				(font
					(size 1.27 1.27)
					(thickness 0.15)
				)
			)
		)
		(property "Description" "SMD Multilayer Ceramic Capacitor, 0.1 µF, 50 V, 0402 [1005 Metric], ± 10%, X5R, GRM Series"
			(at 0 0 180)
			(layer "F.Fab")
			(hide yes)
			(effects
				(font
					(size 1.27 1.27)
					(thickness 0.15)
				)
			)
		)
		(property "Manufacturer" "Murata"
			(at 0 0 180)
			(unlocked yes)
			(layer "F.Fab")
			(hide yes)
			(effects
				(font
					(size 1 1)
					(thickness 0.15)
				)
			)
		)
		(property "MPN" "GRM155R61H104KE14D"
			(at 0 0 180)
			(unlocked yes)
			(layer "F.Fab")
			(hide yes)
			(effects
				(font
					(size 1 1)
					(thickness 0.15)
				)
			)
		)
		(property "Val" "100n"
			(at 0 0 180)
			(unlocked yes)
			(layer "F.Fab")
			(hide yes)
			(effects
				(font
					(size 1 1)
					(thickness 0.15)
				)
			)
		)
		(property "License" "Apache-2.0"
			(at 0 0 180)
			(unlocked yes)
			(layer "F.Fab")
			(hide yes)
			(effects
				(font
					(size 1 1)
					(thickness 0.15)
				)
			)
		)
		(property "Author" "Antmicro"
			(at 0 0 180)
			(unlocked yes)
			(layer "F.Fab")
			(hide yes)
			(effects
				(font
					(size 1 1)
					(thickness 0.15)
				)
			)
		)
		(property "Voltage" "50V"
			(at 0 0 180)
			(unlocked yes)
			(layer "F.Fab")
			(hide yes)
			(effects
				(font
					(size 1 1)
					(thickness 0.15)
				)
			)
		)
		(property "Dielectric" "X5R"
			(at 0 0 180)
			(unlocked yes)
			(layer "F.Fab")
			(hide yes)
			(effects
				(font
					(size 1 1)
					(thickness 0.15)
				)
			)
		)
		(property "Public" "False"
			(at 0 0 180)
			(unlocked yes)
			(layer "F.Fab")
			(hide yes)
			(effects
				(font
					(size 1 1)
					(thickness 0.15)
				)
			)
		)
		(sheetname "/SFP/")
		(sheetfile "sfp.kicad_sch")
		(attr smd)
		(fp_rect
			(start -0.925 -0.47)
			(end 0.925 0.47)
			(stroke
				(width 0.05)
				(type default)
			)
			(fill no)
			(layer "F.CrtYd")
		)
		(fp_line
			(start 0.504 0.248)
			(end -0.494 0.248)
			(stroke
				(width 0.15)
				(type solid)
			)
			(layer "F.Fab")
		)
		(fp_line
			(start 0.504 -0.25)
			(end 0.504 0.248)
			(stroke
				(width 0.15)
				(type solid)
			)
			(layer "F.Fab")
		)
		(fp_line
			(start -0.494 0.248)
			(end -0.494 -0.25)
			(stroke
				(width 0.15)
				(type solid)
			)
			(layer "F.Fab")
		)
		(fp_line
			(start -0.494 -0.25)
			(end 0.504 -0.25)
			(stroke
				(width 0.15)
				(type solid)
			)
			(layer "F.Fab")
		)
		(fp_text user "License: Apache-2.0"
			(at -0.939 5.799 180)
			(layer "F.Fab")
			(effects
				(font
					(size 0.7 0.7)
					(thickness 0.15)
				)
				(justify left bottom)
			)
		)
		(fp_text user "${REFERENCE}"
			(at -0.939 4.599 180)
			(layer "F.Fab")
			(effects
				(font
					(size 0.7 0.7)
					(thickness 0.15)
				)
				(justify left bottom)
			)
		)
		(fp_text user "Author: Antmicro"
			(at -0.939 3.399 180)
			(layer "F.Fab")
			(effects
				(font
					(size 0.7 0.7)
					(thickness 0.15)
				)
				(justify left bottom)
			)
		)
		(pad "1" smd roundrect
			(at -0.48 0 180)
			(size 0.59 0.64)
			(layers "F.Cu" "F.Mask" "F.Paste")
			(roundrect_rratio 0.25)
			(net 30 "/SFP/SFI_CONN_RX_N")
			(pintype "passive")
		)
		(pad "2" smd roundrect
			(at 0.48 0 180)
			(size 0.59 0.64)
			(layers "F.Cu" "F.Mask" "F.Paste")
			(roundrect_rratio 0.25)
			(net 147 "/SFP/SFI.RX-")
			(pintype "passive")
		)
	)
	(footprint "antmicro-footprints:C_0402_1005Metric"
		(layer "F.Cu")
		(at 218.8 111.7 180)
		(descr "Capacitor SMD 0402")
		(tags "capacitor SMD 0402")
		(property "Reference" "C113"
			(at 0.9 0.4 0)
			(layer "F.SilkS")
			(effects
				(font
					(size 0.7 0.7)
					(thickness 0.15)
				)
				(justify right top)
			)
		)
		(property "Value" "C_100n_0402"
			(at -1.022927 2.155213 0)
			(layer "F.Fab")
			(effects
				(font
					(size 0.7 0.7)
					(thickness 0.15)
				)
				(justify right top)
			)
		)
		(property "Datasheet" "https://www.murata.com/products/productdetail?partno=GRM155R61H104KE14%23"
			(at 0 0 0)
			(layer "F.Fab")
			(hide yes)
			(effects
				(font
					(size 1.27 1.27)
					(thickness 0.15)
				)
			)
		)
		(property "Description" "SMD Multilayer Ceramic Capacitor, 0.1 µF, 50 V, 0402 [1005 Metric], ± 10%, X5R, GRM Series"
			(at 0 0 0)
			(layer "F.Fab")
			(hide yes)
			(effects
				(font
					(size 1.27 1.27)
					(thickness 0.15)
				)
			)
		)
		(property "Manufacturer" "Murata"
			(at 0 0 180)
			(unlocked yes)
			(layer "F.Fab")
			(hide yes)
			(effects
				(font
					(size 1 1)
					(thickness 0.15)
				)
			)
		)
		(property "MPN" "GRM155R61H104KE14D"
			(at 0 0 180)
			(unlocked yes)
			(layer "F.Fab")
			(hide yes)
			(effects
				(font
					(size 1 1)
					(thickness 0.15)
				)
			)
		)
		(property "Val" "100n"
			(at 0 0 180)
			(unlocked yes)
			(layer "F.Fab")
			(hide yes)
			(effects
				(font
					(size 1 1)
					(thickness 0.15)
				)
			)
		)
		(property "License" "Apache-2.0"
			(at 0 0 180)
			(unlocked yes)
			(layer "F.Fab")
			(hide yes)
			(effects
				(font
					(size 1 1)
					(thickness 0.15)
				)
			)
		)
		(property "Author" "Antmicro"
			(at 0 0 180)
			(unlocked yes)
			(layer "F.Fab")
			(hide yes)
			(effects
				(font
					(size 1 1)
					(thickness 0.15)
				)
			)
		)
		(property "Voltage" "50V"
			(at 0 0 180)
			(unlocked yes)
			(layer "F.Fab")
			(hide yes)
			(effects
				(font
					(size 1 1)
					(thickness 0.15)
				)
			)
		)
		(property "Dielectric" "X5R"
			(at 0 0 180)
			(unlocked yes)
			(layer "F.Fab")
			(hide yes)
			(effects
				(font
					(size 1 1)
					(thickness 0.15)
				)
			)
		)
		(sheetname "/USB Hub/")
		(sheetfile "usb_hub.kicad_sch")
		(attr smd)
		(fp_rect
			(start -0.925 -0.47)
			(end 0.925 0.47)
			(stroke
				(width 0.05)
				(type default)
			)
			(fill no)
			(layer "F.CrtYd")
		)
		(fp_line
			(start 0.504 0.248)
			(end -0.494 0.248)
			(stroke
				(width 0.15)
				(type solid)
			)
			(layer "F.Fab")
		)
		(fp_line
			(start 0.504 -0.25)
			(end 0.504 0.248)
			(stroke
				(width 0.15)
				(type solid)
			)
			(layer "F.Fab")
		)
		(fp_line
			(start -0.494 0.248)
			(end -0.494 -0.25)
			(stroke
				(width 0.15)
				(type solid)
			)
			(layer "F.Fab")
		)
		(fp_line
			(start -0.494 -0.25)
			(end 0.504 -0.25)
			(stroke
				(width 0.15)
				(type solid)
			)
			(layer "F.Fab")
		)
		(fp_text user "License: Apache-2.0"
			(at -0.939 5.799 0)
			(layer "F.Fab")
			(effects
				(font
					(size 0.7 0.7)
					(thickness 0.15)
				)
				(justify right top)
			)
		)
		(fp_text user "Author: Antmicro"
			(at -0.939 3.399 0)
			(layer "F.Fab")
			(effects
				(font
					(size 0.7 0.7)
					(thickness 0.15)
				)
				(justify right top)
			)
		)
		(fp_text user "${REFERENCE}"
			(at -0.939 4.599 0)
			(layer "F.Fab")
			(effects
				(font
					(size 0.7 0.7)
					(thickness 0.15)
				)
				(justify right top)
			)
		)
		(pad "1" smd roundrect
			(at -0.48 0 180)
			(size 0.59 0.64)
			(layers "F.Cu" "F.Mask" "F.Paste")
			(roundrect_rratio 0.25)
			(net 174 "/USB Hub/USBC3_CONN_TX2_P")
			(pintype "passive")
		)
		(pad "2" smd roundrect
			(at 0.48 0 180)
			(size 0.59 0.64)
			(layers "F.Cu" "F.Mask" "F.Paste")
			(roundrect_rratio 0.25)
			(net 285 "/USB Hub/USBC3_TX_{2}-")
			(pintype "passive")
		)
	)
	(footprint "antmicro-footprints:R_0805_2012Metric"
		(layer "F.Cu")
		(at 170.774468 131.24 180)
		(property "Reference" "R258"
			(at 1.974468 0.34 0)
			(layer "F.SilkS")
			(effects
				(font
					(size 0.7 0.7)
					(thickness 0.15)
				)
				(justify right top)
			)
		)
		(property "Value" "R_0R001_0805"
			(at 0 1.8 0)
			(layer "F.Fab")
			(effects
				(font
					(size 0.7 0.7)
					(thickness 0.15)
				)
				(justify right top)
			)
		)
		(property "Datasheet" "https://www.eaton.com/content/dam/eaton/products/electronic-components/resources/data-sheet/eaton-msma-automotive-smd-current-sense-resistor-metal-strip-data-sheet-elx1179.pdf"
			(at 0 0 0)
			(layer "F.Fab")
			(hide yes)
			(effects
				(font
					(size 1.27 1.27)
					(thickness 0.15)
				)
			)
		)
		(property "Description" "Current Sense Resistors - SMD MSMA, 0805 SIZE, 1/2 Watt, 1 mohm, 50 TCR MnCu Metal AEC-Q"
			(at 0 0 0)
			(layer "F.Fab")
			(hide yes)
			(effects
				(font
					(size 1.27 1.27)
					(thickness 0.15)
				)
			)
		)
		(property "MPN" "MSMA0805R0010FSM"
			(at 0 0 0)
			(unlocked yes)
			(layer "F.Fab")
			(hide yes)
			(effects
				(font
					(size 1 1)
					(thickness 0.15)
				)
			)
		)
		(property "Manufacturer" "Eaton"
			(at 0 0 0)
			(unlocked yes)
			(layer "F.Fab")
			(hide yes)
			(effects
				(font
					(size 1 1)
					(thickness 0.15)
				)
			)
		)
		(property "License" "Apache-2.0"
			(at 0 0 0)
			(unlocked yes)
			(layer "F.Fab")
			(hide yes)
			(effects
				(font
					(size 1 1)
					(thickness 0.15)
				)
			)
		)
		(property "Author" "Antmicro"
			(at 0 0 0)
			(unlocked yes)
			(layer "F.Fab")
			(hide yes)
			(effects
				(font
					(size 1 1)
					(thickness 0.15)
				)
			)
		)
		(property "Val" "0R001"
			(at 0 0 0)
			(unlocked yes)
			(layer "F.Fab")
			(hide yes)
			(effects
				(font
					(size 1 1)
					(thickness 0.15)
				)
			)
		)
		(property "Tolerance" "1%"
			(at 0 0 0)
			(unlocked yes)
			(layer "F.Fab")
			(hide yes)
			(effects
				(font
					(size 1 1)
					(thickness 0.15)
				)
			)
		)
		(property "Public" "False"
			(at 0 0 0)
			(unlocked yes)
			(layer "F.Fab")
			(hide yes)
			(effects
				(font
					(size 1 1)
					(thickness 0.15)
				)
			)
		)
		(sheetname "/DCDC/")
		(sheetfile "dcdc.kicad_sch")
		(attr smd)
		(fp_line
			(start -0.3 -0.701)
			(end 0.298 -0.701)
			(stroke
				(width 0.15)
				(type solid)
			)
			(layer "F.SilkS")
		)
		(fp_line
			(start -0.32 0.699)
			(end 0.28 0.699)
			(stroke
				(width 0.15)
				(type solid)
			)
			(layer "F.SilkS")
		)
		(fp_rect
			(start 1.95 -0.9)
			(end -1.95 0.9)
			(stroke
				(width 0.05)
				(type default)
			)
			(fill no)
			(layer "F.CrtYd")
		)
		(fp_line
			(start 0.949 -0.677)
			(end 0.949 0.675)
			(stroke
				(width 0.15)
				(type solid)
			)
			(layer "F.Fab")
		)
		(fp_line
			(start -0.951 0.68)
			(end 0.949 0.68)
			(stroke
				(width 0.15)
				(type solid)
			)
			(layer "F.Fab")
		)
		(fp_line
			(start -0.951 -0.677)
			(end -0.951 0.675)
			(stroke
				(width 0.15)
				(type solid)
			)
			(layer "F.Fab")
		)
		(fp_line
			(start -0.951 -0.682)
			(end 0.949 -0.682)
			(stroke
				(width 0.15)
				(type solid)
			)
			(layer "F.Fab")
		)
		(fp_text user "${REFERENCE}"
			(at -1.9 3.1 0)
			(layer "F.Fab")
			(effects
				(font
					(size 0.7 0.7)
					(thickness 0.15)
				)
				(justify right top)
			)
		)
		(fp_text user "Author: Antmicro"
			(at -1.9 4.4 0)
			(layer "F.Fab")
			(effects
				(font
					(size 0.7 0.7)
					(thickness 0.15)
				)
				(justify right top)
			)
		)
		(fp_text user "License: Apache-2.0"
			(at -1.9 5.75 0)
			(layer "F.Fab")
			(effects
				(font
					(size 0.7 0.7)
					(thickness 0.15)
				)
				(justify right top)
			)
		)
		(pad "1" smd roundrect
			(at -1.1 0 180)
			(size 1.2 1.3)
			(layers "F.Cu" "F.Mask" "F.Paste")
			(roundrect_rratio 0.25)
			(net 567 "/DCDC/3V3_OUT")
			(pintype "passive")
		)
		(pad "2" smd roundrect
			(at 1.1 0 180)
			(size 1.2 1.3)
			(layers "F.Cu" "F.Mask" "F.Paste")
			(roundrect_rratio 0.25)
			(net 2 "+3V3")
			(pintype "passive")
		)
	)
	(footprint "antmicro-footprints:C_0402_1005Metric"
		(layer "F.Cu")
		(at 94 61.5 180)
		(descr "Capacitor SMD 0402")
		(tags "capacitor SMD 0402")
		(property "Reference" "C8"
			(at -8.4 -0.75 0)
			(layer "F.SilkS")
			(effects
				(font
					(size 0.7 0.7)
					(thickness 0.15)
				)
				(justify right top)
			)
		)
		(property "Value" "C_100n_0402"
			(at -1.022927 2.155213 0)
			(layer "F.Fab")
			(effects
				(font
					(size 0.7 0.7)
					(thickness 0.15)
				)
				(justify right top)
			)
		)
		(property "Datasheet" "https://www.murata.com/products/productdetail?partno=GRM155R61H104KE14%23"
			(at 0 0 0)
			(layer "F.Fab")
			(hide yes)
			(effects
				(font
					(size 1.27 1.27)
					(thickness 0.15)
				)
			)
		)
		(property "Description" "SMD Multilayer Ceramic Capacitor, 0.1 µF, 50 V, 0402 [1005 Metric], ± 10%, X5R, GRM Series"
			(at 0 0 0)
			(layer "F.Fab")
			(hide yes)
			(effects
				(font
					(size 1.27 1.27)
					(thickness 0.15)
				)
			)
		)
		(property "MPN" "GRM155R61H104KE14D"
			(at 0 0 180)
			(unlocked yes)
			(layer "F.Fab")
			(hide yes)
			(effects
				(font
					(size 1 1)
					(thickness 0.15)
				)
			)
		)
		(property "Manufacturer" "Murata"
			(at 0 0 180)
			(unlocked yes)
			(layer "F.Fab")
			(hide yes)
			(effects
				(font
					(size 1 1)
					(thickness 0.15)
				)
			)
		)
		(property "License" "Apache-2.0"
			(at 0 0 180)
			(unlocked yes)
			(layer "F.Fab")
			(hide yes)
			(effects
				(font
					(size 1 1)
					(thickness 0.15)
				)
			)
		)
		(property "Author" "Antmicro"
			(at 0 0 180)
			(unlocked yes)
			(layer "F.Fab")
			(hide yes)
			(effects
				(font
					(size 1 1)
					(thickness 0.15)
				)
			)
		)
		(property "Val" "100n"
			(at 0 0 180)
			(unlocked yes)
			(layer "F.Fab")
			(hide yes)
			(effects
				(font
					(size 1 1)
					(thickness 0.15)
				)
			)
		)
		(property "Voltage" "50V"
			(at 0 0 180)
			(unlocked yes)
			(layer "F.Fab")
			(hide yes)
			(effects
				(font
					(size 1 1)
					(thickness 0.15)
				)
			)
		)
		(property "Dielectric" "X5R"
			(at 0 0 180)
			(unlocked yes)
			(layer "F.Fab")
			(hide yes)
			(effects
				(font
					(size 1 1)
					(thickness 0.15)
				)
			)
		)
		(property "Public" "False"
			(at 0 0 180)
			(unlocked yes)
			(layer "F.Fab")
			(hide yes)
			(effects
				(font
					(size 1 1)
					(thickness 0.15)
				)
			)
		)
		(sheetname "/SoM_Power/")
		(sheetfile "som_power.kicad_sch")
		(attr smd exclude_from_pos_files exclude_from_bom dnp)
		(fp_poly
			(pts
				(xy -0.925 -0.47) (xy 0.925 -0.47) (xy 0.925 0.47) (xy -0.925 0.47)
			)
			(stroke
				(width 0.05)
				(type default)
			)
			(fill no)
			(layer "F.CrtYd")
		)
		(fp_line
			(start 0.504 0.248)
			(end -0.494 0.248)
			(stroke
				(width 0.15)
				(type solid)
			)
			(layer "F.Fab")
		)
		(fp_line
			(start 0.504 -0.25)
			(end 0.504 0.248)
			(stroke
				(width 0.15)
				(type solid)
			)
			(layer "F.Fab")
		)
		(fp_line
			(start -0.494 0.248)
			(end -0.494 -0.25)
			(stroke
				(width 0.15)
				(type solid)
			)
			(layer "F.Fab")
		)
		(fp_line
			(start -0.494 -0.25)
			(end 0.504 -0.25)
			(stroke
				(width 0.15)
				(type solid)
			)
			(layer "F.Fab")
		)
		(fp_text user "${REFERENCE}"
			(at -0.939 4.599 0)
			(layer "F.Fab")
			(effects
				(font
					(size 0.7 0.7)
					(thickness 0.15)
				)
				(justify right top)
			)
		)
		(fp_text user "Author: Antmicro"
			(at -0.939 3.399 0)
			(layer "F.Fab")
			(effects
				(font
					(size 0.7 0.7)
					(thickness 0.15)
				)
				(justify right top)
			)
		)
		(fp_text user "License: Apache-2.0"
			(at -0.939 5.799 0)
			(layer "F.Fab")
			(effects
				(font
					(size 0.7 0.7)
					(thickness 0.15)
				)
				(justify right top)
			)
		)
		(pad "1" smd roundrect
			(at -0.48 0 180)
			(size 0.59 0.64)
			(layers "F.Cu" "F.Mask" "F.Paste")
			(roundrect_rratio 0.25)
			(net 1 "GND")
			(pintype "passive")
		)
		(pad "2" smd roundrect
			(at 0.48 0 180)
			(size 0.59 0.64)
			(layers "F.Cu" "F.Mask" "F.Paste")
			(roundrect_rratio 0.25)
			(net 1287 "/SoM_Power/MODULE_POWER_ON")
			(pintype "passive")
		)
	)
	(footprint "antmicro-footprints:USON-10_2.5x1mm_P0.5mm"
		(layer "F.Cu")
		(at 220.815 111.427 180)
		(descr "USON-10 2.5x1mm_ Pitch 0.5mm")
		(tags "USON-10 2.5x1mm Pitch 0.5mm")
		(property "Reference" "U27"
			(at -1.045 -2.103 90)
			(layer "F.SilkS")
			(effects
				(font
					(size 0.7 0.7)
					(thickness 0.15)
				)
				(justify right top)
			)
		)
		(property "Value" "TPD4E05U06QDQARQ1"
			(at 0.018 2.499 0)
			(layer "F.Fab")
			(effects
				(font
					(size 0.7 0.7)
					(thickness 0.15)
				)
				(justify right top)
			)
		)
		(property "Datasheet" "https://www.ti.com/lit/ds/symlink/tpd4e05u06-q1.pdf?HQS=dis-mous-null-mousermode-dsf-pf-null-wwe&ts=1663591265741&ref_url=https%253A%252F%252Fwww.mouser.com%252F"
			(at 0 0 0)
			(layer "F.Fab")
			(hide yes)
			(effects
				(font
					(size 1.27 1.27)
					(thickness 0.15)
				)
			)
		)
		(property "Description" "TVS diode array, 12 kV, USON-10, 5.5 V, 0.5 pF"
			(at 0 0 0)
			(layer "F.Fab")
			(hide yes)
			(effects
				(font
					(size 1.27 1.27)
					(thickness 0.15)
				)
			)
		)
		(property "Manufacturer" "Texas Instruments"
			(at 0 0 180)
			(unlocked yes)
			(layer "F.Fab")
			(hide yes)
			(effects
				(font
					(size 1 1)
					(thickness 0.15)
				)
			)
		)
		(property "MPN" "TPD4E05U06QDQARQ1"
			(at 0 0 180)
			(unlocked yes)
			(layer "F.Fab")
			(hide yes)
			(effects
				(font
					(size 1 1)
					(thickness 0.15)
				)
			)
		)
		(property "Author" "Antmicro"
			(at 0 0 180)
			(unlocked yes)
			(layer "F.Fab")
			(hide yes)
			(effects
				(font
					(size 1 1)
					(thickness 0.15)
				)
			)
		)
		(property "License" "Apache-2.0"
			(at 0 0 180)
			(unlocked yes)
			(layer "F.Fab")
			(hide yes)
			(effects
				(font
					(size 1 1)
					(thickness 0.15)
				)
			)
		)
		(sheetname "/USB Hub/")
		(sheetfile "usb_hub.kicad_sch")
		(attr smd)
		(fp_line
			(start 0.498 1.398)
			(end -0.5 1.398)
			(stroke
				(width 0.15)
				(type solid)
			)
			(layer "F.SilkS")
		)
		(fp_line
			(start 0.498 -1.401)
			(end -0.5 -1.401)
			(stroke
				(width 0.15)
				(type solid)
			)
			(layer "F.SilkS")
		)
		(fp_circle
			(center -0.68 -1.27)
			(end -0.63 -1.27)
			(stroke
				(width 0.15)
				(type solid)
			)
			(fill yes)
			(layer "F.SilkS")
		)
		(fp_rect
			(start -0.8 -1.5)
			(end 0.8 1.499)
			(stroke
				(width 0.05)
				(type solid)
			)
			(fill no)
			(layer "F.CrtYd")
		)
		(fp_line
			(start 0.498 -1.25)
			(end 0.498 1.249)
			(stroke
				(width 0.15)
				(type solid)
			)
			(layer "F.Fab")
		)
		(fp_line
			(start 0.498 -1.25)
			(end -0.25 -1.25)
			(stroke
				(width 0.15)
				(type solid)
			)
			(layer "F.Fab")
		)
		(fp_line
			(start -0.25 -1.25)
			(end -0.5 -1)
			(stroke
				(width 0.15)
				(type solid)
			)
			(layer "F.Fab")
		)
		(fp_line
			(start -0.5 1.249)
			(end 0.498 1.249)
			(stroke
				(width 0.15)
				(type solid)
			)
			(layer "F.Fab")
		)
		(fp_line
			(start -0.5 -1)
			(end -0.5 1.249)
			(stroke
				(width 0.15)
				(type solid)
			)
			(layer "F.Fab")
		)
		(fp_text user "Author: Antmicro"
			(at -0.802 5.7 0)
			(layer "F.Fab")
			(effects
				(font
					(size 0.7 0.7)
					(thickness 0.15)
				)
				(justify right top)
			)
		)
		(fp_text user "License: Apache-2.0"
			(at -0.802 6.9 0)
			(layer "F.Fab")
			(effects
				(font
					(size 0.7 0.7)
					(thickness 0.15)
				)
				(justify right top)
			)
		)
		(fp_text user "${REFERENCE}"
			(at -0.802 4.498 0)
			(layer "F.Fab")
			(effects
				(font
					(size 0.7 0.7)
					(thickness 0.15)
				)
				(justify right top)
			)
		)
		(pad "1" smd roundrect
			(at -0.387 -1 90)
			(size 0.25 0.55)
			(layers "F.Cu" "F.Mask" "F.Paste")
			(roundrect_rratio 0.25)
			(net 103 "/USB Hub/USBC3_CONN_TX2_N")
			(pintype "passive")
		)
		(pad "2" smd roundrect
			(at -0.387 -0.5 90)
			(size 0.25 0.55)
			(layers "F.Cu" "F.Mask" "F.Paste")
			(roundrect_rratio 0.25)
			(net 174 "/USB Hub/USBC3_CONN_TX2_P")
			(pintype "passive")
		)
		(pad "3" smd roundrect
			(at -0.387 0 90)
			(size 0.4 0.55)
			(layers "F.Cu" "F.Mask" "F.Paste")
			(roundrect_rratio 0.25)
			(net 1 "GND")
			(pintype "power_in")
		)
		(pad "4" smd roundrect
			(at -0.387 0.498 90)
			(size 0.25 0.55)
			(layers "F.Cu" "F.Mask" "F.Paste")
			(roundrect_rratio 0.25)
			(net 512 "/USB Hub/USBC3_RX_{2}+")
			(pintype "passive")
		)
		(pad "5" smd roundrect
			(at -0.387 0.998 90)
			(size 0.25 0.55)
			(layers "F.Cu" "F.Mask" "F.Paste")
			(roundrect_rratio 0.25)
			(net 511 "/USB Hub/USBC3_RX_{2}-")
			(pintype "passive")
		)
		(pad "6" smd roundrect
			(at 0.385 0.998 90)
			(size 0.25 0.55)
			(layers "F.Cu" "F.Mask" "F.Paste")
			(roundrect_rratio 0.25)
			(net 511 "/USB Hub/USBC3_RX_{2}-")
			(pintype "passive")
		)
		(pad "7" smd roundrect
			(at 0.385 0.498 90)
			(size 0.25 0.55)
			(layers "F.Cu" "F.Mask" "F.Paste")
			(roundrect_rratio 0.25)
			(net 512 "/USB Hub/USBC3_RX_{2}+")
			(pintype "passive")
		)
		(pad "8" smd roundrect
			(at 0.385 0 90)
			(size 0.4 0.55)
			(layers "F.Cu" "F.Mask" "F.Paste")
			(roundrect_rratio 0.25)
			(net 1 "GND")
			(pintype "passive")
		)
		(pad "9" smd roundrect
			(at 0.385 -0.5 90)
			(size 0.25 0.55)
			(layers "F.Cu" "F.Mask" "F.Paste")
			(roundrect_rratio 0.25)
			(net 174 "/USB Hub/USBC3_CONN_TX2_P")
			(pintype "passive")
		)
		(pad "10" smd roundrect
			(at 0.385 -1 90)
			(size 0.25 0.55)
			(layers "F.Cu" "F.Mask" "F.Paste")
			(roundrect_rratio 0.25)
			(net 103 "/USB Hub/USBC3_CONN_TX2_N")
			(pintype "passive")
		)
	)
	(footprint "antmicro-footprints:C_0402_1005Metric"
		(layer "F.Cu")
		(at 168.924468 134.56 180)
		(descr "Capacitor SMD 0402")
		(tags "capacitor SMD 0402")
		(property "Reference" "C217"
			(at 1.024468 0.16 0)
			(layer "F.SilkS")
			(effects
				(font
					(size 0.7 0.7)
					(thickness 0.15)
				)
				(justify right top)
			)
		)
		(property "Value" "C_100n_0402"
			(at -1.022927 2.155213 0)
			(layer "F.Fab")
			(effects
				(font
					(size 0.7 0.7)
					(thickness 0.15)
				)
				(justify right top)
			)
		)
		(property "Datasheet" "https://www.murata.com/products/productdetail?partno=GRM155R61H104KE14%23"
			(at 0 0 0)
			(layer "F.Fab")
			(hide yes)
			(effects
				(font
					(size 1.27 1.27)
					(thickness 0.15)
				)
			)
		)
		(property "Description" "SMD Multilayer Ceramic Capacitor, 0.1 µF, 50 V, 0402 [1005 Metric], ± 10%, X5R, GRM Series"
			(at 0 0 0)
			(layer "F.Fab")
			(hide yes)
			(effects
				(font
					(size 1.27 1.27)
					(thickness 0.15)
				)
			)
		)
		(property "MPN" "GRM155R61H104KE14D"
			(at 0 0 180)
			(unlocked yes)
			(layer "F.Fab")
			(hide yes)
			(effects
				(font
					(size 1 1)
					(thickness 0.15)
				)
			)
		)
		(property "Manufacturer" "Murata"
			(at 0 0 180)
			(unlocked yes)
			(layer "F.Fab")
			(hide yes)
			(effects
				(font
					(size 1 1)
					(thickness 0.15)
				)
			)
		)
		(property "License" "Apache-2.0"
			(at 0 0 180)
			(unlocked yes)
			(layer "F.Fab")
			(hide yes)
			(effects
				(font
					(size 1 1)
					(thickness 0.15)
				)
			)
		)
		(property "Author" "Antmicro"
			(at 0 0 180)
			(unlocked yes)
			(layer "F.Fab")
			(hide yes)
			(effects
				(font
					(size 1 1)
					(thickness 0.15)
				)
			)
		)
		(property "Val" "100n"
			(at 0 0 180)
			(unlocked yes)
			(layer "F.Fab")
			(hide yes)
			(effects
				(font
					(size 1 1)
					(thickness 0.15)
				)
			)
		)
		(property "Voltage" "50V"
			(at 0 0 180)
			(unlocked yes)
			(layer "F.Fab")
			(hide yes)
			(effects
				(font
					(size 1 1)
					(thickness 0.15)
				)
			)
		)
		(property "Dielectric" "X5R"
			(at 0 0 180)
			(unlocked yes)
			(layer "F.Fab")
			(hide yes)
			(effects
				(font
					(size 1 1)
					(thickness 0.15)
				)
			)
		)
		(property "Public" "False"
			(at 0 0 180)
			(unlocked yes)
			(layer "F.Fab")
			(hide yes)
			(effects
				(font
					(size 1 1)
					(thickness 0.15)
				)
			)
		)
		(sheetname "/DCDC/")
		(sheetfile "dcdc.kicad_sch")
		(attr smd)
		(fp_rect
			(start -0.925 -0.47)
			(end 0.925 0.47)
			(stroke
				(width 0.05)
				(type default)
			)
			(fill no)
			(layer "F.CrtYd")
		)
		(fp_line
			(start 0.504 0.248)
			(end -0.494 0.248)
			(stroke
				(width 0.15)
				(type solid)
			)
			(layer "F.Fab")
		)
		(fp_line
			(start 0.504 -0.25)
			(end 0.504 0.248)
			(stroke
				(width 0.15)
				(type solid)
			)
			(layer "F.Fab")
		)
		(fp_line
			(start -0.494 0.248)
			(end -0.494 -0.25)
			(stroke
				(width 0.15)
				(type solid)
			)
			(layer "F.Fab")
		)
		(fp_line
			(start -0.494 -0.25)
			(end 0.504 -0.25)
			(stroke
				(width 0.15)
				(type solid)
			)
			(layer "F.Fab")
		)
		(fp_text user "License: Apache-2.0"
			(at -0.939 5.799 0)
			(layer "F.Fab")
			(effects
				(font
					(size 0.7 0.7)
					(thickness 0.15)
				)
				(justify right top)
			)
		)
		(fp_text user "${REFERENCE}"
			(at -0.939 4.599 0)
			(layer "F.Fab")
			(effects
				(font
					(size 0.7 0.7)
					(thickness 0.15)
				)
				(justify right top)
			)
		)
		(fp_text user "Author: Antmicro"
			(at -0.939 3.399 0)
			(layer "F.Fab")
			(effects
				(font
					(size 0.7 0.7)
					(thickness 0.15)
				)
				(justify right top)
			)
		)
		(pad "1" smd roundrect
			(at -0.48 0 180)
			(size 0.59 0.64)
			(layers "F.Cu" "F.Mask" "F.Paste")
			(roundrect_rratio 0.25)
			(net 1 "GND")
			(pintype "passive")
		)
		(pad "2" smd roundrect
			(at 0.48 0 180)
			(size 0.59 0.64)
			(layers "F.Cu" "F.Mask" "F.Paste")
			(roundrect_rratio 0.25)
			(net 4 "+3V3_AON")
			(pintype "passive")
		)
	)
	(footprint "antmicro-footprints:R_0402_1005Metric"
		(layer "F.Cu")
		(at 214.8 107 90)
		(descr "Resistor SMD 0402")
		(tags "resistor SMD 0402")
		(property "Reference" "R276"
			(at -1.75 1.465 90)
			(layer "F.SilkS")
			(effects
				(font
					(size 0.7 0.7)
					(thickness 0.15)
				)
				(justify left bottom)
			)
		)
		(property "Value" "R_0R_0402"
			(at -1.011843 1.772046 90)
			(layer "F.Fab")
			(effects
				(font
					(size 0.7 0.7)
					(thickness 0.15)
				)
				(justify left bottom)
			)
		)
		(property "Datasheet" "https://industrial.panasonic.com/cdbs/www-data/pdf/RDA0000/AOA0000C301.pdf"
			(at 0 0 90)
			(layer "F.Fab")
			(hide yes)
			(effects
				(font
					(size 1.27 1.27)
					(thickness 0.15)
				)
			)
		)
		(property "Description" "SMD Chip Resistor, Jumper, 0 ohm, 100 mW, 0402 [1005 Metric], Thick Film, General Purpose"
			(at 0 0 90)
			(layer "F.Fab")
			(hide yes)
			(effects
				(font
					(size 1.27 1.27)
					(thickness 0.15)
				)
			)
		)
		(property "Manufacturer" "Panasonic"
			(at 0 0 90)
			(unlocked yes)
			(layer "F.Fab")
			(hide yes)
			(effects
				(font
					(size 1 1)
					(thickness 0.15)
				)
			)
		)
		(property "MPN" "ERJ2GE0R00X"
			(at 0 0 90)
			(unlocked yes)
			(layer "F.Fab")
			(hide yes)
			(effects
				(font
					(size 1 1)
					(thickness 0.15)
				)
			)
		)
		(property "Val" "0R"
			(at 0 0 90)
			(unlocked yes)
			(layer "F.Fab")
			(hide yes)
			(effects
				(font
					(size 1 1)
					(thickness 0.15)
				)
			)
		)
		(property "License" "Apache-2.0"
			(at 0 0 90)
			(unlocked yes)
			(layer "F.Fab")
			(hide yes)
			(effects
				(font
					(size 1 1)
					(thickness 0.15)
				)
			)
		)
		(property "Author" "Antmicro"
			(at 0 0 90)
			(unlocked yes)
			(layer "F.Fab")
			(hide yes)
			(effects
				(font
					(size 1 1)
					(thickness 0.15)
				)
			)
		)
		(property "Tolerance" "~"
			(at 0 0 90)
			(unlocked yes)
			(layer "F.Fab")
			(hide yes)
			(effects
				(font
					(size 1 1)
					(thickness 0.15)
				)
			)
		)
		(property "Current" "1A"
			(at 0 0 90)
			(unlocked yes)
			(layer "F.Fab")
			(hide yes)
			(effects
				(font
					(size 1 1)
					(thickness 0.15)
				)
			)
		)
		(sheetname "/Recovery USB/")
		(sheetfile "recovery_usb.kicad_sch")
		(attr smd)
		(fp_poly
			(pts
				(xy -0.925 -0.47) (xy -0.925 0.47) (xy 0.925 0.47) (xy 0.925 -0.47)
			)
			(stroke
				(width 0.05)
				(type default)
			)
			(fill no)
			(layer "F.CrtYd")
		)
		(fp_poly
			(pts
				(xy -0.5 -0.25) (xy -0.5 0.25) (xy 0.5 0.25) (xy 0.5 -0.25)
			)
			(stroke
				(width 0.15)
				(type solid)
			)
			(fill no)
			(layer "F.Fab")
		)
		(fp_text user "Author: Antmicro"
			(at -0.95 4.169 90)
			(layer "F.Fab")
			(effects
				(font
					(size 0.7 0.7)
					(thickness 0.15)
				)
				(justify left bottom)
			)
		)
		(fp_text user "License: Apache-2.0"
			(at -0.949999 5.169 90)
			(layer "F.Fab")
			(effects
				(font
					(size 0.7 0.7)
					(thickness 0.15)
				)
				(justify left bottom)
			)
		)
		(fp_text user "${REFERENCE}"
			(at -0.95 3.168 90)
			(layer "F.Fab")
			(effects
				(font
					(size 0.7 0.7)
					(thickness 0.15)
				)
				(justify left bottom)
			)
		)
		(pad "1" smd roundrect
			(at -0.48 0 90)
			(size 0.59 0.64)
			(layers "F.Cu" "F.Mask" "F.Paste")
			(roundrect_rratio 0.25)
			(net 1 "GND")
			(pintype "passive")
		)
		(pad "2" smd roundrect
			(at 0.48 0 90)
			(size 0.59 0.64)
			(layers "F.Cu" "F.Mask" "F.Paste")
			(roundrect_rratio 0.25)
			(net 1021 "/Recovery USB/~{USBC2_EN_MUX}")
			(pintype "passive")
		)
	)
	(footprint "antmicro-footprints:Vishay_PowerPAK_1212-8_Single"
		(layer "F.Cu")
		(at 114.016 60.91)
		(descr "PowerPAK 1212-8 Single")
		(tags "Vishay PowerPAK 1212-8 Single")
		(property "Reference" "Q9"
			(at 3.694 2.47 0)
			(layer "F.SilkS")
			(effects
				(font
					(size 0.7 0.7)
					(thickness 0.15)
				)
				(justify right top)
			)
		)
		(property "Value" "SISS05DN-T1-GE3"
			(at 0 2.7 0)
			(layer "F.Fab")
			(effects
				(font
					(size 0.7 0.7)
					(thickness 0.15)
				)
				(justify left bottom)
			)
		)
		(property "Datasheet" "https://www.vishay.com/docs/77029/siss05dn.pdf"
			(at 0 0 0)
			(layer "F.Fab")
			(hide yes)
			(effects
				(font
					(size 1.27 1.27)
					(thickness 0.15)
				)
			)
		)
		(property "Description" "Power MOSFET, P Channel, 30 V, 108 A, 0.0035 ohm, PowerPAK 1212, Surface Mount"
			(at 0 0 0)
			(layer "F.Fab")
			(hide yes)
			(effects
				(font
					(size 1.27 1.27)
					(thickness 0.15)
				)
			)
		)
		(property "MPN" "SISS05DN-T1-GE3"
			(at 0 0 0)
			(unlocked yes)
			(layer "F.Fab")
			(hide yes)
			(effects
				(font
					(size 1 1)
					(thickness 0.15)
				)
			)
		)
		(property "Manufacturer" "Vishay"
			(at 0 0 0)
			(unlocked yes)
			(layer "F.Fab")
			(hide yes)
			(effects
				(font
					(size 1 1)
					(thickness 0.15)
				)
			)
		)
		(property "Author" "Antmicro"
			(at 0 0 0)
			(unlocked yes)
			(layer "F.Fab")
			(hide yes)
			(effects
				(font
					(size 1 1)
					(thickness 0.15)
				)
			)
		)
		(property "License" "Apache-2.0"
			(at 0 0 0)
			(unlocked yes)
			(layer "F.Fab")
			(hide yes)
			(effects
				(font
					(size 1 1)
					(thickness 0.15)
				)
			)
		)
		(sheetname "/SoM_Power/")
		(sheetfile "som_power.kicad_sch")
		(attr smd)
		(fp_line
			(start -1.651 -1.651)
			(end -1.651 -1.317)
			(stroke
				(width 0.15)
				(type solid)
			)
			(layer "F.SilkS")
		)
		(fp_line
			(start -1.651 -1.651)
			(end 1.648 -1.651)
			(stroke
				(width 0.15)
				(type solid)
			)
			(layer "F.SilkS")
		)
		(fp_line
			(start -1.635 1.3)
			(end -1.635 1.634)
			(stroke
				(width 0.15)
				(type solid)
			)
			(layer "F.SilkS")
		)
		(fp_line
			(start -1.635 1.634)
			(end 1.634 1.634)
			(stroke
				(width 0.15)
				(type solid)
			)
			(layer "F.SilkS")
		)
		(fp_line
			(start 1.634 1.3)
			(end 1.634 1.634)
			(stroke
				(width 0.15)
				(type solid)
			)
			(layer "F.SilkS")
		)
		(fp_line
			(start 1.648 -1.651)
			(end 1.648 -1.317001)
			(stroke
				(width 0.15)
				(type solid)
			)
			(layer "F.SilkS")
		)
		(fp_circle
			(center -1.899999 -1.4)
			(end -1.85 -1.4)
			(stroke
				(width 0.15)
				(type solid)
			)
			(fill yes)
			(layer "F.SilkS")
		)
		(fp_poly
			(pts
				(xy -2 -1.8) (xy 2 -1.8) (xy 2.000001 1.798) (xy -2.000001 1.798)
			)
			(stroke
				(width 0.05)
				(type solid)
			)
			(fill no)
			(layer "F.CrtYd")
		)
		(fp_line
			(start -1.6425 -1.4175)
			(end -1.4175 -1.6425)
			(stroke
				(width 0.15)
				(type solid)
			)
			(layer "F.Fab")
		)
		(fp_poly
			(pts
				(xy -1.651 -1.651) (xy 1.648 -1.651) (xy 1.648 1.648) (xy -1.651 1.648)
			)
			(stroke
				(width 0.15)
				(type solid)
			)
			(fill no)
			(layer "F.Fab")
		)
		(fp_text user "${REFERENCE}"
			(at -8 4.7 0)
			(layer "F.Fab")
			(effects
				(font
					(size 0.7 0.7)
					(thickness 0.15)
				)
				(justify left bottom)
			)
		)
		(fp_text user "License: Apache-2.0"
			(at -8 7.1 0)
			(layer "F.Fab")
			(effects
				(font
					(size 0.7 0.7)
					(thickness 0.15)
				)
				(justify left bottom)
			)
		)
		(fp_text user "Author: Antmicro"
			(at -8 5.9 0)
			(layer "F.Fab")
			(effects
				(font
					(size 0.7 0.7)
					(thickness 0.15)
				)
				(justify left bottom)
			)
		)
		(pad "1" smd rect
			(at -1.436 -0.99)
			(size 0.99 0.405)
			(layers "F.Cu" "F.Mask" "F.Paste")
			(net 491 "+5V_AON")
			(pinfunction "S")
			(pintype "passive")
		)
		(pad "2" smd rect
			(at -1.436 -0.332)
			(size 0.99 0.405)
			(layers "F.Cu" "F.Mask" "F.Paste")
			(net 491 "+5V_AON")
			(pinfunction "S")
			(pintype "passive")
		)
		(pad "3" smd rect
			(at -1.436 0.33)
			(size 0.99 0.405)
			(layers "F.Cu" "F.Mask" "F.Paste")
			(net 491 "+5V_AON")
			(pinfunction "S")
			(pintype "passive")
		)
		(pad "4" smd rect
			(at -1.436 0.988)
			(size 0.99 0.405)
			(layers "F.Cu" "F.Mask" "F.Paste")
			(net 1392 "Net-(Q6-D)")
			(pinfunction "G")
			(pintype "input")
		)
		(pad "5" smd custom
			(at 0.556999 0)
			(size 1.725 2.235)
			(layers "F.Cu" "F.Mask" "F.Paste")
			(net 1096 "Net-(Q9-D)")
			(pinfunction "D")
			(pintype "passive")
			(zone_connect 2)
			(options
				(clearance outline)
				(anchor rect)
			)
			(primitives
				(gr_poly
					(pts
						(xy 0.8625 0.1275) (xy 0.8625 -0.1275) (xy 1.3725 -0.1275) (xy 1.3725 -0.5325) (xy 0.8625 -0.5325)
						(xy 0.8625 -0.7875) (xy 1.3725 -0.7875) (xy 1.3725 -1.195) (xy 0.6125 -1.195) (xy 0.6125 1.195)
						(xy 1.3725 1.195) (xy 1.3725 0.7875) (xy 0.8625 0.7875) (xy 0.8625 0.5325) (xy 1.3725 0.5325)
						(xy 1.3725 0.1275)
					)
					(width 0)
					(fill yes)
				)
			)
		)
	)
	(footprint "antmicro-footprints:C_0402_1005Metric"
		(layer "F.Cu")
		(at 160.369468 79.51 180)
		(descr "Capacitor SMD 0402")
		(tags "capacitor SMD 0402")
		(property "Reference" "C304"
			(at 3.569468 0.31 0)
			(layer "F.SilkS")
			(effects
				(font
					(size 0.7 0.7)
					(thickness 0.15)
				)
				(justify right top)
			)
		)
		(property "Value" "C_100n_0402"
			(at -1.022927 2.155213 0)
			(layer "F.Fab")
			(effects
				(font
					(size 0.7 0.7)
					(thickness 0.15)
				)
				(justify right top)
			)
		)
		(property "Datasheet" "https://www.murata.com/products/productdetail?partno=GRM155R61H104KE14%23"
			(at 0 0 0)
			(layer "F.Fab")
			(hide yes)
			(effects
				(font
					(size 1.27 1.27)
					(thickness 0.15)
				)
			)
		)
		(property "Description" "SMD Multilayer Ceramic Capacitor, 0.1 µF, 50 V, 0402 [1005 Metric], ± 10%, X5R, GRM Series"
			(at 0 0 0)
			(layer "F.Fab")
			(hide yes)
			(effects
				(font
					(size 1.27 1.27)
					(thickness 0.15)
				)
			)
		)
		(property "MPN" "GRM155R61H104KE14D"
			(at 0 0 180)
			(unlocked yes)
			(layer "F.Fab")
			(hide yes)
			(effects
				(font
					(size 1 1)
					(thickness 0.15)
				)
			)
		)
		(property "Manufacturer" "Murata"
			(at 0 0 180)
			(unlocked yes)
			(layer "F.Fab")
			(hide yes)
			(effects
				(font
					(size 1 1)
					(thickness 0.15)
				)
			)
		)
		(property "License" "Apache-2.0"
			(at 0 0 180)
			(unlocked yes)
			(layer "F.Fab")
			(hide yes)
			(effects
				(font
					(size 1 1)
					(thickness 0.15)
				)
			)
		)
		(property "Author" "Antmicro"
			(at 0 0 180)
			(unlocked yes)
			(layer "F.Fab")
			(hide yes)
			(effects
				(font
					(size 1 1)
					(thickness 0.15)
				)
			)
		)
		(property "Val" "100n"
			(at 0 0 180)
			(unlocked yes)
			(layer "F.Fab")
			(hide yes)
			(effects
				(font
					(size 1 1)
					(thickness 0.15)
				)
			)
		)
		(property "Voltage" "50V"
			(at 0 0 180)
			(unlocked yes)
			(layer "F.Fab")
			(hide yes)
			(effects
				(font
					(size 1 1)
					(thickness 0.15)
				)
			)
		)
		(property "Dielectric" "X5R"
			(at 0 0 180)
			(unlocked yes)
			(layer "F.Fab")
			(hide yes)
			(effects
				(font
					(size 1 1)
					(thickness 0.15)
				)
			)
		)
		(property "Public" "False"
			(at 0 0 180)
			(unlocked yes)
			(layer "F.Fab")
			(hide yes)
			(effects
				(font
					(size 1 1)
					(thickness 0.15)
				)
			)
		)
		(component_classes
			(class "DCDC_20V")
		)
		(sheetname "/DCDC/")
		(sheetfile "dcdc.kicad_sch")
		(attr smd)
		(fp_rect
			(start -0.925 -0.47)
			(end 0.925 0.47)
			(stroke
				(width 0.05)
				(type default)
			)
			(fill no)
			(layer "F.CrtYd")
		)
		(fp_line
			(start 0.504 0.248)
			(end -0.494 0.248)
			(stroke
				(width 0.15)
				(type solid)
			)
			(layer "F.Fab")
		)
		(fp_line
			(start 0.504 -0.25)
			(end 0.504 0.248)
			(stroke
				(width 0.15)
				(type solid)
			)
			(layer "F.Fab")
		)
		(fp_line
			(start -0.494 0.248)
			(end -0.494 -0.25)
			(stroke
				(width 0.15)
				(type solid)
			)
			(layer "F.Fab")
		)
		(fp_line
			(start -0.494 -0.25)
			(end 0.504 -0.25)
			(stroke
				(width 0.15)
				(type solid)
			)
			(layer "F.Fab")
		)
		(fp_text user "License: Apache-2.0"
			(at -0.939 5.799 0)
			(layer "F.Fab")
			(effects
				(font
					(size 0.7 0.7)
					(thickness 0.15)
				)
				(justify right top)
			)
		)
		(fp_text user "Author: Antmicro"
			(at -0.939 3.399 0)
			(layer "F.Fab")
			(effects
				(font
					(size 0.7 0.7)
					(thickness 0.15)
				)
				(justify right top)
			)
		)
		(fp_text user "${REFERENCE}"
			(at -0.939 4.599 0)
			(layer "F.Fab")
			(effects
				(font
					(size 0.7 0.7)
					(thickness 0.15)
				)
				(justify right top)
			)
		)
		(pad "1" smd roundrect
			(at -0.48 0 180)
			(size 0.59 0.64)
			(layers "F.Cu" "F.Mask" "F.Paste")
			(roundrect_rratio 0.25)
			(net 1 "GND")
			(pintype "passive")
		)
		(pad "2" smd roundrect
			(at 0.48 0 180)
			(size 0.59 0.64)
			(layers "F.Cu" "F.Mask" "F.Paste")
			(roundrect_rratio 0.25)
			(net 4 "+3V3_AON")
			(pintype "passive")
		)
	)
	(footprint "antmicro-footprints:R_0402_1005Metric"
		(layer "F.Cu")
		(at 147 112)
		(descr "Resistor SMD 0402")
		(tags "resistor SMD 0402")
		(property "Reference" "R353"
			(at -3.6 0.4 0)
			(layer "F.SilkS")
			(effects
				(font
					(size 0.7 0.7)
					(thickness 0.15)
				)
				(justify left bottom)
			)
		)
		(property "Value" "R_2k2_0402"
			(at -1.011843 1.772047 0)
			(layer "F.Fab")
			(effects
				(font
					(size 0.7 0.7)
					(thickness 0.15)
				)
				(justify left bottom)
			)
		)
		(property "Datasheet" "https://www.bourns.com/docs/product-datasheets/cr.pdf"
			(at 0 0 0)
			(layer "F.Fab")
			(hide yes)
			(effects
				(font
					(size 1.27 1.27)
					(thickness 0.15)
				)
			)
		)
		(property "Description" "SMD Chip Resistor, 2.2 kohm, ± 1%, 62.5 mW, 0402 [1005 Metric], Thick Film, General Purpose"
			(at 0 0 0)
			(layer "F.Fab")
			(hide yes)
			(effects
				(font
					(size 1.27 1.27)
					(thickness 0.15)
				)
			)
		)
		(property "MPN" "CR0402-FX-2201GLF"
			(at 0 0 0)
			(unlocked yes)
			(layer "F.Fab")
			(hide yes)
			(effects
				(font
					(size 1 1)
					(thickness 0.15)
				)
			)
		)
		(property "Manufacturer" "Bourns"
			(at 0 0 0)
			(unlocked yes)
			(layer "F.Fab")
			(hide yes)
			(effects
				(font
					(size 1 1)
					(thickness 0.15)
				)
			)
		)
		(property "License" "Apache-2.0"
			(at 0 0 0)
			(unlocked yes)
			(layer "F.Fab")
			(hide yes)
			(effects
				(font
					(size 1 1)
					(thickness 0.15)
				)
			)
		)
		(property "Author" "Antmicro"
			(at 0 0 0)
			(unlocked yes)
			(layer "F.Fab")
			(hide yes)
			(effects
				(font
					(size 1 1)
					(thickness 0.15)
				)
			)
		)
		(property "Val" "2k2"
			(at 0 0 0)
			(unlocked yes)
			(layer "F.Fab")
			(hide yes)
			(effects
				(font
					(size 1 1)
					(thickness 0.15)
				)
			)
		)
		(property "Tolerance" "1%"
			(at 0 0 0)
			(unlocked yes)
			(layer "F.Fab")
			(hide yes)
			(effects
				(font
					(size 1 1)
					(thickness 0.15)
				)
			)
		)
		(sheetname "/SoM_IO/")
		(sheetfile "som_io.kicad_sch")
		(attr smd exclude_from_pos_files exclude_from_bom dnp)
		(fp_rect
			(start -0.925 -0.47)
			(end 0.925 0.47)
			(stroke
				(width 0.05)
				(type default)
			)
			(fill no)
			(layer "F.CrtYd")
		)
		(fp_rect
			(start -0.5 -0.25)
			(end 0.5 0.25)
			(stroke
				(width 0.15)
				(type solid)
			)
			(fill no)
			(layer "F.Fab")
		)
		(fp_text user "Author: Antmicro"
			(at -0.95 4.169 0)
			(layer "F.Fab")
			(effects
				(font
					(size 0.7 0.7)
					(thickness 0.15)
				)
				(justify left bottom)
			)
		)
		(fp_text user "License: Apache-2.0"
			(at -0.95 5.169 0)
			(layer "F.Fab")
			(effects
				(font
					(size 0.7 0.7)
					(thickness 0.15)
				)
				(justify left bottom)
			)
		)
		(fp_text user "${REFERENCE}"
			(at -0.95 3.168 0)
			(layer "F.Fab")
			(effects
				(font
					(size 0.7 0.7)
					(thickness 0.15)
				)
				(justify left bottom)
			)
		)
		(pad "1" smd roundrect
			(at -0.48 0)
			(size 0.59 0.64)
			(layers "F.Cu" "F.Mask" "F.Paste")
			(roundrect_rratio 0.25)
			(net 11 "+1V8")
			(pintype "passive")
		)
		(pad "2" smd roundrect
			(at 0.48 0)
			(size 0.59 0.64)
			(layers "F.Cu" "F.Mask" "F.Paste")
			(roundrect_rratio 0.25)
			(net 133 "/SoM_IO/I2C5_SCL_1V8")
			(pintype "passive")
		)
	)
	(footprint "antmicro-footprints:C_0402_1005Metric"
		(layer "F.Cu")
		(at 182.764468 89.705 -90)
		(descr "Capacitor SMD 0402")
		(tags "capacitor SMD 0402")
		(property "Reference" "C244"
			(at -1 -1.65 90)
			(layer "F.SilkS")
			(effects
				(font
					(size 0.7 0.7)
					(thickness 0.15)
				)
				(justify right top)
			)
		)
		(property "Value" "C_1u_0402"
			(at -1.022927 2.155213 90)
			(layer "F.Fab")
			(effects
				(font
					(size 0.7 0.7)
					(thickness 0.15)
				)
				(justify right top)
			)
		)
		(property "Datasheet" "https://product.tdk.com/en/search/capacitor/ceramic/mlcc/info?part_no=C1005X6S1A105K050BC"
			(at 0 0 90)
			(layer "F.Fab")
			(hide yes)
			(effects
				(font
					(size 1.27 1.27)
					(thickness 0.15)
				)
			)
		)
		(property "Description" "SMD Multilayer Ceramic Capacitor, 1 µF, 10 V, 0402 [1005 Metric], ± 10%, X6S, C"
			(at 0 0 90)
			(layer "F.Fab")
			(hide yes)
			(effects
				(font
					(size 1.27 1.27)
					(thickness 0.15)
				)
			)
		)
		(property "Manufacturer" "TDK"
			(at 0 0 270)
			(unlocked yes)
			(layer "F.Fab")
			(hide yes)
			(effects
				(font
					(size 1 1)
					(thickness 0.15)
				)
			)
		)
		(property "MPN" "C1005X6S1A105K050BC"
			(at 0 0 270)
			(unlocked yes)
			(layer "F.Fab")
			(hide yes)
			(effects
				(font
					(size 1 1)
					(thickness 0.15)
				)
			)
		)
		(property "Val" "1u"
			(at 0 0 270)
			(unlocked yes)
			(layer "F.Fab")
			(hide yes)
			(effects
				(font
					(size 1 1)
					(thickness 0.15)
				)
			)
		)
		(property "License" "Apache-2.0"
			(at 0 0 270)
			(unlocked yes)
			(layer "F.Fab")
			(hide yes)
			(effects
				(font
					(size 1 1)
					(thickness 0.15)
				)
			)
		)
		(property "Author" "Antmicro"
			(at 0 0 270)
			(unlocked yes)
			(layer "F.Fab")
			(hide yes)
			(effects
				(font
					(size 1 1)
					(thickness 0.15)
				)
			)
		)
		(property "Voltage" ""
			(at 0 0 270)
			(unlocked yes)
			(layer "F.Fab")
			(hide yes)
			(effects
				(font
					(size 1 1)
					(thickness 0.15)
				)
			)
		)
		(property "Dielectric" ""
			(at 0 0 270)
			(unlocked yes)
			(layer "F.Fab")
			(hide yes)
			(effects
				(font
					(size 1 1)
					(thickness 0.15)
				)
			)
		)
		(component_classes
			(class "DCDC_SOM")
		)
		(sheetname "/DCDC/")
		(sheetfile "dcdc.kicad_sch")
		(attr smd)
		(fp_rect
			(start -0.925 -0.47)
			(end 0.925 0.47)
			(stroke
				(width 0.05)
				(type default)
			)
			(fill no)
			(layer "F.CrtYd")
		)
		(fp_line
			(start -0.494 0.248)
			(end -0.494 -0.25)
			(stroke
				(width 0.15)
				(type solid)
			)
			(layer "F.Fab")
		)
		(fp_line
			(start 0.504 0.248)
			(end -0.494 0.248)
			(stroke
				(width 0.15)
				(type solid)
			)
			(layer "F.Fab")
		)
		(fp_line
			(start -0.494 -0.25)
			(end 0.504 -0.25)
			(stroke
				(width 0.15)
				(type solid)
			)
			(layer "F.Fab")
		)
		(fp_line
			(start 0.504 -0.25)
			(end 0.504 0.248)
			(stroke
				(width 0.15)
				(type solid)
			)
			(layer "F.Fab")
		)
		(fp_text user "${REFERENCE}"
			(at -0.939 4.599 90)
			(layer "F.Fab")
			(effects
				(font
					(size 0.7 0.7)
					(thickness 0.15)
				)
				(justify right top)
			)
		)
		(fp_text user "Author: Antmicro"
			(at -0.939 3.399 90)
			(layer "F.Fab")
			(effects
				(font
					(size 0.7 0.7)
					(thickness 0.15)
				)
				(justify right top)
			)
		)
		(fp_text user "License: Apache-2.0"
			(at -0.939 5.799 90)
			(layer "F.Fab")
			(effects
				(font
					(size 0.7 0.7)
					(thickness 0.15)
				)
				(justify right top)
			)
		)
		(pad "1" smd roundrect
			(at -0.48 0 270)
			(size 0.59 0.64)
			(layers "F.Cu" "F.Mask" "F.Paste")
			(roundrect_rratio 0.25)
			(net 1 "GND")
			(pintype "passive")
		)
		(pad "2" smd roundrect
			(at 0.48 0 270)
			(size 0.59 0.64)
			(layers "F.Cu" "F.Mask" "F.Paste")
			(roundrect_rratio 0.25)
			(net 896 "/DCDC/16V_VDD")
			(pintype "passive")
		)
	)
	(footprint "antmicro-footprints:R_0402_1005Metric"
		(layer "F.Cu")
		(at 179.009468 66.03 90)
		(descr "Resistor SMD 0402")
		(tags "resistor SMD 0402")
		(property "Reference" "R23"
			(at 0.89 0.45 90)
			(layer "F.SilkS")
			(effects
				(font
					(size 0.7 0.7)
					(thickness 0.15)
				)
				(justify left bottom)
			)
		)
		(property "Value" "R_499k_0402"
			(at -1.011843 1.772047 90)
			(layer "F.Fab")
			(effects
				(font
					(size 0.7 0.7)
					(thickness 0.15)
				)
				(justify left bottom)
			)
		)
		(property "Datasheet" "https://www.mouser.com/datasheet/2/54/cr-1858361.pdf"
			(at 0 0 90)
			(layer "F.Fab")
			(hide yes)
			(effects
				(font
					(size 1.27 1.27)
					(thickness 0.15)
				)
			)
		)
		(property "Description" "SMD Chip Resistor, 499 kohm, ± 1%, 63 mW, 0402 [1005 Metric], Thick Film, General Purpose"
			(at 0 0 90)
			(layer "F.Fab")
			(hide yes)
			(effects
				(font
					(size 1.27 1.27)
					(thickness 0.15)
				)
			)
		)
		(property "MPN" "CR0402-FX-4993GLF"
			(at 0 0 90)
			(unlocked yes)
			(layer "F.Fab")
			(hide yes)
			(effects
				(font
					(size 1 1)
					(thickness 0.15)
				)
			)
		)
		(property "Manufacturer" "Bourns"
			(at 0 0 90)
			(unlocked yes)
			(layer "F.Fab")
			(hide yes)
			(effects
				(font
					(size 1 1)
					(thickness 0.15)
				)
			)
		)
		(property "License" "Apache-2.0"
			(at 0 0 90)
			(unlocked yes)
			(layer "F.Fab")
			(hide yes)
			(effects
				(font
					(size 1 1)
					(thickness 0.15)
				)
			)
		)
		(property "Author" "Antmicro"
			(at 0 0 90)
			(unlocked yes)
			(layer "F.Fab")
			(hide yes)
			(effects
				(font
					(size 1 1)
					(thickness 0.15)
				)
			)
		)
		(property "Val" "499k"
			(at 0 0 90)
			(unlocked yes)
			(layer "F.Fab")
			(hide yes)
			(effects
				(font
					(size 1 1)
					(thickness 0.15)
				)
			)
		)
		(property "Tolerance" "1%"
			(at 0 0 90)
			(unlocked yes)
			(layer "F.Fab")
			(hide yes)
			(effects
				(font
					(size 1 1)
					(thickness 0.15)
				)
			)
		)
		(component_classes
			(class "DCDC_20V")
		)
		(sheetname "/DCDC/")
		(sheetfile "dcdc.kicad_sch")
		(attr smd exclude_from_pos_files exclude_from_bom dnp)
		(fp_rect
			(start -0.925 -0.47)
			(end 0.925 0.47)
			(stroke
				(width 0.05)
				(type default)
			)
			(fill no)
			(layer "F.CrtYd")
		)
		(fp_rect
			(start -0.5 -0.25)
			(end 0.5 0.25)
			(stroke
				(width 0.15)
				(type solid)
			)
			(fill no)
			(layer "F.Fab")
		)
		(fp_text user "Author: Antmicro"
			(at -0.95 4.169 90)
			(layer "F.Fab")
			(effects
				(font
					(size 0.7 0.7)
					(thickness 0.15)
				)
				(justify left bottom)
			)
		)
		(fp_text user "License: Apache-2.0"
			(at -0.95 5.169 90)
			(layer "F.Fab")
			(effects
				(font
					(size 0.7 0.7)
					(thickness 0.15)
				)
				(justify left bottom)
			)
		)
		(fp_text user "${REFERENCE}"
			(at -0.95 3.168 90)
			(layer "F.Fab")
			(effects
				(font
					(size 0.7 0.7)
					(thickness 0.15)
				)
				(justify left bottom)
			)
		)
		(pad "1" smd roundrect
			(at -0.48 0 90)
			(size 0.59 0.64)
			(layers "F.Cu" "F.Mask" "F.Paste")
			(roundrect_rratio 0.25)
			(net 1208 "/DCDC/20V_MODE1")
			(pintype "passive")
		)
		(pad "2" smd roundrect
			(at 0.48 0 90)
			(size 0.59 0.64)
			(layers "F.Cu" "F.Mask" "F.Paste")
			(roundrect_rratio 0.25)
			(net 905 "/DCDC/20V_VDD")
			(pintype "passive")
		)
	)
	(footprint "antmicro-footprints:C_0805_2012Metric"
		(layer "F.Cu")
		(at 165.88 93.31 -90)
		(descr "Capacitor SMD 0805")
		(tags "capacitor SMD 0805")
		(property "Reference" "C294"
			(at 1.745 0.425 90)
			(layer "F.SilkS")
			(effects
				(font
					(size 0.7 0.7)
					(thickness 0.15)
				)
				(justify right top)
			)
		)
		(property "Value" "C_22u_25V_0805"
			(at -2.055717 1.963152 90)
			(layer "F.Fab")
			(effects
				(font
					(size 0.7 0.7)
					(thickness 0.15)
				)
				(justify right top)
			)
		)
		(property "Datasheet" "https://product.samsungsem.com/mlcc/CL21A226MAYNNN.do"
			(at 0 0 90)
			(layer "F.Fab")
			(hide yes)
			(effects
				(font
					(size 1.27 1.27)
					(thickness 0.15)
				)
			)
		)
		(property "Description" "SMT Multilayer Ceramic Capacitor, 22uF, +/-20%, 25V, X5R, 0805 [2012 Metric]"
			(at 0 0 90)
			(layer "F.Fab")
			(hide yes)
			(effects
				(font
					(size 1.27 1.27)
					(thickness 0.15)
				)
			)
		)
		(property "MPN" "CL21A226MAYNNNE"
			(at 0 0 270)
			(unlocked yes)
			(layer "F.Fab")
			(hide yes)
			(effects
				(font
					(size 1 1)
					(thickness 0.15)
				)
			)
		)
		(property "Manufacturer" "Samsung Electro-Mechanics"
			(at 0 0 270)
			(unlocked yes)
			(layer "F.Fab")
			(hide yes)
			(effects
				(font
					(size 1 1)
					(thickness 0.15)
				)
			)
		)
		(property "License" "Apache-2.0"
			(at 0 0 270)
			(unlocked yes)
			(layer "F.Fab")
			(hide yes)
			(effects
				(font
					(size 1 1)
					(thickness 0.15)
				)
			)
		)
		(property "Author" "Antmicro"
			(at 0 0 270)
			(unlocked yes)
			(layer "F.Fab")
			(hide yes)
			(effects
				(font
					(size 1 1)
					(thickness 0.15)
				)
			)
		)
		(property "Val" "22u"
			(at 0 0 270)
			(unlocked yes)
			(layer "F.Fab")
			(hide yes)
			(effects
				(font
					(size 1 1)
					(thickness 0.15)
				)
			)
		)
		(property "Voltage" "25V"
			(at 0 0 270)
			(unlocked yes)
			(layer "F.Fab")
			(hide yes)
			(effects
				(font
					(size 1 1)
					(thickness 0.15)
				)
			)
		)
		(property "Dielectric" "X5R"
			(at 0 0 270)
			(unlocked yes)
			(layer "F.Fab")
			(hide yes)
			(effects
				(font
					(size 1 1)
					(thickness 0.15)
				)
			)
		)
		(property "Public" "False"
			(at 0 0 270)
			(unlocked yes)
			(layer "F.Fab")
			(hide yes)
			(effects
				(font
					(size 1 1)
					(thickness 0.15)
				)
			)
		)
		(component_classes
			(class "DCDC_SOM")
		)
		(sheetname "/DCDC/")
		(sheetfile "dcdc.kicad_sch")
		(attr smd)
		(fp_line
			(start -0.3 0.7)
			(end 0.3 0.7)
			(stroke
				(width 0.15)
				(type solid)
			)
			(layer "F.SilkS")
		)
		(fp_line
			(start -0.3 -0.7)
			(end 0.3 -0.7)
			(stroke
				(width 0.15)
				(type solid)
			)
			(layer "F.SilkS")
		)
		(fp_rect
			(start 1.95 -0.9)
			(end -1.95 0.9)
			(stroke
				(width 0.05)
				(type default)
			)
			(fill no)
			(layer "F.CrtYd")
		)
		(fp_rect
			(start -0.95 -0.675)
			(end 0.95 0.675)
			(stroke
				(width 0.15)
				(type solid)
			)
			(fill no)
			(layer "F.Fab")
		)
		(fp_text user "${REFERENCE}"
			(at -1.9 3.947 90)
			(layer "F.Fab")
			(effects
				(font
					(size 0.7 0.7)
					(thickness 0.15)
				)
				(justify right top)
			)
		)
		(fp_text user "Author: Antmicro"
			(at -1.9 5.947 90)
			(layer "F.Fab")
			(effects
				(font
					(size 0.7 0.7)
					(thickness 0.15)
				)
				(justify right top)
			)
		)
		(fp_text user "License: Apache-2.0"
			(at -1.9 4.947 90)
			(layer "F.Fab")
			(effects
				(font
					(size 0.7 0.7)
					(thickness 0.15)
				)
				(justify right top)
			)
		)
		(pad "1" smd roundrect
			(at -1.1 0 270)
			(size 1.2 1.3)
			(layers "F.Cu" "F.Mask" "F.Paste")
			(roundrect_rratio 0.25)
			(net 1 "GND")
			(pintype "passive")
		)
		(pad "2" smd roundrect
			(at 1.1 0 270)
			(size 1.2 1.3)
			(layers "F.Cu" "F.Mask" "F.Paste")
			(roundrect_rratio 0.25)
			(net 903 "/DCDC/16V_OUT")
			(pintype "passive")
		)
	)
	(footprint "antmicro-footprints:C_0402_1005Metric"
		(layer "F.Cu")
		(at 152.48 121.5 180)
		(descr "Capacitor SMD 0402")
		(tags "capacitor SMD 0402")
		(property "Reference" "C2"
			(at -2.42 0.3 0)
			(layer "F.SilkS")
			(effects
				(font
					(size 0.7 0.7)
					(thickness 0.15)
				)
				(justify right top)
			)
		)
		(property "Value" "C_100n_0402"
			(at -1.022927 2.155213 0)
			(layer "F.Fab")
			(effects
				(font
					(size 0.7 0.7)
					(thickness 0.15)
				)
				(justify right top)
			)
		)
		(property "Datasheet" "https://www.murata.com/products/productdetail?partno=GRM155R61H104KE14%23"
			(at 0 0 0)
			(layer "F.Fab")
			(hide yes)
			(effects
				(font
					(size 1.27 1.27)
					(thickness 0.15)
				)
			)
		)
		(property "Description" "SMD Multilayer Ceramic Capacitor, 0.1 µF, 50 V, 0402 [1005 Metric], ± 10%, X5R, GRM Series"
			(at 0 0 0)
			(layer "F.Fab")
			(hide yes)
			(effects
				(font
					(size 1.27 1.27)
					(thickness 0.15)
				)
			)
		)
		(property "Manufacturer" "Murata"
			(at 0 0 180)
			(unlocked yes)
			(layer "F.Fab")
			(hide yes)
			(effects
				(font
					(size 1 1)
					(thickness 0.15)
				)
			)
		)
		(property "MPN" "GRM155R61H104KE14D"
			(at 0 0 180)
			(unlocked yes)
			(layer "F.Fab")
			(hide yes)
			(effects
				(font
					(size 1 1)
					(thickness 0.15)
				)
			)
		)
		(property "Val" "100n"
			(at 0 0 180)
			(unlocked yes)
			(layer "F.Fab")
			(hide yes)
			(effects
				(font
					(size 1 1)
					(thickness 0.15)
				)
			)
		)
		(property "License" "Apache-2.0"
			(at 0 0 180)
			(unlocked yes)
			(layer "F.Fab")
			(hide yes)
			(effects
				(font
					(size 1 1)
					(thickness 0.15)
				)
			)
		)
		(property "Author" "Antmicro"
			(at 0 0 180)
			(unlocked yes)
			(layer "F.Fab")
			(hide yes)
			(effects
				(font
					(size 1 1)
					(thickness 0.15)
				)
			)
		)
		(property "Voltage" "50V"
			(at 0 0 180)
			(unlocked yes)
			(layer "F.Fab")
			(hide yes)
			(effects
				(font
					(size 1 1)
					(thickness 0.15)
				)
			)
		)
		(property "Dielectric" "X5R"
			(at 0 0 180)
			(unlocked yes)
			(layer "F.Fab")
			(hide yes)
			(effects
				(font
					(size 1 1)
					(thickness 0.15)
				)
			)
		)
		(sheetname "/SoM_IO/")
		(sheetfile "som_io.kicad_sch")
		(attr smd)
		(fp_poly
			(pts
				(xy -0.925 -0.47) (xy -0.925 0.47) (xy 0.925 0.47) (xy 0.925 -0.47)
			)
			(stroke
				(width 0.05)
				(type default)
			)
			(fill no)
			(layer "F.CrtYd")
		)
		(fp_line
			(start 0.504 0.248)
			(end -0.494 0.248)
			(stroke
				(width 0.15)
				(type solid)
			)
			(layer "F.Fab")
		)
		(fp_line
			(start 0.504 -0.25)
			(end 0.504 0.248)
			(stroke
				(width 0.15)
				(type solid)
			)
			(layer "F.Fab")
		)
		(fp_line
			(start -0.494 0.248)
			(end -0.494 -0.25)
			(stroke
				(width 0.15)
				(type solid)
			)
			(layer "F.Fab")
		)
		(fp_line
			(start -0.494 -0.25)
			(end 0.504 -0.25)
			(stroke
				(width 0.15)
				(type solid)
			)
			(layer "F.Fab")
		)
		(fp_text user "License: Apache-2.0"
			(at -0.939 5.799 0)
			(layer "F.Fab")
			(effects
				(font
					(size 0.7 0.7)
					(thickness 0.15)
				)
				(justify right top)
			)
		)
		(fp_text user "${REFERENCE}"
			(at -0.939 4.599 0)
			(layer "F.Fab")
			(effects
				(font
					(size 0.7 0.7)
					(thickness 0.15)
				)
				(justify right top)
			)
		)
		(fp_text user "Author: Antmicro"
			(at -0.939 3.399 0)
			(layer "F.Fab")
			(effects
				(font
					(size 0.7 0.7)
					(thickness 0.15)
				)
				(justify right top)
			)
		)
		(pad "1" smd roundrect
			(at -0.48 0 180)
			(size 0.59 0.64)
			(layers "F.Cu" "F.Mask" "F.Paste")
			(roundrect_rratio 0.25)
			(net 1 "GND")
			(pintype "passive")
		)
		(pad "2" smd roundrect
			(at 0.48 0 180)
			(size 0.59 0.64)
			(layers "F.Cu" "F.Mask" "F.Paste")
			(roundrect_rratio 0.25)
			(net 2 "+3V3")
			(pintype "passive")
		)
	)
	(footprint "antmicro-footprints:MLP44-24L_4x4x0.75mm"
		(layer "F.Cu")
		(at 179.7 70.45)
		(property "Reference" "U65"
			(at -3.36 0.73 90)
			(layer "F.SilkS")
			(effects
				(font
					(size 0.7 0.7)
					(thickness 0.15)
				)
				(justify right top)
			)
		)
		(property "Value" "SIC437AED-T1-GE3"
			(at -2.7 3.6 0)
			(layer "F.Fab")
			(effects
				(font
					(size 0.7 0.7)
					(thickness 0.15)
				)
				(justify left bottom)
			)
		)
		(property "Datasheet" "https://www.vishay.com/docs/75921/sic437.pdf"
			(at 0 0 0)
			(layer "F.Fab")
			(hide yes)
			(effects
				(font
					(size 1.27 1.27)
					(thickness 0.15)
				)
			)
		)
		(property "Description" "DC/DC Buck Step Down Regulator Adjustable, 4.5-28V In, 0.6V to 20V/12A Out, 1MHz, PowerPAK MLP44-24"
			(at 0 0 0)
			(layer "F.Fab")
			(hide yes)
			(effects
				(font
					(size 1.27 1.27)
					(thickness 0.15)
				)
			)
		)
		(property "Manufacturer" "Vishay"
			(at 0 0 0)
			(unlocked yes)
			(layer "F.Fab")
			(hide yes)
			(effects
				(font
					(size 1 1)
					(thickness 0.15)
				)
			)
		)
		(property "MPN" "SIC437AED-T1-GE3"
			(at 0 0 0)
			(unlocked yes)
			(layer "F.Fab")
			(hide yes)
			(effects
				(font
					(size 1 1)
					(thickness 0.15)
				)
			)
		)
		(property "Author" "Antmicro"
			(at 0 0 0)
			(unlocked yes)
			(layer "F.Fab")
			(hide yes)
			(effects
				(font
					(size 1 1)
					(thickness 0.15)
				)
			)
		)
		(property "License" "Apache-2.0"
			(at 0 0 0)
			(unlocked yes)
			(layer "F.Fab")
			(hide yes)
			(effects
				(font
					(size 1 1)
					(thickness 0.15)
				)
			)
		)
		(component_classes
			(class "DCDC_20V")
		)
		(sheetname "/DCDC/")
		(sheetfile "dcdc.kicad_sch")
		(attr smd)
		(net_tie_pad_groups "1,2,26" "3,4,27" "5,6,7,8,9")
		(fp_line
			(start -2.11 -1.38)
			(end -2.11 -2.1)
			(stroke
				(width 0.15)
				(type solid)
			)
			(layer "F.SilkS")
		)
		(fp_line
			(start -2.11 2.11)
			(end -2.11 1.39)
			(stroke
				(width 0.15)
				(type solid)
			)
			(layer "F.SilkS")
		)
		(fp_line
			(start -1.89 -2.1)
			(end -2.11 -2.1)
			(stroke
				(width 0.15)
				(type solid)
			)
			(layer "F.SilkS")
		)
		(fp_line
			(start -1.89 2.11)
			(end -2.11 2.11)
			(stroke
				(width 0.15)
				(type solid)
			)
			(layer "F.SilkS")
		)
		(fp_line
			(start 1.44 2.11)
			(end 2.11 2.11)
			(stroke
				(width 0.15)
				(type solid)
			)
			(layer "F.SilkS")
		)
		(fp_line
			(start 1.89 -2.11)
			(end 2.11 -2.11)
			(stroke
				(width 0.15)
				(type solid)
			)
			(layer "F.SilkS")
		)
		(fp_line
			(start 2.11 -2.11)
			(end 2.11 -1.69)
			(stroke
				(width 0.15)
				(type solid)
			)
			(layer "F.SilkS")
		)
		(fp_line
			(start 2.11 2.11)
			(end 2.11 1.84)
			(stroke
				(width 0.15)
				(type solid)
			)
			(layer "F.SilkS")
		)
		(fp_circle
			(center -2.25 -1.15)
			(end -2.2 -1.15)
			(stroke
				(width 0.15)
				(type solid)
			)
			(fill yes)
			(layer "F.SilkS")
		)
		(fp_line
			(start -2.55 -2.55)
			(end 2.55 -2.55)
			(stroke
				(width 0.05)
				(type solid)
			)
			(layer "F.CrtYd")
		)
		(fp_line
			(start -2.55 2.55)
			(end -2.55 -2.55)
			(stroke
				(width 0.05)
				(type solid)
			)
			(layer "F.CrtYd")
		)
		(fp_line
			(start 2.55 -2.55)
			(end 2.55 2.55)
			(stroke
				(width 0.05)
				(type solid)
			)
			(layer "F.CrtYd")
		)
		(fp_line
			(start 2.55 2.55)
			(end -2.55 2.55)
			(stroke
				(width 0.05)
				(type solid)
			)
			(layer "F.CrtYd")
		)
		(fp_line
			(start -2 -1)
			(end -2 2)
			(stroke
				(width 0.15)
				(type solid)
			)
			(layer "F.Fab")
		)
		(fp_line
			(start -2 2)
			(end 2 2)
			(stroke
				(width 0.15)
				(type solid)
			)
			(layer "F.Fab")
		)
		(fp_line
			(start -1 -2)
			(end -2 -1)
			(stroke
				(width 0.15)
				(type solid)
			)
			(layer "F.Fab")
		)
		(fp_line
			(start 2 -2)
			(end -1 -2)
			(stroke
				(width 0.15)
				(type solid)
			)
			(layer "F.Fab")
		)
		(fp_line
			(start 2 2)
			(end 2 -2)
			(stroke
				(width 0.15)
				(type solid)
			)
			(layer "F.Fab")
		)
		(fp_text user "Author: Antmicro"
			(at -2.7 8 0)
			(layer "F.Fab")
			(effects
				(font
					(size 0.7 0.7)
					(thickness 0.15)
				)
				(justify left bottom)
			)
		)
		(fp_text user "License: Apache-2.0"
			(at -2.7 5.6 0)
			(layer "F.Fab")
			(effects
				(font
					(size 0.7 0.7)
					(thickness 0.15)
				)
				(justify left bottom)
			)
		)
		(fp_text user "${REFERENCE}"
			(at -2.7 6.8 0)
			(layer "F.Fab")
			(effects
				(font
					(size 0.7 0.7)
					(thickness 0.15)
				)
				(justify left bottom)
			)
		)
		(pad "1" smd roundrect
			(at -1.94 -0.825 90)
			(size 0.3 0.725)
			(layers "F.Cu" "F.Mask" "F.Paste")
			(roundrect_rratio 0.25)
			(net 13 "VCC")
			(pinfunction "V_{IN}")
			(pintype "power_in")
		)
		(pad "2" smd roundrect
			(at -1.94 -0.375 90)
			(size 0.3 0.725)
			(layers "F.Cu" "F.Mask" "F.Paste")
			(roundrect_rratio 0.25)
			(net 13 "VCC")
			(pinfunction "V_{IN}")
			(pintype "passive")
		)
		(pad "3" smd roundrect
			(at -1.94 0.525 90)
			(size 0.3 0.725)
			(layers "F.Cu" "F.Mask" "F.Paste")
			(roundrect_rratio 0.25)
			(net 1 "GND")
			(pinfunction "P_{GND}")
			(pintype "passive")
		)
		(pad "4" smd roundrect
			(at -1.94 0.975 90)
			(size 0.3 0.725)
			(layers "F.Cu" "F.Mask" "F.Paste")
			(roundrect_rratio 0.25)
			(net 1 "GND")
			(pinfunction "P_{GND}")
			(pintype "passive")
		)
		(pad "5" smd custom
			(at -1.475 1.94)
			(size 0.3 0.3)
			(layers "F.Cu" "F.Mask" "F.Paste")
			(net 1184 "/DCDC/20V_SW")
			(pinfunction "SW")
			(pintype "passive")
			(options
				(clearance outline)
				(anchor circle)
			)
			(primitives
				(gr_poly
					(pts
						(xy -0.15 -0.2875) (xy -0.144291 -0.316201) (xy -0.128033 -0.340533) (xy -0.103701 -0.356791)
						(xy -0.075 -0.3625) (xy 0.075 -0.3625) (xy 0.103701 -0.356791) (xy 0.128033 -0.340533) (xy 0.144291 -0.316201)
						(xy 0.15 -0.2875) (xy 0.15 0.2875) (xy 0.144291 0.316201) (xy 0.128033 0.340533) (xy 0.103701 0.356791)
						(xy 0.075 0.3625) (xy -0.075 0.3625) (xy -0.103701 0.356791) (xy -0.128033 0.340533) (xy -0.144291 0.316201)
						(xy -0.15 0.2875)
					)
					(width 0)
					(fill yes)
				)
				(gr_poly
					(pts
						(xy -0.15 -0.3625) (xy 2.2 -0.3625) (xy 2.2 -0.0875) (xy -0.15 -0.0875)
					)
					(width 0)
					(fill yes)
				)
			)
		)
		(pad "6" smd roundrect
			(at -1.025 1.94)
			(size 0.3 0.725)
			(layers "F.Cu" "F.Mask" "F.Paste")
			(roundrect_rratio 0.25)
			(net 1184 "/DCDC/20V_SW")
			(pinfunction "SW")
			(pintype "passive")
		)
		(pad "7" smd roundrect
			(at -0.575 1.94)
			(size 0.3 0.725)
			(layers "F.Cu" "F.Mask" "F.Paste")
			(roundrect_rratio 0.25)
			(net 1184 "/DCDC/20V_SW")
			(pinfunction "SW")
			(pintype "passive")
		)
		(pad "8" smd roundrect
			(at 0.125 1.94)
			(size 0.3 0.725)
			(layers "F.Cu" "F.Mask" "F.Paste")
			(roundrect_rratio 0.25)
			(net 1184 "/DCDC/20V_SW")
			(pinfunction "SW")
			(pintype "passive")
		)
		(pad "9" smd roundrect
			(at 0.575 1.94)
			(size 0.3 0.725)
			(layers "F.Cu" "F.Mask" "F.Paste")
			(roundrect_rratio 0.25)
			(net 1184 "/DCDC/20V_SW")
			(pinfunction "SW")
			(pintype "passive")
		)
		(pad "10" smd roundrect
			(at 1.025 1.935)
			(size 0.3 0.725)
			(layers "F.Cu" "F.Mask" "F.Paste")
			(roundrect_rratio 0.25)
			(net 1231 "unconnected-(U65-GL-Pad10)_2")
			(pinfunction "GL")
			(pintype "passive+no_connect")
		)
		(pad "11" smd roundrect
			(at 1.94 1.425 90)
			(size 0.3 0.725)
			(layers "F.Cu" "F.Mask" "F.Paste")
			(roundrect_rratio 0.25)
			(net 1230 "unconnected-(U65-GL-Pad10)_1")
			(pinfunction "GL")
			(pintype "passive+no_connect")
		)
		(pad "12" smd roundrect
			(at 1.94 0.975 90)
			(size 0.3 0.725)
			(layers "F.Cu" "F.Mask" "F.Paste")
			(roundrect_rratio 0.25)
			(net 1081 "/DCDC/20V_VDRV")
			(pinfunction "V_{DRV}")
			(pintype "passive")
		)
		(pad "13" smd roundrect
			(at 1.94 0.525 90)
			(size 0.3 0.725)
			(layers "F.Cu" "F.Mask" "F.Paste")
			(roundrect_rratio 0.25)
			(net 1 "GND")
			(pinfunction "P_{GND}")
			(pintype "power_in")
		)
		(pad "14" smd roundrect
			(at 1.94 0.075 90)
			(size 0.3 0.725)
			(layers "F.Cu" "F.Mask" "F.Paste")
			(roundrect_rratio 0.25)
			(net 1228 "unconnected-(U65-P_{GOOD}-Pad14)")
			(pinfunction "P_{GOOD}")
			(pintype "output+no_connect")
		)
		(pad "15" smd roundrect
			(at 1.94 -0.375 90)
			(size 0.3 0.725)
			(layers "F.Cu" "F.Mask" "F.Paste")
			(roundrect_rratio 0.25)
			(net 905 "/DCDC/20V_VDD")
			(pinfunction "V_{DD}")
			(pintype "passive")
		)
		(pad "16" smd roundrect
			(at 1.94 -0.825 90)
			(size 0.3 0.725)
			(layers "F.Cu" "F.Mask" "F.Paste")
			(roundrect_rratio 0.25)
			(net 1 "GND")
			(pinfunction "A_{GND}")
			(pintype "power_in")
		)
		(pad "17" smd roundrect
			(at 1.94 -1.275 90)
			(size 0.3 0.725)
			(layers "F.Cu" "F.Mask" "F.Paste")
			(roundrect_rratio 0.25)
			(net 1220 "/DCDC/20V_FB")
			(pinfunction "FB")
			(pintype "passive")
		)
		(pad "18" smd roundrect
			(at 1.475 -1.94)
			(size 0.3 0.725)
			(layers "F.Cu" "F.Mask" "F.Paste")
			(roundrect_rratio 0.25)
			(net 1105 "/DCDC/20V_OUT")
			(pinfunction "V_{OUT}")
			(pintype "passive")
		)
		(pad "19" smd roundrect
			(at 1.025 -1.94)
			(size 0.3 0.725)
			(layers "F.Cu" "F.Mask" "F.Paste")
			(roundrect_rratio 0.25)
			(net 1211 "/DCDC/20V_EN")
			(pinfunction "EN")
			(pintype "input")
		)
		(pad "20" smd roundrect
			(at 0.575 -1.94)
			(size 0.3 0.725)
			(layers "F.Cu" "F.Mask" "F.Paste")
			(roundrect_rratio 0.25)
			(net 1210 "/DCDC/20V_MODE2")
			(pinfunction "MODE2")
			(pintype "input")
		)
		(pad "21" smd roundrect
			(at 0.125 -1.94)
			(size 0.3 0.725)
			(layers "F.Cu" "F.Mask" "F.Paste")
			(roundrect_rratio 0.25)
			(net 1208 "/DCDC/20V_MODE1")
			(pinfunction "MODE1")
			(pintype "input")
		)
		(pad "22" smd roundrect
			(at -0.575 -1.94)
			(size 0.3 0.725)
			(layers "F.Cu" "F.Mask" "F.Paste")
			(roundrect_rratio 0.25)
			(net 13 "VCC")
			(pinfunction "V_{IN}")
			(pintype "passive")
		)
		(pad "23" smd roundrect
			(at -1.025 -1.94)
			(size 0.3 0.725)
			(layers "F.Cu" "F.Mask" "F.Paste")
			(roundrect_rratio 0.25)
			(net 1086 "/DCDC/20V_BOOT")
			(pinfunction "BOOT")
			(pintype "passive")
		)
		(pad "24" smd roundrect
			(at -1.475 -1.94)
			(size 0.3 0.725)
			(layers "F.Cu" "F.Mask" "F.Paste")
			(roundrect_rratio 0.25)
			(net 1104 "/DCDC/20V_PHASE")
			(pinfunction "PHASE")
			(pintype "passive")
		)
		(pad "25" smd rect
			(at 0.49 -0.75 180)
			(size 1.575 1.05)
			(layers "F.Cu" "F.Mask" "F.Paste")
			(net 1 "GND")
			(pinfunction "A_{GND}")
			(pintype "passive")
		)
		(pad "26" smd rect
			(at -1.175 -0.75 180)
			(size 1.15 1.05)
			(layers "F.Cu" "F.Mask" "F.Paste")
			(net 13 "VCC")
			(pinfunction "V_{IN}")
			(pintype "passive")
		)
		(pad "27" smd custom
			(at -0.75 0.775)
			(size 1 1)
			(layers "F.Cu" "F.Mask" "F.Paste")
			(net 1 "GND")
			(pinfunction "P_{GND}")
			(pintype "passive")
			(options
				(clearance outline)
				(anchor rect)
			)
			(primitives
				(gr_poly
					(pts
						(xy -1 0.5) (xy -1 -0.7) (xy 1.825 -0.7) (xy 1.825 -0.245) (xy 1.175 -0.245) (xy 1.175 0.5)
					)
					(width 0)
					(fill yes)
				)
			)
		)
		(pad "28" smd rect
			(at 0.985 0.99 180)
			(size 0.58 0.38)
			(layers "F.Cu" "F.Mask" "F.Paste")
			(net 1229 "unconnected-(U65-GL-Pad10)")
			(pinfunction "GL")
			(pintype "passive+no_connect")
		)
	)
	(footprint "antmicro-footprints:C_0402_1005Metric"
		(layer "F.Cu")
		(at 184.044468 127.21 -90)
		(descr "Capacitor SMD 0402")
		(tags "capacitor SMD 0402")
		(property "Reference" "C53"
			(at -1.11 -0.555532 90)
			(layer "F.SilkS")
			(effects
				(font
					(size 0.7 0.7)
					(thickness 0.15)
				)
				(justify right top)
			)
		)
		(property "Value" "C_1u_0402"
			(at -1.022927 2.155213 90)
			(layer "F.Fab")
			(effects
				(font
					(size 0.7 0.7)
					(thickness 0.15)
				)
				(justify right top)
			)
		)
		(property "Datasheet" "https://product.tdk.com/en/search/capacitor/ceramic/mlcc/info?part_no=C1005X6S1A105K050BC"
			(at 0 0 90)
			(layer "F.Fab")
			(hide yes)
			(effects
				(font
					(size 1.27 1.27)
					(thickness 0.15)
				)
			)
		)
		(property "Description" "SMD Multilayer Ceramic Capacitor, 1 µF, 10 V, 0402 [1005 Metric], ± 10%, X6S, C"
			(at 0 0 90)
			(layer "F.Fab")
			(hide yes)
			(effects
				(font
					(size 1.27 1.27)
					(thickness 0.15)
				)
			)
		)
		(property "Manufacturer" "TDK"
			(at 0 0 270)
			(unlocked yes)
			(layer "F.Fab")
			(hide yes)
			(effects
				(font
					(size 1 1)
					(thickness 0.15)
				)
			)
		)
		(property "MPN" "C1005X6S1A105K050BC"
			(at 0 0 270)
			(unlocked yes)
			(layer "F.Fab")
			(hide yes)
			(effects
				(font
					(size 1 1)
					(thickness 0.15)
				)
			)
		)
		(property "Val" "1u"
			(at 0 0 270)
			(unlocked yes)
			(layer "F.Fab")
			(hide yes)
			(effects
				(font
					(size 1 1)
					(thickness 0.15)
				)
			)
		)
		(property "License" "Apache-2.0"
			(at 0 0 270)
			(unlocked yes)
			(layer "F.Fab")
			(hide yes)
			(effects
				(font
					(size 1 1)
					(thickness 0.15)
				)
			)
		)
		(property "Author" "Antmicro"
			(at 0 0 270)
			(unlocked yes)
			(layer "F.Fab")
			(hide yes)
			(effects
				(font
					(size 1 1)
					(thickness 0.15)
				)
			)
		)
		(property "Voltage" ""
			(at 0 0 270)
			(unlocked yes)
			(layer "F.Fab")
			(hide yes)
			(effects
				(font
					(size 1 1)
					(thickness 0.15)
				)
			)
		)
		(property "Dielectric" ""
			(at 0 0 270)
			(unlocked yes)
			(layer "F.Fab")
			(hide yes)
			(effects
				(font
					(size 1 1)
					(thickness 0.15)
				)
			)
		)
		(sheetname "/DCDC/")
		(sheetfile "dcdc.kicad_sch")
		(attr smd)
		(fp_rect
			(start -0.925 -0.47)
			(end 0.925 0.47)
			(stroke
				(width 0.05)
				(type default)
			)
			(fill no)
			(layer "F.CrtYd")
		)
		(fp_line
			(start -0.494 0.248)
			(end -0.494 -0.25)
			(stroke
				(width 0.15)
				(type solid)
			)
			(layer "F.Fab")
		)
		(fp_line
			(start 0.504 0.248)
			(end -0.494 0.248)
			(stroke
				(width 0.15)
				(type solid)
			)
			(layer "F.Fab")
		)
		(fp_line
			(start -0.494 -0.25)
			(end 0.504 -0.25)
			(stroke
				(width 0.15)
				(type solid)
			)
			(layer "F.Fab")
		)
		(fp_line
			(start 0.504 -0.25)
			(end 0.504 0.248)
			(stroke
				(width 0.15)
				(type solid)
			)
			(layer "F.Fab")
		)
		(fp_text user "Author: Antmicro"
			(at -0.939 3.399 90)
			(layer "F.Fab")
			(effects
				(font
					(size 0.7 0.7)
					(thickness 0.15)
				)
				(justify right top)
			)
		)
		(fp_text user "License: Apache-2.0"
			(at -0.939 5.799 90)
			(layer "F.Fab")
			(effects
				(font
					(size 0.7 0.7)
					(thickness 0.15)
				)
				(justify right top)
			)
		)
		(fp_text user "${REFERENCE}"
			(at -0.939 4.599 90)
			(layer "F.Fab")
			(effects
				(font
					(size 0.7 0.7)
					(thickness 0.15)
				)
				(justify right top)
			)
		)
		(pad "1" smd roundrect
			(at -0.48 0 270)
			(size 0.59 0.64)
			(layers "F.Cu" "F.Mask" "F.Paste")
			(roundrect_rratio 0.25)
			(net 1 "GND")
			(pintype "passive")
		)
		(pad "2" smd roundrect
			(at 0.48 0 270)
			(size 0.59 0.64)
			(layers "F.Cu" "F.Mask" "F.Paste")
			(roundrect_rratio 0.25)
			(net 19 "/DCDC/3V3_VDD")
			(pintype "passive")
		)
	)
	(footprint "antmicro-footprints:SOT-23-8"
		(layer "F.Cu")
		(at 102.74 56.53 180)
		(descr "http://www.ti.com/lit/ds/symlink/ina219.pdf")
		(property "Reference" "U76"
			(at 1.06 2.33 0)
			(layer "F.SilkS")
			(effects
				(font
					(size 0.7 0.7)
					(thickness 0.15)
				)
				(justify right top)
			)
		)
		(property "Value" "INA219AIDCNR"
			(at -2.925 2.8 0)
			(layer "F.Fab")
			(effects
				(font
					(size 0.7 0.7)
					(thickness 0.15)
				)
				(justify right top)
			)
		)
		(property "Datasheet" "https://www.ti.com/lit/ds/symlink/ina219.pdf?ts=1713856455637&ref_url=https%253A%252F%252Fwww.mouser.es%252F"
			(at 0 0 0)
			(layer "F.Fab")
			(hide yes)
			(effects
				(font
					(size 1.27 1.27)
					(thickness 0.15)
				)
			)
		)
		(property "Description" "Zerø-Drift, Bidirectional Current/Power Monitor With I2C Interface"
			(at 0 0 0)
			(layer "F.Fab")
			(hide yes)
			(effects
				(font
					(size 1.27 1.27)
					(thickness 0.15)
				)
			)
		)
		(property "Manufacturer" "Texas Instruments"
			(at 0 0 180)
			(unlocked yes)
			(layer "F.Fab")
			(hide yes)
			(effects
				(font
					(size 1 1)
					(thickness 0.15)
				)
			)
		)
		(property "MPN" "INA219AIDCNR"
			(at 0 0 180)
			(unlocked yes)
			(layer "F.Fab")
			(hide yes)
			(effects
				(font
					(size 1 1)
					(thickness 0.15)
				)
			)
		)
		(property "Author" "Antmicro"
			(at 0 0 180)
			(unlocked yes)
			(layer "F.Fab")
			(hide yes)
			(effects
				(font
					(size 1 1)
					(thickness 0.15)
				)
			)
		)
		(property "License" "Apache-2.0"
			(at 0 0 180)
			(unlocked yes)
			(layer "F.Fab")
			(hide yes)
			(effects
				(font
					(size 1 1)
					(thickness 0.15)
				)
			)
		)
		(sheetname "/DCDC/")
		(sheetfile "dcdc.kicad_sch")
		(attr smd)
		(fp_line
			(start 1 1.6)
			(end 0.6 1.6)
			(stroke
				(width 0.15)
				(type solid)
			)
			(layer "F.SilkS")
		)
		(fp_line
			(start 1 1.3)
			(end 1 1.6)
			(stroke
				(width 0.15)
				(type solid)
			)
			(layer "F.SilkS")
		)
		(fp_line
			(start 1 -1.3)
			(end 1 -1.6)
			(stroke
				(width 0.15)
				(type solid)
			)
			(layer "F.SilkS")
		)
		(fp_line
			(start 1 -1.6)
			(end 0.625 -1.6)
			(stroke
				(width 0.15)
				(type solid)
			)
			(layer "F.SilkS")
		)
		(fp_line
			(start -0.613 1.6)
			(end -0.987 1.6)
			(stroke
				(width 0.15)
				(type solid)
			)
			(layer "F.SilkS")
		)
		(fp_line
			(start -0.987 1.6)
			(end -0.987 1.324)
			(stroke
				(width 0.15)
				(type solid)
			)
			(layer "F.SilkS")
		)
		(fp_line
			(start -1 -1.3)
			(end -1 -1.6)
			(stroke
				(width 0.15)
				(type solid)
			)
			(layer "F.SilkS")
		)
		(fp_line
			(start -1 -1.6)
			(end -0.6 -1.6)
			(stroke
				(width 0.15)
				(type solid)
			)
			(layer "F.SilkS")
		)
		(fp_circle
			(center -1.3 -1.4)
			(end -1.25 -1.4)
			(stroke
				(width 0.15)
				(type solid)
			)
			(fill yes)
			(layer "F.SilkS")
		)
		(fp_poly
			(pts
				(xy -1.9 -1.75) (xy 1.898 -1.75) (xy 1.898 1.75) (xy -1.9 1.75)
			)
			(stroke
				(width 0.05)
				(type solid)
			)
			(fill no)
			(layer "F.CrtYd")
		)
		(fp_line
			(start -1.4 -1.25)
			(end -1.2 -1.45)
			(stroke
				(width 0.15)
				(type solid)
			)
			(layer "F.Fab")
		)
		(fp_poly
			(pts
				(xy -1.401 -1.45) (xy 1.398 -1.45) (xy 1.398 1.449) (xy -1.401 1.449)
			)
			(stroke
				(width 0.15)
				(type solid)
			)
			(fill no)
			(layer "F.Fab")
		)
		(fp_text user "${REFERENCE}"
			(at -2.925 4.8 0)
			(layer "F.Fab")
			(effects
				(font
					(size 0.7 0.7)
					(thickness 0.15)
				)
				(justify right top)
			)
		)
		(fp_text user "License: Apache-2.0"
			(at -2.925 6 0)
			(layer "F.Fab")
			(effects
				(font
					(size 0.7 0.7)
					(thickness 0.15)
				)
				(justify right top)
			)
		)
		(fp_text user "Author: Antmicro"
			(at -2.925 7.2 0)
			(layer "F.Fab")
			(effects
				(font
					(size 0.7 0.7)
					(thickness 0.15)
				)
				(justify right top)
			)
		)
		(pad "1" smd roundrect
			(at -1.3 -0.975 90)
			(size 0.45 1.1)
			(layers "F.Cu" "F.Mask" "F.Paste")
			(roundrect_rratio 0.25)
			(net 1280 "Net-(U76-IN+)")
			(pinfunction "IN+")
			(pintype "passive")
		)
		(pad "2" smd roundrect
			(at -1.3 -0.325 90)
			(size 0.45 1.1)
			(layers "F.Cu" "F.Mask" "F.Paste")
			(roundrect_rratio 0.25)
			(net 1279 "Net-(U76-IN-)")
			(pinfunction "IN-")
			(pintype "passive")
		)
		(pad "3" smd roundrect
			(at -1.3 0.325 90)
			(size 0.45 1.1)
			(layers "F.Cu" "F.Mask" "F.Paste")
			(roundrect_rratio 0.25)
			(net 1 "GND")
			(pinfunction "GND")
			(pintype "power_in")
		)
		(pad "4" smd roundrect
			(at -1.3 0.975 90)
			(size 0.45 1.1)
			(layers "F.Cu" "F.Mask" "F.Paste")
			(roundrect_rratio 0.25)
			(net 4 "+3V3_AON")
			(pinfunction "V_{S}")
			(pintype "power_in")
		)
		(pad "5" smd roundrect
			(at 1.3 0.975 90)
			(size 0.45 1.1)
			(layers "F.Cu" "F.Mask" "F.Paste")
			(roundrect_rratio 0.25)
			(net 853 "/I2C_{SYS}.SCL")
			(pinfunction "SCL")
			(pintype "open_collector")
		)
		(pad "6" smd roundrect
			(at 1.3 0.325 90)
			(size 0.45 1.1)
			(layers "F.Cu" "F.Mask" "F.Paste")
			(roundrect_rratio 0.25)
			(net 850 "/I2C_{SYS}.SDA")
			(pinfunction "SDA")
			(pintype "open_collector")
		)
		(pad "7" smd roundrect
			(at 1.3 -0.325 90)
			(size 0.45 1.1)
			(layers "F.Cu" "F.Mask" "F.Paste")
			(roundrect_rratio 0.25)
			(net 850 "/I2C_{SYS}.SDA")
			(pinfunction "A0")
			(pintype "passive")
		)
		(pad "8" smd roundrect
			(at 1.3 -0.975 90)
			(size 0.45 1.1)
			(layers "F.Cu" "F.Mask" "F.Paste")
			(roundrect_rratio 0.25)
			(net 4 "+3V3_AON")
			(pinfunction "A1")
			(pintype "passive")
		)
	)
	(footprint "antmicro-footprints:IC_TPS65987DDHRSHR"
		(layer "F.Cu")
		(at 200.599 78.48 180)
		(property "Reference" "U30"
			(at -4.801 4.98 180)
			(layer "F.SilkS")
			(effects
				(font
					(size 0.7 0.7)
					(thickness 0.15)
				)
				(justify right top)
			)
		)
		(property "Value" "TPS65988DHRSHR"
			(at 0 4.9 0)
			(layer "F.Fab")
			(effects
				(font
					(size 0.7 0.7)
					(thickness 0.15)
				)
				(justify right top)
			)
		)
		(property "Datasheet" "https://www.ti.com/lit/ds/symlink/tps65988.pdf?ts=1662726631004&ref_url=https%253A%252F%252Fwww.ti.com%252Fproduct%252FTPS65988"
			(at 0 0 0)
			(layer "F.Fab")
			(hide yes)
			(effects
				(font
					(size 1.27 1.27)
					(thickness 0.15)
				)
			)
		)
		(property "Description" "USB, Type-C Controller PMIC 56-VQFN (7x7)"
			(at 0 0 0)
			(layer "F.Fab")
			(hide yes)
			(effects
				(font
					(size 1.27 1.27)
					(thickness 0.15)
				)
			)
		)
		(property "MPN" "TPS65988DHRSHR "
			(at 0 0 180)
			(unlocked yes)
			(layer "F.Fab")
			(hide yes)
			(effects
				(font
					(size 1 1)
					(thickness 0.15)
				)
			)
		)
		(property "Manufacturer" "Texas Instruments"
			(at 0 0 180)
			(unlocked yes)
			(layer "F.Fab")
			(hide yes)
			(effects
				(font
					(size 1 1)
					(thickness 0.15)
				)
			)
		)
		(property "License" "Apache-2.0"
			(at 0 0 180)
			(unlocked yes)
			(layer "F.Fab")
			(hide yes)
			(effects
				(font
					(size 1 1)
					(thickness 0.15)
				)
			)
		)
		(property "Author" "Antmicro"
			(at 0 0 180)
			(unlocked yes)
			(layer "F.Fab")
			(hide yes)
			(effects
				(font
					(size 1 1)
					(thickness 0.15)
				)
			)
		)
		(sheetname "/USB DP Alt mode/")
		(sheetfile "usb_dp.kicad_sch")
		(attr smd)
		(fp_poly
			(pts
				(xy -3.65 2.1) (xy -3.051 2.1) (xy -3.048 2.1) (xy -3.045 2.1) (xy -3.043 2.1) (xy -3.04 2.1) (xy -3.037 2.1)
				(xy -3.036 2.1) (xy -3.032 2.103) (xy -3.031 2.104) (xy -3.028 2.104) (xy -3.025 2.107) (xy -3.024 2.108)
				(xy -3.021 2.108) (xy -3.02 2.111) (xy -3.017 2.112) (xy -3.016 2.115) (xy -3.013 2.116) (xy -3.012 2.119)
				(xy -3.011 2.12) (xy -3.008 2.123) (xy -3.008 2.124) (xy -3.005 2.125) (xy -3.004 2.128) (xy -3.004 2.132)
				(xy -3.003 2.133) (xy -3.003 2.136) (xy -3.001 2.14) (xy -3 2.144) (xy -3 2.145) (xy -3 2.148) (xy -3 2.648)
				(xy -3 2.652) (xy -3 2.653) (xy -3.001 2.656) (xy -3.001 2.66) (xy -3.003 2.661) (xy -3.003 2.664)
				(xy -3.004 2.668) (xy -3.005 2.672) (xy -3.008 2.673) (xy -3.008 2.676) (xy -3.011 2.677) (xy -3.012 2.68)
				(xy -3.013 2.681) (xy -3.016 2.684) (xy -3.017 2.685) (xy -3.02 2.689) (xy -3.021 2.689) (xy -3.024 2.692)
				(xy -3.025 2.693) (xy -3.028 2.693) (xy -3.031 2.696) (xy -3.032 2.697) (xy -3.036 2.697) (xy -3.037 2.697)
				(xy -3.04 2.697) (xy -3.043 2.697) (xy -3.045 2.7) (xy -3.048 2.7) (xy -3.051 2.7) (xy -3.65 2.7)
				(xy -3.653 2.7) (xy -3.656 2.7) (xy -3.658 2.697) (xy -3.661 2.697) (xy -3.664 2.697) (xy -3.665 2.697)
				(xy -3.669 2.697) (xy -3.67 2.696) (xy -3.673 2.693) (xy -3.676 2.693) (xy -3.677 2.692) (xy -3.68 2.689)
				(xy -3.681 2.689) (xy -3.684 2.685) (xy -3.685 2.684) (xy -3.688 2.681) (xy -3.689 2.68) (xy -3.69 2.677)
				(xy -3.693 2.676) (xy -3.693 2.673) (xy -3.696 2.672) (xy -3.697 2.668) (xy -3.698 2.664) (xy -3.698 2.661)
				(xy -3.7 2.66) (xy -3.7 2.656) (xy -3.701 2.653) (xy -3.701 2.652) (xy -3.701 2.648) (xy -3.701 2.548)
				(xy -3.701 2.547) (xy -3.701 2.543) (xy -3.7 2.54) (xy -3.7 2.539) (xy -3.698 2.535) (xy -3.697 2.531)
				(xy -3.697 2.528) (xy -3.696 2.527) (xy -3.693 2.523) (xy -3.69 2.519) (xy -3.689 2.519) (xy -3.688 2.515)
				(xy -3.685 2.515) (xy -3.684 2.511) (xy -3.681 2.511) (xy -3.68 2.508) (xy -3.677 2.507) (xy -3.676 2.507)
				(xy -3.673 2.503) (xy -3.67 2.503) (xy -3.669 2.503) (xy -3.665 2.5) (xy -3.664 2.5) (xy -3.661 2.499)
				(xy -3.658 2.499) (xy -3.656 2.499) (xy -3.653 2.499) (xy -3.65 2.499) (xy -3.25 2.499) (xy -3.247 2.499)
				(xy -3.246 2.499) (xy -3.242 2.499) (xy -3.238 2.498) (xy -3.235 2.498) (xy -3.234 2.495) (xy -3.23 2.495)
				(xy -3.227 2.495) (xy -3.226 2.491) (xy -3.223 2.491) (xy -3.222 2.49) (xy -3.219 2.487) (xy -3.218 2.487)
				(xy -3.215 2.483) (xy -3.214 2.483) (xy -3.211 2.479) (xy -3.21 2.479) (xy -3.21 2.475) (xy -3.207 2.475)
				(xy -3.206 2.471) (xy -3.206 2.47) (xy -3.203 2.467) (xy -3.202 2.463) (xy -3.202 2.459) (xy -3.202 2.458)
				(xy -3.202 2.455) (xy -3.202 2.451) (xy -3.202 2.45) (xy -3.202 2.35) (xy -3.202 2.346) (xy -3.202 2.345)
				(xy -3.202 2.342) (xy -3.202 2.338) (xy -3.202 2.337) (xy -3.202 2.334) (xy -3.203 2.33) (xy -3.206 2.33)
				(xy -3.206 2.326) (xy -3.207 2.325) (xy -3.21 2.322) (xy -3.21 2.321) (xy -3.211 2.318) (xy -3.214 2.317)
				(xy -3.215 2.314) (xy -3.218 2.313) (xy -3.219 2.31) (xy -3.222 2.31) (xy -3.223 2.306) (xy -3.226 2.306)
				(xy -3.227 2.305) (xy -3.23 2.302) (xy -3.234 2.301) (xy -3.235 2.301) (xy -3.238 2.301) (xy -3.242 2.301)
				(xy -3.246 2.298) (xy -3.247 2.298) (xy -3.25 2.298) (xy -3.65 2.298) (xy -3.653 2.298) (xy -3.656 2.298)
				(xy -3.658 2.297) (xy -3.661 2.297) (xy -3.664 2.297) (xy -3.665 2.297) (xy -3.669 2.297) (xy -3.67 2.294)
				(xy -3.673 2.293) (xy -3.676 2.293) (xy -3.677 2.29) (xy -3.68 2.289) (xy -3.681 2.289) (xy -3.684 2.285)
				(xy -3.685 2.285) (xy -3.688 2.281) (xy -3.689 2.281) (xy -3.69 2.277) (xy -3.693 2.277) (xy -3.693 2.273)
				(xy -3.696 2.273) (xy -3.697 2.269) (xy -3.697 2.266) (xy -3.698 2.265) (xy -3.698 2.261) (xy -3.7 2.258)
				(xy -3.7 2.257) (xy -3.701 2.253) (xy -3.701 2.249) (xy -3.701 2.148) (xy -3.701 2.145) (xy -3.701 2.144)
				(xy -3.7 2.14) (xy -3.698 2.136) (xy -3.698 2.133) (xy -3.697 2.132) (xy -3.697 2.128) (xy -3.696 2.125)
				(xy -3.693 2.124) (xy -3.693 2.123) (xy -3.69 2.12) (xy -3.689 2.119) (xy -3.688 2.116) (xy -3.685 2.115)
				(xy -3.684 2.112) (xy -3.681 2.111) (xy -3.68 2.108) (xy -3.677 2.108) (xy -3.676 2.107) (xy -3.673 2.104)
				(xy -3.67 2.104) (xy -3.669 2.103) (xy -3.665 2.1) (xy -3.664 2.1) (xy -3.661 2.1) (xy -3.658 2.1)
				(xy -3.656 2.1) (xy -3.653 2.1) (xy -3.65 2.1)
			)
			(stroke
				(width 0.0001)
				(type solid)
			)
			(fill yes)
			(layer "F.Mask")
		)
		(fp_poly
			(pts
				(xy -3.65 -2.701) (xy -3.051 -2.701) (xy -3.048 -2.701) (xy -3.045 -2.701) (xy -3.043 -2.698) (xy -3.04 -2.698)
				(xy -3.037 -2.697) (xy -3.036 -2.697) (xy -3.032 -2.697) (xy -3.031 -2.697) (xy -3.028 -2.694) (xy -3.025 -2.693)
				(xy -3.024 -2.693) (xy -3.021 -2.689) (xy -3.02 -2.689) (xy -3.017 -2.687) (xy -3.016 -2.684) (xy -3.013 -2.683)
				(xy -3.012 -2.68) (xy -3.011 -2.679) (xy -3.008 -2.676) (xy -3.008 -2.675) (xy -3.005 -2.672) (xy -3.004 -2.669)
				(xy -3.004 -2.668) (xy -3.003 -2.664) (xy -3.003 -2.663) (xy -3.001 -2.66) (xy -3.001 -2.657) (xy -3 -2.655)
				(xy -3 -2.652) (xy -3 -2.649) (xy -3 -2.149) (xy -3 -2.147) (xy -3 -2.144) (xy -3.001 -2.141) (xy -3.001 -2.14)
				(xy -3.003 -2.136) (xy -3.003 -2.135) (xy -3.004 -2.132) (xy -3.004 -2.129) (xy -3.005 -2.127) (xy -3.008 -2.124)
				(xy -3.011 -2.12) (xy -3.012 -2.12) (xy -3.013 -2.116) (xy -3.016 -2.116) (xy -3.017 -2.112) (xy -3.02 -2.112)
				(xy -3.021 -2.109) (xy -3.024 -2.108) (xy -3.025 -2.108) (xy -3.028 -2.104) (xy -3.031 -2.104) (xy -3.032 -2.104)
				(xy -3.036 -2.101) (xy -3.037 -2.101) (xy -3.04 -2.1) (xy -3.043 -2.1) (xy -3.045 -2.1) (xy -3.048 -2.1)
				(xy -3.051 -2.1) (xy -3.65 -2.1) (xy -3.653 -2.1) (xy -3.656 -2.1) (xy -3.658 -2.1) (xy -3.661 -2.1)
				(xy -3.664 -2.101) (xy -3.665 -2.101) (xy -3.669 -2.104) (xy -3.67 -2.104) (xy -3.673 -2.104) (xy -3.676 -2.108)
				(xy -3.677 -2.108) (xy -3.68 -2.109) (xy -3.681 -2.112) (xy -3.684 -2.112) (xy -3.685 -2.116) (xy -3.688 -2.116)
				(xy -3.689 -2.12) (xy -3.69 -2.12) (xy -3.693 -2.124) (xy -3.696 -2.127) (xy -3.697 -2.129) (xy -3.697 -2.132)
				(xy -3.698 -2.135) (xy -3.698 -2.136) (xy -3.7 -2.14) (xy -3.7 -2.141) (xy -3.701 -2.144) (xy -3.701 -2.147)
				(xy -3.701 -2.149) (xy -3.701 -2.249) (xy -3.701 -2.253) (xy -3.701 -2.254) (xy -3.7 -2.257) (xy -3.7 -2.26)
				(xy -3.698 -2.262) (xy -3.698 -2.265) (xy -3.697 -2.268) (xy -3.697 -2.269) (xy -3.696 -2.273) (xy -3.693 -2.274)
				(xy -3.693 -2.277) (xy -3.69 -2.278) (xy -3.689 -2.281) (xy -3.688 -2.282) (xy -3.685 -2.285) (xy -3.684 -2.286)
				(xy -3.681 -2.289) (xy -3.68 -2.289) (xy -3.677 -2.292) (xy -3.676 -2.293) (xy -3.673 -2.294) (xy -3.67 -2.296)
				(xy -3.669 -2.297) (xy -3.665 -2.297) (xy -3.664 -2.297) (xy -3.661 -2.298) (xy -3.658 -2.298) (xy -3.656 -2.3)
				(xy -3.653 -2.3) (xy -3.65 -2.3) (xy -3.25 -2.3) (xy -3.247 -2.3) (xy -3.246 -2.3) (xy -3.242 -2.301)
				(xy -3.238 -2.301) (xy -3.235 -2.301) (xy -3.234 -2.302) (xy -3.23 -2.304) (xy -3.227 -2.306) (xy -3.226 -2.306)
				(xy -3.223 -2.307) (xy -3.222 -2.31) (xy -3.219 -2.31) (xy -3.218 -2.314) (xy -3.215 -2.314) (xy -3.214 -2.318)
				(xy -3.211 -2.318) (xy -3.21 -2.322) (xy -3.207 -2.326) (xy -3.206 -2.326) (xy -3.206 -2.33) (xy -3.203 -2.331)
				(xy -3.202 -2.334) (xy -3.202 -2.338) (xy -3.202 -2.339) (xy -3.202 -2.342) (xy -3.202 -2.346) (xy -3.202 -2.35)
				(xy -3.202 -2.451) (xy -3.202 -2.452) (xy -3.202 -2.455) (xy -3.202 -2.459) (xy -3.202 -2.463) (xy -3.202 -2.464)
				(xy -3.203 -2.467) (xy -3.206 -2.471) (xy -3.206 -2.472) (xy -3.207 -2.475) (xy -3.21 -2.476) (xy -3.21 -2.479)
				(xy -3.211 -2.48) (xy -3.214 -2.483) (xy -3.215 -2.484) (xy -3.218 -2.487) (xy -3.219 -2.488) (xy -3.222 -2.491)
				(xy -3.223 -2.491) (xy -3.226 -2.492) (xy -3.227 -2.495) (xy -3.23 -2.495) (xy -3.234 -2.496) (xy -3.235 -2.499)
				(xy -3.238 -2.499) (xy -3.242 -2.499) (xy -3.246 -2.499) (xy -3.247 -2.499) (xy -3.25 -2.499) (xy -3.65 -2.499)
				(xy -3.653 -2.499) (xy -3.656 -2.499) (xy -3.658 -2.5) (xy -3.661 -2.5) (xy -3.664 -2.502) (xy -3.665 -2.502)
				(xy -3.669 -2.503) (xy -3.67 -2.503) (xy -3.673 -2.504) (xy -3.676 -2.507) (xy -3.677 -2.507) (xy -3.68 -2.51)
				(xy -3.681 -2.511) (xy -3.684 -2.512) (xy -3.685 -2.515) (xy -3.688 -2.516) (xy -3.689 -2.519) (xy -3.69 -2.52)
				(xy -3.693 -2.523) (xy -3.693 -2.524) (xy -3.696 -2.527) (xy -3.697 -2.53) (xy -3.697 -2.531) (xy -3.698 -2.535)
				(xy -3.698 -2.536) (xy -3.7 -2.539) (xy -3.7 -2.542) (xy -3.701 -2.544) (xy -3.701 -2.547) (xy -3.701 -2.55)
				(xy -3.701 -2.649) (xy -3.701 -2.652) (xy -3.701 -2.655) (xy -3.7 -2.657) (xy -3.7 -2.66) (xy -3.698 -2.663)
				(xy -3.698 -2.664) (xy -3.697 -2.668) (xy -3.697 -2.669) (xy -3.696 -2.672) (xy -3.693 -2.675) (xy -3.693 -2.676)
				(xy -3.69 -2.679) (xy -3.689 -2.68) (xy -3.688 -2.683) (xy -3.685 -2.684) (xy -3.684 -2.687) (xy -3.681 -2.689)
				(xy -3.68 -2.689) (xy -3.677 -2.693) (xy -3.676 -2.693) (xy -3.673 -2.694) (xy -3.67 -2.697) (xy -3.669 -2.697)
				(xy -3.665 -2.697) (xy -3.664 -2.697) (xy -3.661 -2.698) (xy -3.658 -2.698) (xy -3.656 -2.701) (xy -3.653 -2.701)
				(xy -3.65 -2.701)
			)
			(stroke
				(width 0.0001)
				(type solid)
			)
			(fill yes)
			(layer "F.Mask")
		)
		(fp_poly
			(pts
				(xy -3.65 1.3) (xy -3.051 1.3) (xy -3.048 1.3) (xy -3.045 1.3) (xy -3.043 1.3) (xy -3.04 1.3) (xy -3.037 1.302)
				(xy -3.036 1.302) (xy -3.032 1.302) (xy -3.031 1.304) (xy -3.028 1.304) (xy -3.025 1.306) (xy -3.024 1.308)
				(xy -3.021 1.31) (xy -3.02 1.31) (xy -3.017 1.312) (xy -3.016 1.314) (xy -3.013 1.316) (xy -3.012 1.318)
				(xy -3.011 1.32) (xy -3.008 1.322) (xy -3.008 1.324) (xy -3.005 1.326) (xy -3.004 1.33) (xy -3.004 1.332)
				(xy -3.003 1.334) (xy -3.003 1.336) (xy -3.001 1.34) (xy -3.001 1.342) (xy -3 1.344) (xy -3 1.346)
				(xy -3 1.35) (xy -3 1.85) (xy -3 1.852) (xy -3 1.854) (xy -3.001 1.858) (xy -3.001 1.86) (xy -3.003 1.862)
				(xy -3.003 1.864) (xy -3.004 1.868) (xy -3.004 1.87) (xy -3.005 1.872) (xy -3.008 1.874) (xy -3.008 1.876)
				(xy -3.011 1.878) (xy -3.012 1.88) (xy -3.013 1.882) (xy -3.016 1.884) (xy -3.017 1.886) (xy -3.02 1.888)
				(xy -3.021 1.888) (xy -3.024 1.89) (xy -3.025 1.892) (xy -3.028 1.894) (xy -3.031 1.894) (xy -3.032 1.896)
				(xy -3.036 1.896) (xy -3.037 1.896) (xy -3.04 1.898) (xy -3.043 1.898) (xy -3.045 1.898) (xy -3.048 1.898)
				(xy -3.051 1.898) (xy -3.65 1.898) (xy -3.653 1.898) (xy -3.656 1.898) (xy -3.658 1.898) (xy -3.661 1.898)
				(xy -3.664 1.896) (xy -3.665 1.896) (xy -3.669 1.896) (xy -3.67 1.894) (xy -3.673 1.894) (xy -3.676 1.892)
				(xy -3.677 1.89) (xy -3.68 1.888) (xy -3.681 1.888) (xy -3.684 1.886) (xy -3.685 1.884) (xy -3.688 1.882)
				(xy -3.689 1.88) (xy -3.69 1.878) (xy -3.693 1.876) (xy -3.693 1.874) (xy -3.696 1.872) (xy -3.697 1.87)
				(xy -3.697 1.868) (xy -3.698 1.864) (xy -3.698 1.862) (xy -3.7 1.86) (xy -3.7 1.858) (xy -3.701 1.854)
				(xy -3.701 1.852) (xy -3.701 1.85) (xy -3.701 1.749) (xy -3.701 1.747) (xy -3.701 1.745) (xy -3.7 1.741)
				(xy -3.7 1.739) (xy -3.698 1.737) (xy -3.698 1.735) (xy -3.697 1.731) (xy -3.697 1.729) (xy -3.696 1.727)
				(xy -3.693 1.725) (xy -3.693 1.723) (xy -3.69 1.721) (xy -3.689 1.719) (xy -3.688 1.717) (xy -3.685 1.715)
				(xy -3.684 1.713) (xy -3.681 1.711) (xy -3.68 1.709) (xy -3.677 1.707) (xy -3.676 1.707) (xy -3.673 1.705)
				(xy -3.67 1.703) (xy -3.669 1.703) (xy -3.665 1.701) (xy -3.664 1.701) (xy -3.661 1.701) (xy -3.658 1.701)
				(xy -3.656 1.699) (xy -3.653 1.699) (xy -3.65 1.699) (xy -3.25 1.699) (xy -3.247 1.699) (xy -3.246 1.699)
				(xy -3.242 1.699) (xy -3.238 1.697) (xy -3.235 1.697) (xy -3.234 1.697) (xy -3.23 1.695) (xy -3.227 1.695)
				(xy -3.226 1.693) (xy -3.223 1.691) (xy -3.222 1.689) (xy -3.219 1.689) (xy -3.218 1.687) (xy -3.215 1.685)
				(xy -3.214 1.683) (xy -3.211 1.681) (xy -3.21 1.679) (xy -3.21 1.677) (xy -3.207 1.675) (xy -3.206 1.673)
				(xy -3.206 1.669) (xy -3.203 1.667) (xy -3.202 1.665) (xy -3.202 1.662) (xy -3.202 1.658) (xy -3.202 1.656)
				(xy -3.202 1.654) (xy -3.202 1.652) (xy -3.202 1.648) (xy -3.202 1.55) (xy -3.202 1.546) (xy -3.202 1.544)
				(xy -3.202 1.542) (xy -3.202 1.54) (xy -3.202 1.536) (xy -3.202 1.533) (xy -3.203 1.531) (xy -3.206 1.529)
				(xy -3.206 1.525) (xy -3.207 1.523) (xy -3.21 1.521) (xy -3.21 1.519) (xy -3.211 1.517) (xy -3.214 1.515)
				(xy -3.215 1.513) (xy -3.218 1.511) (xy -3.219 1.509) (xy -3.222 1.509) (xy -3.223 1.507) (xy -3.226 1.505)
				(xy -3.227 1.503) (xy -3.23 1.503) (xy -3.234 1.501) (xy -3.235 1.501) (xy -3.238 1.501) (xy -3.242 1.499)
				(xy -3.246 1.499) (xy -3.247 1.499) (xy -3.25 1.499) (xy -3.65 1.499) (xy -3.653 1.499) (xy -3.656 1.499)
				(xy -3.658 1.499) (xy -3.661 1.499) (xy -3.664 1.497) (xy -3.665 1.497) (xy -3.669 1.497) (xy -3.67 1.495)
				(xy -3.673 1.495) (xy -3.676 1.493) (xy -3.677 1.491) (xy -3.68 1.489) (xy -3.681 1.489) (xy -3.684 1.487)
				(xy -3.685 1.485) (xy -3.688 1.483) (xy -3.689 1.481) (xy -3.69 1.479) (xy -3.693 1.477) (xy -3.693 1.475)
				(xy -3.696 1.473) (xy -3.697 1.469) (xy -3.697 1.467) (xy -3.698 1.465) (xy -3.698 1.463) (xy -3.7 1.459)
				(xy -3.7 1.457) (xy -3.701 1.455) (xy -3.701 1.453) (xy -3.701 1.449) (xy -3.701 1.35) (xy -3.701 1.346)
				(xy -3.701 1.344) (xy -3.7 1.342) (xy -3.7 1.34) (xy -3.698 1.336) (xy -3.698 1.334) (xy -3.697 1.332)
				(xy -3.697 1.33) (xy -3.696 1.326) (xy -3.693 1.324) (xy -3.693 1.322) (xy -3.69 1.32) (xy -3.689 1.318)
				(xy -3.688 1.316) (xy -3.685 1.314) (xy -3.684 1.312) (xy -3.681 1.31) (xy -3.68 1.31) (xy -3.677 1.308)
				(xy -3.676 1.306) (xy -3.673 1.304) (xy -3.67 1.304) (xy -3.669 1.302) (xy -3.665 1.302) (xy -3.664 1.302)
				(xy -3.661 1.3) (xy -3.658 1.3) (xy -3.656 1.3) (xy -3.653 1.3) (xy -3.65 1.3)
			)
			(stroke
				(width 0.0001)
				(type solid)
			)
			(fill yes)
			(layer "F.Mask")
		)
		(fp_poly
			(pts
				(xy -3.65 -1.901) (xy -3.051 -1.901) (xy -3.048 -1.901) (xy -3.045 -1.901) (xy -3.043 -1.899) (xy -3.04 -1.899)
				(xy -3.037 -1.899) (xy -3.036 -1.899) (xy -3.032 -1.897) (xy -3.031 -1.897) (xy -3.028 -1.895) (xy -3.025 -1.893)
				(xy -3.024 -1.893) (xy -3.021 -1.891) (xy -3.02 -1.889) (xy -3.017 -1.887) (xy -3.016 -1.885) (xy -3.013 -1.883)
				(xy -3.012 -1.881) (xy -3.011 -1.879) (xy -3.008 -1.877) (xy -3.008 -1.875) (xy -3.005 -1.873) (xy -3.004 -1.871)
				(xy -3.004 -1.869) (xy -3.003 -1.865) (xy -3.003 -1.863) (xy -3.001 -1.861) (xy -3.001 -1.859) (xy -3 -1.855)
				(xy -3 -1.853) (xy -3 -1.851) (xy -3 -1.351) (xy -3 -1.347) (xy -3 -1.345) (xy -3.001 -1.343) (xy -3.001 -1.341)
				(xy -3.003 -1.337) (xy -3.003 -1.335) (xy -3.004 -1.333) (xy -3.004 -1.331) (xy -3.005 -1.327) (xy -3.008 -1.325)
				(xy -3.008 -1.323) (xy -3.011 -1.321) (xy -3.012 -1.319) (xy -3.013 -1.317) (xy -3.016 -1.315) (xy -3.017 -1.313)
				(xy -3.02 -1.311) (xy -3.021 -1.311) (xy -3.024 -1.309) (xy -3.025 -1.307) (xy -3.028 -1.305) (xy -3.031 -1.305)
				(xy -3.032 -1.303) (xy -3.036 -1.303) (xy -3.037 -1.303) (xy -3.04 -1.301) (xy -3.043 -1.301) (xy -3.045 -1.301)
				(xy -3.048 -1.301) (xy -3.051 -1.301) (xy -3.65 -1.301) (xy -3.653 -1.301) (xy -3.656 -1.301) (xy -3.658 -1.301)
				(xy -3.661 -1.301) (xy -3.664 -1.303) (xy -3.665 -1.303) (xy -3.669 -1.303) (xy -3.67 -1.305) (xy -3.673 -1.305)
				(xy -3.676 -1.307) (xy -3.677 -1.309) (xy -3.68 -1.311) (xy -3.681 -1.311) (xy -3.684 -1.313) (xy -3.685 -1.315)
				(xy -3.688 -1.317) (xy -3.689 -1.319) (xy -3.69 -1.321) (xy -3.693 -1.323) (xy -3.693 -1.325) (xy -3.696 -1.327)
				(xy -3.697 -1.331) (xy -3.697 -1.333) (xy -3.698 -1.335) (xy -3.698 -1.337) (xy -3.7 -1.341) (xy -3.7 -1.343)
				(xy -3.701 -1.345) (xy -3.701 -1.347) (xy -3.701 -1.351) (xy -3.701 -1.45) (xy -3.701 -1.454) (xy -3.701 -1.456)
				(xy -3.7 -1.458) (xy -3.7 -1.46) (xy -3.698 -1.464) (xy -3.698 -1.466) (xy -3.697 -1.468) (xy -3.697 -1.47)
				(xy -3.696 -1.474) (xy -3.693 -1.476) (xy -3.693 -1.478) (xy -3.69 -1.48) (xy -3.689 -1.482) (xy -3.688 -1.484)
				(xy -3.685 -1.486) (xy -3.684 -1.488) (xy -3.681 -1.49) (xy -3.68 -1.49) (xy -3.677 -1.492) (xy -3.676 -1.494)
				(xy -3.673 -1.496) (xy -3.67 -1.496) (xy -3.669 -1.498) (xy -3.665 -1.498) (xy -3.664 -1.498) (xy -3.661 -1.5)
				(xy -3.658 -1.5) (xy -3.656 -1.5) (xy -3.653 -1.5) (xy -3.65 -1.5) (xy -3.25 -1.5) (xy -3.247 -1.5)
				(xy -3.246 -1.5) (xy -3.242 -1.502) (xy -3.238 -1.502) (xy -3.235 -1.502) (xy -3.234 -1.504) (xy -3.23 -1.504)
				(xy -3.227 -1.506) (xy -3.226 -1.508) (xy -3.223 -1.508) (xy -3.222 -1.51) (xy -3.219 -1.512) (xy -3.218 -1.514)
				(xy -3.215 -1.516) (xy -3.214 -1.518) (xy -3.211 -1.52) (xy -3.21 -1.522) (xy -3.21 -1.524) (xy -3.207 -1.526)
				(xy -3.206 -1.528) (xy -3.206 -1.53) (xy -3.203 -1.532) (xy -3.202 -1.536) (xy -3.202 -1.537) (xy -3.202 -1.541)
				(xy -3.202 -1.543) (xy -3.202 -1.545) (xy -3.202 -1.547) (xy -3.202 -1.551) (xy -3.202 -1.651) (xy -3.202 -1.653)
				(xy -3.202 -1.655) (xy -3.202 -1.659) (xy -3.202 -1.661) (xy -3.202 -1.663) (xy -3.202 -1.666) (xy -3.203 -1.668)
				(xy -3.206 -1.67) (xy -3.206 -1.674) (xy -3.207 -1.676) (xy -3.21 -1.678) (xy -3.21 -1.68) (xy -3.211 -1.682)
				(xy -3.214 -1.684) (xy -3.215 -1.686) (xy -3.218 -1.688) (xy -3.219 -1.69) (xy -3.222 -1.69) (xy -3.223 -1.692)
				(xy -3.226 -1.694) (xy -3.227 -1.696) (xy -3.23 -1.696) (xy -3.234 -1.698) (xy -3.235 -1.698) (xy -3.238 -1.698)
				(xy -3.242 -1.7) (xy -3.246 -1.7) (xy -3.247 -1.7) (xy -3.25 -1.7) (xy -3.65 -1.7) (xy -3.653 -1.7)
				(xy -3.656 -1.7) (xy -3.658 -1.702) (xy -3.661 -1.702) (xy -3.664 -1.702) (xy -3.665 -1.702) (xy -3.669 -1.704)
				(xy -3.67 -1.704) (xy -3.673 -1.706) (xy -3.676 -1.708) (xy -3.677 -1.708) (xy -3.68 -1.71) (xy -3.681 -1.712)
				(xy -3.684 -1.714) (xy -3.685 -1.716) (xy -3.688 -1.718) (xy -3.689 -1.72) (xy -3.69 -1.722) (xy -3.693 -1.724)
				(xy -3.693 -1.726) (xy -3.696 -1.728) (xy -3.697 -1.73) (xy -3.697 -1.732) (xy -3.698 -1.736) (xy -3.698 -1.738)
				(xy -3.7 -1.74) (xy -3.7 -1.742) (xy -3.701 -1.746) (xy -3.701 -1.748) (xy -3.701 -1.75) (xy -3.701 -1.851)
				(xy -3.701 -1.853) (xy -3.701 -1.855) (xy -3.7 -1.859) (xy -3.7 -1.861) (xy -3.698 -1.863) (xy -3.698 -1.865)
				(xy -3.697 -1.869) (xy -3.697 -1.871) (xy -3.696 -1.873) (xy -3.693 -1.875) (xy -3.693 -1.877) (xy -3.69 -1.879)
				(xy -3.689 -1.881) (xy -3.688 -1.883) (xy -3.685 -1.885) (xy -3.684 -1.887) (xy -3.681 -1.889) (xy -3.68 -1.891)
				(xy -3.677 -1.893) (xy -3.676 -1.893) (xy -3.673 -1.895) (xy -3.67 -1.897) (xy -3.669 -1.897) (xy -3.665 -1.899)
				(xy -3.664 -1.899) (xy -3.661 -1.899) (xy -3.658 -1.899) (xy -3.656 -1.901) (xy -3.653 -1.901) (xy -3.65 -1.901)
			)
			(stroke
				(width 0.0001)
				(type solid)
			)
			(fill yes)
			(layer "F.Mask")
		)
		(fp_line
			(start 3.499 3.499)
			(end 3.499 2.898)
			(stroke
				(width 0.15)
				(type solid)
			)
			(layer "F.SilkS")
		)
		(fp_line
			(start 3.499 -3.5)
			(end 3.499 -2.9)
			(stroke
				(width 0.15)
				(type solid)
			)
			(layer "F.SilkS")
		)
		(fp_line
			(start 2.898 3.499)
			(end 3.499 3.499)
			(stroke
				(width 0.15)
				(type solid)
			)
			(layer "F.SilkS")
		)
		(fp_line
			(start 2.898 -3.5)
			(end 3.499 -3.5)
			(stroke
				(width 0.15)
				(type solid)
			)
			(layer "F.SilkS")
		)
		(fp_line
			(start -2.9 3.499)
			(end -3.5 3.499)
			(stroke
				(width 0.15)
				(type solid)
			)
			(layer "F.SilkS")
		)
		(fp_line
			(start -2.9 -3.5)
			(end -3.5 -3.5)
			(stroke
				(width 0.15)
				(type solid)
			)
			(layer "F.SilkS")
		)
		(fp_line
			(start -3.5 3.499)
			(end -3.5 2.999)
			(stroke
				(width 0.15)
				(type solid)
			)
			(layer "F.SilkS")
		)
		(fp_line
			(start -3.5 -3.5)
			(end -3.5 -3)
			(stroke
				(width 0.15)
				(type solid)
			)
			(layer "F.SilkS")
		)
		(fp_circle
			(center -4.3 -2.4)
			(end -4.25 -2.36)
			(stroke
				(width 0.15)
				(type solid)
			)
			(fill yes)
			(layer "F.SilkS")
		)
		(fp_poly
			(pts
				(xy 1.148 1.419) (xy 2.62 1.419) (xy 2.62 2.539) (xy 1.148 2.539)
			)
			(stroke
				(width 0.01)
				(type solid)
			)
			(fill yes)
			(layer "F.Paste")
		)
		(fp_poly
			(pts
				(xy 1.148 0.1) (xy 2.62 0.1) (xy 2.62 1.219) (xy 1.148 1.219)
			)
			(stroke
				(width 0.01)
				(type solid)
			)
			(fill yes)
			(layer "F.Paste")
		)
		(fp_poly
			(pts
				(xy 1.148 -1.22) (xy 2.62 -1.22) (xy 2.62 -0.102) (xy 1.148 -0.102)
			)
			(stroke
				(width 0.01)
				(type solid)
			)
			(fill yes)
			(layer "F.Paste")
		)
		(fp_poly
			(pts
				(xy 1.148 -2.54) (xy 2.62 -2.54) (xy 2.62 -1.42) (xy 1.148 -1.42)
			)
			(stroke
				(width 0.01)
				(type solid)
			)
			(fill yes)
			(layer "F.Paste")
		)
		(fp_poly
			(pts
				(xy -0.522 1.419) (xy 0.949 1.419) (xy 0.949 2.539) (xy -0.522 2.539)
			)
			(stroke
				(width 0.01)
				(type solid)
			)
			(fill yes)
			(layer "F.Paste")
		)
		(fp_poly
			(pts
				(xy -0.522 0.1) (xy 0.949 0.1) (xy 0.949 1.219) (xy -0.522 1.219)
			)
			(stroke
				(width 0.01)
				(type solid)
			)
			(fill yes)
			(layer "F.Paste")
		)
		(fp_poly
			(pts
				(xy -0.522 -1.22) (xy 0.949 -1.22) (xy 0.949 -0.102) (xy -0.522 -0.102)
			)
			(stroke
				(width 0.01)
				(type solid)
			)
			(fill yes)
			(layer "F.Paste")
		)
		(fp_poly
			(pts
				(xy -0.522 -2.54) (xy 0.949 -2.54) (xy 0.949 -1.42) (xy -0.522 -1.42)
			)
			(stroke
				(width 0.01)
				(type solid)
			)
			(fill yes)
			(layer "F.Paste")
		)
		(fp_poly
			(pts
				(xy -2.61 1.574) (xy -1.141 1.574) (xy -1.141 2.725) (xy -2.61 2.725)
			)
			(stroke
				(width 0.01)
				(type solid)
			)
			(fill yes)
			(layer "F.Paste")
		)
		(fp_poly
			(pts
				(xy -2.61 0.225) (xy -1.141 0.225) (xy -1.141 1.374) (xy -2.61 1.374)
			)
			(stroke
				(width 0.01)
				(type solid)
			)
			(fill yes)
			(layer "F.Paste")
		)
		(fp_poly
			(pts
				(xy -2.61 -1.351) (xy -1.141 -1.351) (xy -1.141 -0.202) (xy -2.61 -0.202)
			)
			(stroke
				(width 0.01)
				(type solid)
			)
			(fill yes)
			(layer "F.Paste")
		)
		(fp_poly
			(pts
				(xy -2.61 -2.702) (xy -1.141 -2.702) (xy -1.141 -1.551) (xy -2.61 -1.551)
			)
			(stroke
				(width 0.01)
				(type solid)
			)
			(fill yes)
			(layer "F.Paste")
		)
		(fp_poly
			(pts
				(xy -3.65 2.1) (xy -3.051 2.1) (xy -3.048 2.1) (xy -3.045 2.1) (xy -3.043 2.1) (xy -3.04 2.1) (xy -3.037 2.1)
				(xy -3.036 2.1) (xy -3.032 2.103) (xy -3.031 2.104) (xy -3.028 2.104) (xy -3.025 2.107) (xy -3.024 2.108)
				(xy -3.021 2.108) (xy -3.02 2.111) (xy -3.017 2.112) (xy -3.016 2.115) (xy -3.013 2.116) (xy -3.012 2.119)
				(xy -3.011 2.12) (xy -3.008 2.123) (xy -3.008 2.124) (xy -3.005 2.125) (xy -3.004 2.128) (xy -3.004 2.132)
				(xy -3.003 2.133) (xy -3.003 2.136) (xy -3.001 2.14) (xy -3 2.144) (xy -3 2.145) (xy -3 2.148) (xy -3 2.648)
				(xy -3 2.652) (xy -3 2.653) (xy -3.001 2.656) (xy -3.001 2.66) (xy -3.003 2.661) (xy -3.003 2.664)
				(xy -3.004 2.668) (xy -3.005 2.672) (xy -3.008 2.673) (xy -3.008 2.676) (xy -3.011 2.677) (xy -3.012 2.68)
				(xy -3.013 2.681) (xy -3.016 2.684) (xy -3.017 2.685) (xy -3.02 2.689) (xy -3.021 2.689) (xy -3.024 2.692)
				(xy -3.025 2.693) (xy -3.028 2.693) (xy -3.031 2.696) (xy -3.032 2.697) (xy -3.036 2.697) (xy -3.037 2.697)
				(xy -3.04 2.697) (xy -3.043 2.697) (xy -3.045 2.7) (xy -3.048 2.7) (xy -3.051 2.7) (xy -3.65 2.7)
				(xy -3.653 2.7) (xy -3.656 2.7) (xy -3.658 2.697) (xy -3.661 2.697) (xy -3.664 2.697) (xy -3.665 2.697)
				(xy -3.669 2.697) (xy -3.67 2.696) (xy -3.673 2.693) (xy -3.676 2.693) (xy -3.677 2.692) (xy -3.68 2.689)
				(xy -3.681 2.689) (xy -3.684 2.685) (xy -3.685 2.684) (xy -3.688 2.681) (xy -3.689 2.68) (xy -3.69 2.677)
				(xy -3.693 2.676) (xy -3.693 2.673) (xy -3.696 2.672) (xy -3.697 2.668) (xy -3.698 2.664) (xy -3.698 2.661)
				(xy -3.7 2.66) (xy -3.7 2.656) (xy -3.701 2.653) (xy -3.701 2.652) (xy -3.701 2.648) (xy -3.701 2.548)
				(xy -3.701 2.547) (xy -3.701 2.543) (xy -3.7 2.54) (xy -3.7 2.539) (xy -3.698 2.535) (xy -3.697 2.531)
				(xy -3.697 2.528) (xy -3.696 2.527) (xy -3.693 2.523) (xy -3.69 2.519) (xy -3.689 2.519) (xy -3.688 2.515)
				(xy -3.685 2.515) (xy -3.684 2.511) (xy -3.681 2.511) (xy -3.68 2.508) (xy -3.677 2.507) (xy -3.676 2.507)
				(xy -3.673 2.503) (xy -3.67 2.503) (xy -3.669 2.503) (xy -3.665 2.5) (xy -3.664 2.5) (xy -3.661 2.499)
				(xy -3.658 2.499) (xy -3.656 2.499) (xy -3.653 2.499) (xy -3.65 2.499) (xy -3.25 2.499) (xy -3.247 2.499)
				(xy -3.246 2.499) (xy -3.242 2.499) (xy -3.238 2.498) (xy -3.235 2.498) (xy -3.234 2.495) (xy -3.23 2.495)
				(xy -3.227 2.495) (xy -3.226 2.491) (xy -3.223 2.491) (xy -3.222 2.49) (xy -3.219 2.487) (xy -3.218 2.487)
				(xy -3.215 2.483) (xy -3.214 2.483) (xy -3.211 2.479) (xy -3.21 2.479) (xy -3.21 2.475) (xy -3.207 2.475)
				(xy -3.206 2.471) (xy -3.206 2.47) (xy -3.203 2.467) (xy -3.202 2.463) (xy -3.202 2.459) (xy -3.202 2.458)
				(xy -3.202 2.455) (xy -3.202 2.451) (xy -3.202 2.45) (xy -3.202 2.35) (xy -3.202 2.346) (xy -3.202 2.345)
				(xy -3.202 2.342) (xy -3.202 2.338) (xy -3.202 2.337) (xy -3.202 2.334) (xy -3.203 2.33) (xy -3.206 2.33)
				(xy -3.206 2.326) (xy -3.207 2.325) (xy -3.21 2.322) (xy -3.21 2.321) (xy -3.211 2.318) (xy -3.214 2.317)
				(xy -3.215 2.314) (xy -3.218 2.313) (xy -3.219 2.31) (xy -3.222 2.31) (xy -3.223 2.306) (xy -3.226 2.306)
				(xy -3.227 2.305) (xy -3.23 2.302) (xy -3.234 2.301) (xy -3.235 2.301) (xy -3.238 2.301) (xy -3.242 2.301)
				(xy -3.246 2.298) (xy -3.247 2.298) (xy -3.25 2.298) (xy -3.65 2.298) (xy -3.653 2.298) (xy -3.656 2.298)
				(xy -3.658 2.297) (xy -3.661 2.297) (xy -3.664 2.297) (xy -3.665 2.297) (xy -3.669 2.297) (xy -3.67 2.294)
				(xy -3.673 2.293) (xy -3.676 2.293) (xy -3.677 2.29) (xy -3.68 2.289) (xy -3.681 2.289) (xy -3.684 2.285)
				(xy -3.685 2.285) (xy -3.688 2.281) (xy -3.689 2.281) (xy -3.69 2.277) (xy -3.693 2.277) (xy -3.693 2.273)
				(xy -3.696 2.273) (xy -3.697 2.269) (xy -3.697 2.266) (xy -3.698 2.265) (xy -3.698 2.261) (xy -3.7 2.258)
				(xy -3.7 2.257) (xy -3.701 2.253) (xy -3.701 2.249) (xy -3.701 2.148) (xy -3.701 2.145) (xy -3.701 2.144)
				(xy -3.7 2.14) (xy -3.698 2.136) (xy -3.698 2.133) (xy -3.697 2.132) (xy -3.697 2.128) (xy -3.696 2.125)
				(xy -3.693 2.124) (xy -3.693 2.123) (xy -3.69 2.12) (xy -3.689 2.119) (xy -3.688 2.116) (xy -3.685 2.115)
				(xy -3.684 2.112) (xy -3.681 2.111) (xy -3.68 2.108) (xy -3.677 2.108) (xy -3.676 2.107) (xy -3.673 2.104)
				(xy -3.67 2.104) (xy -3.669 2.103) (xy -3.665 2.1) (xy -3.664 2.1) (xy -3.661 2.1) (xy -3.658 2.1)
				(xy -3.656 2.1) (xy -3.653 2.1) (xy -3.65 2.1)
			)
			(stroke
				(width 0.0001)
				(type solid)
			)
			(fill yes)
			(layer "F.Paste")
		)
		(fp_poly
			(pts
				(xy -3.65 -2.702) (xy -3.051 -2.702) (xy -3.048 -2.702) (xy -3.045 -2.702) (xy -3.043 -2.699) (xy -3.04 -2.699)
				(xy -3.037 -2.698) (xy -3.036 -2.698) (xy -3.032 -2.698) (xy -3.031 -2.698) (xy -3.028 -2.695) (xy -3.025 -2.694)
				(xy -3.024 -2.694) (xy -3.021 -2.69) (xy -3.02 -2.69) (xy -3.017 -2.688) (xy -3.016 -2.685) (xy -3.013 -2.684)
				(xy -3.012 -2.681) (xy -3.011 -2.68) (xy -3.008 -2.677) (xy -3.008 -2.676) (xy -3.005 -2.673) (xy -3.004 -2.67)
				(xy -3.004 -2.669) (xy -3.003 -2.665) (xy -3.003 -2.664) (xy -3.001 -2.661) (xy -3.001 -2.658) (xy -3 -2.656)
				(xy -3 -2.653) (xy -3 -2.65) (xy -3 -2.15) (xy -3 -2.148) (xy -3 -2.145) (xy -3.001 -2.142) (xy -3.001 -2.141)
				(xy -3.003 -2.137) (xy -3.003 -2.136) (xy -3.004 -2.133) (xy -3.004 -2.13) (xy -3.005 -2.128) (xy -3.008 -2.125)
				(xy -3.011 -2.121) (xy -3.012 -2.121) (xy -3.013 -2.117) (xy -3.016 -2.117) (xy -3.017 -2.113) (xy -3.02 -2.113)
				(xy -3.021 -2.11) (xy -3.024 -2.109) (xy -3.025 -2.109) (xy -3.028 -2.105) (xy -3.031 -2.105) (xy -3.032 -2.105)
				(xy -3.036 -2.102) (xy -3.037 -2.102) (xy -3.04 -2.101) (xy -3.043 -2.101) (xy -3.045 -2.101) (xy -3.048 -2.101)
				(xy -3.051 -2.101) (xy -3.65 -2.101) (xy -3.653 -2.101) (xy -3.656 -2.101) (xy -3.658 -2.101) (xy -3.661 -2.101)
				(xy -3.664 -2.102) (xy -3.665 -2.102) (xy -3.669 -2.105) (xy -3.67 -2.105) (xy -3.673 -2.105) (xy -3.676 -2.109)
				(xy -3.677 -2.109) (xy -3.68 -2.11) (xy -3.681 -2.113) (xy -3.684 -2.113) (xy -3.685 -2.117) (xy -3.688 -2.117)
				(xy -3.689 -2.121) (xy -3.69 -2.121) (xy -3.693 -2.125) (xy -3.696 -2.128) (xy -3.697 -2.13) (xy -3.697 -2.133)
				(xy -3.698 -2.136) (xy -3.698 -2.137) (xy -3.7 -2.141) (xy -3.7 -2.142) (xy -3.701 -2.145) (xy -3.701 -2.148)
				(xy -3.701 -2.15) (xy -3.701 -2.25) (xy -3.701 -2.254) (xy -3.701 -2.255) (xy -3.7 -2.258) (xy -3.7 -2.261)
				(xy -3.698 -2.263) (xy -3.698 -2.266) (xy -3.697 -2.269) (xy -3.697 -2.27) (xy -3.696 -2.274) (xy -3.693 -2.275)
				(xy -3.693 -2.278) (xy -3.69 -2.279) (xy -3.689 -2.282) (xy -3.688 -2.283) (xy -3.685 -2.286) (xy -3.684 -2.287)
				(xy -3.681 -2.29) (xy -3.68 -2.29) (xy -3.677 -2.293) (xy -3.676 -2.294) (xy -3.673 -2.295) (xy -3.67 -2.297)
				(xy -3.669 -2.298) (xy -3.665 -2.298) (xy -3.664 -2.298) (xy -3.661 -2.299) (xy -3.658 -2.299) (xy -3.656 -2.301)
				(xy -3.653 -2.301) (xy -3.65 -2.301) (xy -3.25 -2.301) (xy -3.247 -2.301) (xy -3.246 -2.301) (xy -3.242 -2.302)
				(xy -3.238 -2.302) (xy -3.235 -2.302) (xy -3.234 -2.303) (xy -3.23 -2.305) (xy -3.227 -2.307) (xy -3.226 -2.307)
				(xy -3.223 -2.308) (xy -3.222 -2.311) (xy -3.219 -2.311) (xy -3.218 -2.315) (xy -3.215 -2.315) (xy -3.214 -2.319)
				(xy -3.211 -2.319) (xy -3.21 -2.323) (xy -3.207 -2.327) (xy -3.206 -2.327) (xy -3.206 -2.331) (xy -3.203 -2.332)
				(xy -3.202 -2.335) (xy -3.202 -2.339) (xy -3.202 -2.34) (xy -3.202 -2.343) (xy -3.202 -2.347) (xy -3.202 -2.351)
				(xy -3.202 -2.452) (xy -3.202 -2.453) (xy -3.202 -2.456) (xy -3.202 -2.46) (xy -3.202 -2.464) (xy -3.202 -2.465)
				(xy -3.203 -2.468) (xy -3.206 -2.472) (xy -3.206 -2.473) (xy -3.207 -2.476) (xy -3.21 -2.477) (xy -3.21 -2.48)
				(xy -3.211 -2.481) (xy -3.214 -2.484) (xy -3.215 -2.485) (xy -3.218 -2.488) (xy -3.219 -2.489) (xy -3.222 -2.492)
				(xy -3.223 -2.492) (xy -3.226 -2.493) (xy -3.227 -2.496) (xy -3.23 -2.496) (xy -3.234 -2.497) (xy -3.235 -2.5)
				(xy -3.238 -2.5) (xy -3.242 -2.5) (xy -3.246 -2.5) (xy -3.247 -2.5) (xy -3.25 -2.5) (xy -3.65 -2.5)
				(xy -3.653 -2.5) (xy -3.656 -2.5) (xy -3.658 -2.501) (xy -3.661 -2.501) (xy -3.664 -2.503) (xy -3.665 -2.503)
				(xy -3.669 -2.504) (xy -3.67 -2.504) (xy -3.673 -2.505) (xy -3.676 -2.508) (xy -3.677 -2.508) (xy -3.68 -2.511)
				(xy -3.681 -2.512) (xy -3.684 -2.513) (xy -3.685 -2.516) (xy -3.688 -2.517) (xy -3.689 -2.52) (xy -3.69 -2.521)
				(xy -3.693 -2.524) (xy -3.693 -2.525) (xy -3.696 -2.528) (xy -3.697 -2.531) (xy -3.697 -2.532) (xy -3.698 -2.536)
				(xy -3.698 -2.537) (xy -3.7 -2.54) (xy -3.7 -2.543) (xy -3.701 -2.545) (xy -3.701 -2.548) (xy -3.701 -2.551)
				(xy -3.701 -2.65) (xy -3.701 -2.653) (xy -3.701 -2.656) (xy -3.7 -2.658) (xy -3.7 -2.661) (xy -3.698 -2.664)
				(xy -3.698 -2.665) (xy -3.697 -2.669) (xy -3.697 -2.67) (xy -3.696 -2.673) (xy -3.693 -2.676) (xy -3.693 -2.677)
				(xy -3.69 -2.68) (xy -3.689 -2.681) (xy -3.688 -2.684) (xy -3.685 -2.685) (xy -3.684 -2.688) (xy -3.681 -2.69)
				(xy -3.68 -2.69) (xy -3.677 -2.694) (xy -3.676 -2.694) (xy -3.673 -2.695) (xy -3.67 -2.698) (xy -3.669 -2.698)
				(xy -3.665 -2.698) (xy -3.664 -2.698) (xy -3.661 -2.699) (xy -3.658 -2.699) (xy -3.656 -2.702) (xy -3.653 -2.702)
				(xy -3.65 -2.702)
			)
			(stroke
				(width 0.0001)
				(type solid)
			)
			(fill yes)
			(layer "F.Paste")
		)
		(fp_poly
			(pts
				(xy -3.65 1.3) (xy -3.051 1.3) (xy -3.048 1.3) (xy -3.045 1.3) (xy -3.043 1.3) (xy -3.04 1.3) (xy -3.037 1.302)
				(xy -3.036 1.302) (xy -3.032 1.302) (xy -3.031 1.304) (xy -3.028 1.304) (xy -3.025 1.306) (xy -3.024 1.308)
				(xy -3.021 1.31) (xy -3.02 1.31) (xy -3.017 1.312) (xy -3.016 1.314) (xy -3.013 1.316) (xy -3.012 1.318)
				(xy -3.011 1.32) (xy -3.008 1.322) (xy -3.008 1.324) (xy -3.005 1.326) (xy -3.004 1.33) (xy -3.004 1.332)
				(xy -3.003 1.334) (xy -3.003 1.336) (xy -3.001 1.34) (xy -3.001 1.342) (xy -3 1.344) (xy -3 1.346)
				(xy -3 1.35) (xy -3 1.85) (xy -3 1.852) (xy -3 1.854) (xy -3.001 1.858) (xy -3.001 1.86) (xy -3.003 1.862)
				(xy -3.003 1.864) (xy -3.004 1.868) (xy -3.004 1.87) (xy -3.005 1.872) (xy -3.008 1.874) (xy -3.008 1.876)
				(xy -3.011 1.878) (xy -3.012 1.88) (xy -3.013 1.882) (xy -3.016 1.884) (xy -3.017 1.886) (xy -3.02 1.888)
				(xy -3.021 1.888) (xy -3.024 1.89) (xy -3.025 1.892) (xy -3.028 1.894) (xy -3.031 1.894) (xy -3.032 1.896)
				(xy -3.036 1.896) (xy -3.037 1.896) (xy -3.04 1.898) (xy -3.043 1.898) (xy -3.045 1.898) (xy -3.048 1.898)
				(xy -3.051 1.898) (xy -3.65 1.898) (xy -3.653 1.898) (xy -3.656 1.898) (xy -3.658 1.898) (xy -3.661 1.898)
				(xy -3.664 1.896) (xy -3.665 1.896) (xy -3.669 1.896) (xy -3.67 1.894) (xy -3.673 1.894) (xy -3.676 1.892)
				(xy -3.677 1.89) (xy -3.68 1.888) (xy -3.681 1.888) (xy -3.684 1.886) (xy -3.685 1.884) (xy -3.688 1.882)
				(xy -3.689 1.88) (xy -3.69 1.878) (xy -3.693 1.876) (xy -3.693 1.874) (xy -3.696 1.872) (xy -3.697 1.87)
				(xy -3.697 1.868) (xy -3.698 1.864) (xy -3.698 1.862) (xy -3.7 1.86) (xy -3.7 1.858) (xy -3.701 1.854)
				(xy -3.701 1.852) (xy -3.701 1.85) (xy -3.701 1.749) (xy -3.701 1.747) (xy -3.701 1.745) (xy -3.7 1.741)
				(xy -3.7 1.739) (xy -3.698 1.737) (xy -3.698 1.735) (xy -3.697 1.731) (xy -3.697 1.729) (xy -3.696 1.727)
				(xy -3.693 1.725) (xy -3.693 1.723) (xy -3.69 1.721) (xy -3.689 1.719) (xy -3.688 1.717) (xy -3.685 1.715)
				(xy -3.684 1.713) (xy -3.681 1.711) (xy -3.68 1.709) (xy -3.677 1.707) (xy -3.676 1.707) (xy -3.673 1.705)
				(xy -3.67 1.703) (xy -3.669 1.703) (xy -3.665 1.701) (xy -3.664 1.701) (xy -3.661 1.701) (xy -3.658 1.701)
				(xy -3.656 1.699) (xy -3.653 1.699) (xy -3.65 1.699) (xy -3.25 1.699) (xy -3.247 1.699) (xy -3.246 1.699)
				(xy -3.242 1.699) (xy -3.238 1.697) (xy -3.235 1.697) (xy -3.234 1.697) (xy -3.23 1.695) (xy -3.227 1.695)
				(xy -3.226 1.693) (xy -3.223 1.691) (xy -3.222 1.689) (xy -3.219 1.689) (xy -3.218 1.687) (xy -3.215 1.685)
				(xy -3.214 1.683) (xy -3.211 1.681) (xy -3.21 1.679) (xy -3.21 1.677) (xy -3.207 1.675) (xy -3.206 1.673)
				(xy -3.206 1.669) (xy -3.203 1.667) (xy -3.202 1.665) (xy -3.202 1.662) (xy -3.202 1.658) (xy -3.202 1.656)
				(xy -3.202 1.654) (xy -3.202 1.652) (xy -3.202 1.648) (xy -3.202 1.55) (xy -3.202 1.546) (xy -3.202 1.544)
				(xy -3.202 1.542) (xy -3.202 1.54) (xy -3.202 1.536) (xy -3.202 1.533) (xy -3.203 1.531) (xy -3.206 1.529)
				(xy -3.206 1.525) (xy -3.207 1.523) (xy -3.21 1.521) (xy -3.21 1.519) (xy -3.211 1.517) (xy -3.214 1.515)
				(xy -3.215 1.513) (xy -3.218 1.511) (xy -3.219 1.509) (xy -3.222 1.509) (xy -3.223 1.507) (xy -3.226 1.505)
				(xy -3.227 1.503) (xy -3.23 1.503) (xy -3.234 1.501) (xy -3.235 1.501) (xy -3.238 1.501) (xy -3.242 1.499)
				(xy -3.246 1.499) (xy -3.247 1.499) (xy -3.25 1.499) (xy -3.65 1.499) (xy -3.653 1.499) (xy -3.656 1.499)
				(xy -3.658 1.499) (xy -3.661 1.499) (xy -3.664 1.497) (xy -3.665 1.497) (xy -3.669 1.497) (xy -3.67 1.495)
				(xy -3.673 1.495) (xy -3.676 1.493) (xy -3.677 1.491) (xy -3.68 1.489) (xy -3.681 1.489) (xy -3.684 1.487)
				(xy -3.685 1.485) (xy -3.688 1.483) (xy -3.689 1.481) (xy -3.69 1.479) (xy -3.693 1.477) (xy -3.693 1.475)
				(xy -3.696 1.473) (xy -3.697 1.469) (xy -3.697 1.467) (xy -3.698 1.465) (xy -3.698 1.463) (xy -3.7 1.459)
				(xy -3.7 1.457) (xy -3.701 1.455) (xy -3.701 1.453) (xy -3.701 1.449) (xy -3.701 1.35) (xy -3.701 1.346)
				(xy -3.701 1.344) (xy -3.7 1.342) (xy -3.7 1.34) (xy -3.698 1.336) (xy -3.698 1.334) (xy -3.697 1.332)
				(xy -3.697 1.33) (xy -3.696 1.326) (xy -3.693 1.324) (xy -3.693 1.322) (xy -3.69 1.32) (xy -3.689 1.318)
				(xy -3.688 1.316) (xy -3.685 1.314) (xy -3.684 1.312) (xy -3.681 1.31) (xy -3.68 1.31) (xy -3.677 1.308)
				(xy -3.676 1.306) (xy -3.673 1.304) (xy -3.67 1.304) (xy -3.669 1.302) (xy -3.665 1.302) (xy -3.664 1.302)
				(xy -3.661 1.3) (xy -3.658 1.3) (xy -3.656 1.3) (xy -3.653 1.3) (xy -3.65 1.3)
			)
			(stroke
				(width 0.0001)
				(type solid)
			)
			(fill yes)
			(layer "F.Paste")
		)
		(fp_poly
			(pts
				(xy -3.65 -1.901) (xy -3.051 -1.901) (xy -3.048 -1.901) (xy -3.045 -1.901) (xy -3.043 -1.899) (xy -3.04 -1.899)
				(xy -3.037 -1.899) (xy -3.036 -1.899) (xy -3.032 -1.897) (xy -3.031 -1.897) (xy -3.028 -1.895) (xy -3.025 -1.893)
				(xy -3.024 -1.893) (xy -3.021 -1.891) (xy -3.02 -1.889) (xy -3.017 -1.887) (xy -3.016 -1.885) (xy -3.013 -1.883)
				(xy -3.012 -1.881) (xy -3.011 -1.879) (xy -3.008 -1.877) (xy -3.008 -1.875) (xy -3.005 -1.873) (xy -3.004 -1.871)
				(xy -3.004 -1.869) (xy -3.003 -1.865) (xy -3.003 -1.863) (xy -3.001 -1.861) (xy -3.001 -1.859) (xy -3 -1.855)
				(xy -3 -1.853) (xy -3 -1.851) (xy -3 -1.351) (xy -3 -1.347) (xy -3 -1.345) (xy -3.001 -1.343) (xy -3.001 -1.341)
				(xy -3.003 -1.337) (xy -3.003 -1.335) (xy -3.004 -1.333) (xy -3.004 -1.331) (xy -3.005 -1.327) (xy -3.008 -1.325)
				(xy -3.008 -1.323) (xy -3.011 -1.321) (xy -3.012 -1.319) (xy -3.013 -1.317) (xy -3.016 -1.315) (xy -3.017 -1.313)
				(xy -3.02 -1.311) (xy -3.021 -1.311) (xy -3.024 -1.309) (xy -3.025 -1.307) (xy -3.028 -1.305) (xy -3.031 -1.305)
				(xy -3.032 -1.303) (xy -3.036 -1.303) (xy -3.037 -1.303) (xy -3.04 -1.301) (xy -3.043 -1.301) (xy -3.045 -1.301)
				(xy -3.048 -1.301) (xy -3.051 -1.301) (xy -3.65 -1.301) (xy -3.653 -1.301) (xy -3.656 -1.301) (xy -3.658 -1.301)
				(xy -3.661 -1.301) (xy -3.664 -1.303) (xy -3.665 -1.303) (xy -3.669 -1.303) (xy -3.67 -1.305) (xy -3.673 -1.305)
				(xy -3.676 -1.307) (xy -3.677 -1.309) (xy -3.68 -1.311) (xy -3.681 -1.311) (xy -3.684 -1.313) (xy -3.685 -1.315)
				(xy -3.688 -1.317) (xy -3.689 -1.319) (xy -3.69 -1.321) (xy -3.693 -1.323) (xy -3.693 -1.325) (xy -3.696 -1.327)
				(xy -3.697 -1.331) (xy -3.697 -1.333) (xy -3.698 -1.335) (xy -3.698 -1.337) (xy -3.7 -1.341) (xy -3.7 -1.343)
				(xy -3.701 -1.345) (xy -3.701 -1.347) (xy -3.701 -1.351) (xy -3.701 -1.45) (xy -3.701 -1.454) (xy -3.701 -1.456)
				(xy -3.7 -1.458) (xy -3.7 -1.46) (xy -3.698 -1.464) (xy -3.698 -1.466) (xy -3.697 -1.468) (xy -3.697 -1.47)
				(xy -3.696 -1.474) (xy -3.693 -1.476) (xy -3.693 -1.478) (xy -3.69 -1.48) (xy -3.689 -1.482) (xy -3.688 -1.484)
				(xy -3.685 -1.486) (xy -3.684 -1.488) (xy -3.681 -1.49) (xy -3.68 -1.49) (xy -3.677 -1.492) (xy -3.676 -1.494)
				(xy -3.673 -1.496) (xy -3.67 -1.496) (xy -3.669 -1.498) (xy -3.665 -1.498) (xy -3.664 -1.498) (xy -3.661 -1.5)
				(xy -3.658 -1.5) (xy -3.656 -1.5) (xy -3.653 -1.5) (xy -3.65 -1.5) (xy -3.25 -1.5) (xy -3.247 -1.5)
				(xy -3.246 -1.5) (xy -3.242 -1.502) (xy -3.238 -1.502) (xy -3.235 -1.502) (xy -3.234 -1.504) (xy -3.23 -1.504)
				(xy -3.227 -1.506) (xy -3.226 -1.508) (xy -3.223 -1.508) (xy -3.222 -1.51) (xy -3.219 -1.512) (xy -3.218 -1.514)
				(xy -3.215 -1.516) (xy -3.214 -1.518) (xy -3.211 -1.52) (xy -3.21 -1.522) (xy -3.21 -1.524) (xy -3.207 -1.526)
				(xy -3.206 -1.528) (xy -3.206 -1.53) (xy -3.203 -1.532) (xy -3.202 -1.536) (xy -3.202 -1.537) (xy -3.202 -1.541)
				(xy -3.202 -1.543) (xy -3.202 -1.545) (xy -3.202 -1.547) (xy -3.202 -1.551) (xy -3.202 -1.651) (xy -3.202 -1.653)
				(xy -3.202 -1.655) (xy -3.202 -1.659) (xy -3.202 -1.661) (xy -3.202 -1.663) (xy -3.202 -1.666) (xy -3.203 -1.668)
				(xy -3.206 -1.67) (xy -3.206 -1.674) (xy -3.207 -1.676) (xy -3.21 -1.678) (xy -3.21 -1.68) (xy -3.211 -1.682)
				(xy -3.214 -1.684) (xy -3.215 -1.686) (xy -3.218 -1.688) (xy -3.219 -1.69) (xy -3.222 -1.69) (xy -3.223 -1.692)
				(xy -3.226 -1.694) (xy -3.227 -1.696) (xy -3.23 -1.696) (xy -3.234 -1.698) (xy -3.235 -1.698) (xy -3.238 -1.698)
				(xy -3.242 -1.7) (xy -3.246 -1.7) (xy -3.247 -1.7) (xy -3.25 -1.7) (xy -3.65 -1.7) (xy -3.653 -1.7)
				(xy -3.656 -1.7) (xy -3.658 -1.702) (xy -3.661 -1.702) (xy -3.664 -1.702) (xy -3.665 -1.702) (xy -3.669 -1.704)
				(xy -3.67 -1.704) (xy -3.673 -1.706) (xy -3.676 -1.708) (xy -3.677 -1.708) (xy -3.68 -1.71) (xy -3.681 -1.712)
				(xy -3.684 -1.714) (xy -3.685 -1.716) (xy -3.688 -1.718) (xy -3.689 -1.72) (xy -3.69 -1.722) (xy -3.693 -1.724)
				(xy -3.693 -1.726) (xy -3.696 -1.728) (xy -3.697 -1.73) (xy -3.697 -1.732) (xy -3.698 -1.736) (xy -3.698 -1.738)
				(xy -3.7 -1.74) (xy -3.7 -1.742) (xy -3.701 -1.746) (xy -3.701 -1.748) (xy -3.701 -1.75) (xy -3.701 -1.851)
				(xy -3.701 -1.853) (xy -3.701 -1.855) (xy -3.7 -1.859) (xy -3.7 -1.861) (xy -3.698 -1.863) (xy -3.698 -1.865)
				(xy -3.697 -1.869) (xy -3.697 -1.871) (xy -3.696 -1.873) (xy -3.693 -1.875) (xy -3.693 -1.877) (xy -3.69 -1.879)
				(xy -3.689 -1.881) (xy -3.688 -1.883) (xy -3.685 -1.885) (xy -3.684 -1.887) (xy -3.681 -1.889) (xy -3.68 -1.891)
				(xy -3.677 -1.893) (xy -3.676 -1.893) (xy -3.673 -1.895) (xy -3.67 -1.897) (xy -3.669 -1.897) (xy -3.665 -1.899)
				(xy -3.664 -1.899) (xy -3.661 -1.899) (xy -3.658 -1.899) (xy -3.656 -1.901) (xy -3.653 -1.901) (xy -3.65 -1.901)
			)
			(stroke
				(width 0.0001)
				(type solid)
			)
			(fill yes)
			(layer "F.Paste")
		)
		(fp_rect
			(start -3.95 -3.95)
			(end 3.95 3.95)
			(stroke
				(width 0.05)
				(type solid)
			)
			(fill no)
			(layer "F.CrtYd")
		)
		(fp_line
			(start 3.499 3.499)
			(end -3.5 3.499)
			(stroke
				(width 0.15)
				(type solid)
			)
			(layer "F.Fab")
		)
		(fp_line
			(start 3.499 -3.5)
			(end 3.499 3.499)
			(stroke
				(width 0.15)
				(type solid)
			)
			(layer "F.Fab")
		)
		(fp_line
			(start -2.5 -3.5)
			(end 3.499 -3.5)
			(stroke
				(width 0.15)
				(type solid)
			)
			(layer "F.Fab")
		)
		(fp_line
			(start -3.5 3.499)
			(end -3.5 -2.5)
			(stroke
				(width 0.15)
				(type solid)
			)
			(layer "F.Fab")
		)
		(fp_line
			(start -3.5 -2.5)
			(end -2.5 -3.5)
			(stroke
				(width 0.15)
				(type solid)
			)
			(layer "F.Fab")
		)
		(fp_text user "License: Apache-2.0"
			(at -4.401 9.079 0)
			(layer "F.Fab")
			(effects
				(font
					(size 0.7 0.7)
					(thickness 0.15)
				)
				(justify right top)
			)
		)
		(fp_text user "Author: Antmicro"
			(at -4.401 8.079 0)
			(layer "F.Fab")
			(effects
				(font
					(size 0.7 0.7)
					(thickness 0.15)
				)
				(justify right top)
			)
		)
		(fp_text user "${REFERENCE}"
			(at -4.401 7.078 0)
			(layer "F.Fab")
			(effects
				(font
					(size 0.7 0.7)
					(thickness 0.15)
				)
				(justify right top)
			)
		)
		(pad "1" smd roundrect
			(at -3.351 -2.4 180)
			(size 0.8 0.65)
			(layers "F.Cu")
			(roundrect_rratio 0.09)
			(net 522 "/Power/USBPD1_HV")
			(pinfunction "PP_HV2")
			(pintype "bidirectional")
		)
		(pad "3" smd roundrect
			(at -3.351 -1.601 180)
			(size 0.8 0.65)
			(layers "F.Cu")
			(roundrect_rratio 0.09)
			(net 376 "/USB DP Alt mode/USBC1_VBUS")
			(pinfunction "VBUS2")
			(pintype "bidirectional")
		)
		(pad "5" smd roundrect
			(at -3.351 -1 180)
			(size 0.7 0.2)
			(layers "F.Cu" "F.Mask" "F.Paste")
			(roundrect_rratio 0.25)
			(net 2 "+3V3")
			(pinfunction "VIN_3V3")
			(pintype "power_in")
		)
		(pad "6" smd roundrect
			(at -3.351 -0.6 180)
			(size 0.7 0.2)
			(layers "F.Cu" "F.Mask" "F.Paste")
			(roundrect_rratio 0.25)
			(net 934 "/USB Debug, PD/PDC_ADCIN1")
			(pinfunction "ADCIN1")
			(pintype "input")
		)
		(pad "7" smd roundrect
			(at -3.351 -0.202 180)
			(size 0.7 0.2)
			(layers "F.Cu" "F.Mask" "F.Paste")
			(roundrect_rratio 0.25)
			(net 1149 "unconnected-(U30C-DRAIN2-Pad52)_2")
			(pinfunction "DRAIN2")
			(pintype "passive+no_connect")
		)
		(pad "8" smd roundrect
			(at -3.351 0.2 180)
			(size 0.7 0.2)
			(layers "F.Cu" "F.Mask" "F.Paste")
			(roundrect_rratio 0.25)
			(net 1145 "unconnected-(U30B-DRAIN1-Pad15)_3")
			(pinfunction "DRAIN1")
			(pintype "passive+no_connect")
		)
		(pad "9" smd roundrect
			(at -3.351 0.598 180)
			(size 0.7 0.2)
			(layers "F.Cu" "F.Mask" "F.Paste")
			(roundrect_rratio 0.25)
			(net 294 "/USB Debug, PD/PDC_LDO_3V3")
			(pinfunction "LDO_3V3")
			(pintype "power_out")
		)
		(pad "10" smd roundrect
			(at -3.351 0.998 180)
			(size 0.7 0.2)
			(layers "F.Cu" "F.Mask" "F.Paste")
			(roundrect_rratio 0.25)
			(net 935 "/USB Debug, PD/PDC_ADCIN2")
			(pinfunction "ADCIN2")
			(pintype "input")
		)
		(pad "11" smd roundrect
			(at -3.351 1.6 180)
			(size 0.8 0.65)
			(layers "F.Cu")
			(roundrect_rratio 0.09)
			(net 525 "/Power/USBPD2_HV")
			(pinfunction "PP_HV1")
			(pintype "bidirectional")
		)
		(pad "13" smd roundrect
			(at -3.351 2.398 180)
			(size 0.8 0.65)
			(layers "F.Cu")
			(roundrect_rratio 0.09)
			(net 176 "/USB Debug, PD/USBC0_VBUS")
			(pinfunction "VBUS1")
			(pintype "bidirectional")
		)
		(pad "15" smd roundrect
			(at -2.601 3.35 270)
			(size 0.7 0.2)
			(layers "F.Cu" "F.Mask" "F.Paste")
			(roundrect_rratio 0.25)
			(net 1157 "unconnected-(U30B-DRAIN1-Pad15)_8")
			(pinfunction "DRAIN1")
			(pintype "passive+no_connect")
		)
		(pad "16" smd roundrect
			(at -2.202 3.35 270)
			(size 0.7 0.2)
			(layers "F.Cu" "F.Mask" "F.Paste")
			(roundrect_rratio 0.25)
			(net 942 "/USB DP Alt mode/USBC1_FLIP")
			(pinfunction "GPIO0")
			(pintype "bidirectional")
		)
		(pad "17" smd roundrect
			(at -1.801 3.35 270)
			(size 0.7 0.2)
			(layers "F.Cu" "F.Mask" "F.Paste")
			(roundrect_rratio 0.25)
			(net 943 "/USB DP Alt mode/USBC1_CTL0")
			(pinfunction "GPIO1")
			(pintype "bidirectional")
		)
		(pad "18" smd roundrect
			(at -1.401 3.35 270)
			(size 0.7 0.2)
			(layers "F.Cu" "F.Mask" "F.Paste")
			(roundrect_rratio 0.25)
			(net 944 "/USB DP Alt mode/USBC1_CTL1")
			(pinfunction "GPIO2")
			(pintype "bidirectional")
		)
		(pad "19" smd roundrect
			(at -1 3.35 270)
			(size 0.7 0.2)
			(layers "F.Cu" "F.Mask" "F.Paste")
			(roundrect_rratio 0.25)
			(net 1144 "unconnected-(U30B-DRAIN1-Pad15)_2")
			(pinfunction "DRAIN1")
			(pintype "passive+no_connect")
		)
		(pad "20" smd roundrect
			(at -0.6 3.35 270)
			(size 0.7 0.2)
			(layers "F.Cu" "F.Mask" "F.Paste")
			(roundrect_rratio 0.25)
			(net 1 "GND")
			(pinfunction "GND")
			(pintype "power_in")
		)
		(pad "21" smd roundrect
			(at -0.202 3.35 270)
			(size 0.7 0.2)
			(layers "F.Cu" "F.Mask" "F.Paste")
			(roundrect_rratio 0.25)
			(net 1039 "/USB Debug, PD/PDC_I2C3_SCL")
			(pinfunction "I2C3_SCL")
			(pintype "bidirectional")
		)
		(pad "22" smd roundrect
			(at 0.2 3.35 270)
			(size 0.7 0.2)
			(layers "F.Cu" "F.Mask" "F.Paste")
			(roundrect_rratio 0.25)
			(net 1040 "/USB Debug, PD/PDC_I2C3_SDA")
			(pinfunction "I2C3_SDA")
			(pintype "bidirectional")
		)
		(pad "23" smd roundrect
			(at 0.598 3.35 270)
			(size 0.7 0.2)
			(layers "F.Cu" "F.Mask" "F.Paste")
			(roundrect_rratio 0.25)
			(net 1041 "/USB Debug, PD/~{PDC_I2C3_IRQ}")
			(pinfunction "~{I2C3_IRQ}")
			(pintype "bidirectional")
		)
		(pad "24" smd roundrect
			(at 0.998 3.35 270)
			(size 0.7 0.2)
			(layers "F.Cu" "F.Mask" "F.Paste")
			(roundrect_rratio 0.25)
			(net 514 "/USB Debug, PD/USBC0_CC1")
			(pinfunction "C1_CC1")
			(pintype "bidirectional")
		)
		(pad "25" smd roundrect
			(at 1.398 3.35 270)
			(size 0.7 0.2)
			(layers "F.Cu" "F.Mask" "F.Paste")
			(roundrect_rratio 0.25)
			(net 5 "+5V")
			(pinfunction "PP1_CABLE")
			(pintype "power_in")
		)
		(pad "26" smd roundrect
			(at 1.8 3.35 270)
			(size 0.7 0.2)
			(layers "F.Cu" "F.Mask" "F.Paste")
			(roundrect_rratio 0.25)
			(net 515 "/USB Debug, PD/USBC0_CC2")
			(pinfunction "C1_CC2")
			(pintype "bidirectional")
		)
		(pad "27" smd roundrect
			(at 2.2 3.35 270)
			(size 0.7 0.2)
			(layers "F.Cu" "F.Mask" "F.Paste")
			(roundrect_rratio 0.25)
			(net 945 "/USB Debug, PD/DEBUG_SCL")
			(pinfunction "I2C1_SCL")
			(pintype "bidirectional")
		)
		(pad "28" smd roundrect
			(at 2.6 3.35 270)
			(size 0.7 0.2)
			(layers "F.Cu" "F.Mask" "F.Paste")
			(roundrect_rratio 0.25)
			(net 946 "/USB Debug, PD/DEBUG_SDA")
			(pinfunction "I2C1_SDA")
			(pintype "bidirectional")
		)
		(pad "29" smd roundrect
			(at 3.35 2.6 180)
			(size 0.7 0.2)
			(layers "F.Cu" "F.Mask" "F.Paste")
			(roundrect_rratio 0.25)
			(net 953 "/USB Debug, PD/PDC_I2C1_IRQn")
			(pinfunction "~{I2C1_IRQ}")
			(pintype "output")
		)
		(pad "30" smd roundrect
			(at 3.35 2.2 180)
			(size 0.7 0.2)
			(layers "F.Cu" "F.Mask" "F.Paste")
			(roundrect_rratio 0.25)
			(net 1168 "Net-(U30A-HPD1)")
			(pinfunction "HPD1")
			(pintype "bidirectional")
		)
		(pad "31" smd roundrect
			(at 3.35 1.8 180)
			(size 0.7 0.2)
			(layers "F.Cu" "F.Mask" "F.Paste")
			(roundrect_rratio 0.25)
			(net 949 "/USB Debug, PD/PDC_HPD2")
			(pinfunction "HPD2")
			(pintype "bidirectional")
		)
		(pad "32" smd roundrect
			(at 3.35 1.398 180)
			(size 0.7 0.2)
			(layers "F.Cu" "F.Mask" "F.Paste")
			(roundrect_rratio 0.25)
			(net 947 "/USB Debug, PD/PDC_I2C2_SCL")
			(pinfunction "I2C2_SCL")
			(pintype "bidirectional")
		)
		(pad "33" smd roundrect
			(at 3.35 0.998 180)
			(size 0.7 0.2)
			(layers "F.Cu" "F.Mask" "F.Paste")
			(roundrect_rratio 0.25)
			(net 950 "/USB Debug, PD/PDC_I2C2_SDA")
			(pinfunction "I2C2_SDA")
			(pintype "bidirectional")
		)
		(pad "34" smd roundrect
			(at 3.35 0.598 180)
			(size 0.7 0.2)
			(layers "F.Cu" "F.Mask" "F.Paste")
			(roundrect_rratio 0.25)
			(net 1042 "/USB Debug, PD/PDC_I2C2_IRQn")
			(pinfunction "~{I2C2_IRQ}")
			(pintype "output")
		)
		(pad "35" smd roundrect
			(at 3.35 0.2 180)
			(size 0.7 0.2)
			(layers "F.Cu" "F.Mask" "F.Paste")
			(roundrect_rratio 0.25)
			(net 293 "/USB Debug, PD/PDC_LDO_1V8")
			(pinfunction "LDO_1V8")
			(pintype "power_out")
		)
		(pad "36" smd roundrect
			(at 3.35 -0.202 180)
			(size 0.7 0.2)
			(layers "F.Cu" "F.Mask" "F.Paste")
			(roundrect_rratio 0.25)
			(net 936 "/USB Debug, PD/PDC_MISO")
			(pinfunction "SPI_POCI")
			(pintype "bidirectional")
		)
		(pad "37" smd roundrect
			(at 3.35 -0.6 180)
			(size 0.7 0.2)
			(layers "F.Cu" "F.Mask" "F.Paste")
			(roundrect_rratio 0.25)
			(net 940 "/USB Debug, PD/PDC_MOSI")
			(pinfunction "SPI_PICO")
			(pintype "bidirectional")
		)
		(pad "38" smd roundrect
			(at 3.35 -1 180)
			(size 0.7 0.2)
			(layers "F.Cu" "F.Mask" "F.Paste")
			(roundrect_rratio 0.25)
			(net 941 "/USB Debug, PD/PDC_SCLK")
			(pinfunction "SPI_CLK")
			(pintype "bidirectional")
		)
		(pad "39" smd roundrect
			(at 3.35 -1.401 180)
			(size 0.7 0.2)
			(layers "F.Cu" "F.Mask" "F.Paste")
			(roundrect_rratio 0.25)
			(net 939 "/USB Debug, PD/~{PDC_CS}")
			(pinfunction "~{SPI_CS}")
			(pintype "bidirectional")
		)
		(pad "40" smd roundrect
			(at 3.35 -1.801 180)
			(size 0.7 0.2)
			(layers "F.Cu" "F.Mask" "F.Paste")
			(roundrect_rratio 0.25)
			(net 1109 "unconnected-(U30A-GPIO12-Pad40)")
			(pinfunction "GPIO12")
			(pintype "bidirectional+no_connect")
		)
		(pad "41" smd roundrect
			(at 3.35 -2.202 180)
			(size 0.7 0.2)
			(layers "F.Cu" "F.Mask" "F.Paste")
			(roundrect_rratio 0.25)
			(net 1110 "unconnected-(U30A-GPIO13-Pad41)")
			(pinfunction "GPIO13")
			(pintype "bidirectional+no_connect")
		)
		(pad "42" smd roundrect
			(at 3.35 -2.601 180)
			(size 0.7 0.2)
			(layers "F.Cu" "F.Mask" "F.Paste")
			(roundrect_rratio 0.25)
			(net 951 "/USB Debug, PD/PDC_GPIO14")
			(pinfunction "PWM1")
			(pintype "bidirectional")
		)
		(pad "43" smd roundrect
			(at 2.6 -3.351 270)
			(size 0.7 0.2)
			(layers "F.Cu" "F.Mask" "F.Paste")
			(roundrect_rratio 0.25)
			(net 952 "/USB Debug, PD/PDC_GPIO15")
			(pinfunction "PWM2")
			(pintype "bidirectional")
		)
		(pad "44" smd roundrect
			(at 2.2 -3.351 270)
			(size 0.7 0.2)
			(layers "F.Cu" "F.Mask" "F.Paste")
			(roundrect_rratio 0.25)
			(net 933 "/USB Debug, PD/PDC_RESET")
			(pinfunction "HRESET")
			(pintype "input")
		)
		(pad "45" smd roundrect
			(at 1.8 -3.351 270)
			(size 0.7 0.2)
			(layers "F.Cu" "F.Mask" "F.Paste")
			(roundrect_rratio 0.25)
			(net 817 "/USB DP Alt mode/USBC1_CC1")
			(pinfunction "C2_CC1")
			(pintype "bidirectional")
		)
		(pad "46" smd roundrect
			(at 1.398 -3.351 270)
			(size 0.7 0.2)
			(layers "F.Cu" "F.Mask" "F.Paste")
			(roundrect_rratio 0.25)
			(net 5 "+5V")
			(pinfunction "PP2_CABLE")
			(pintype "power_in")
		)
		(pad "47" smd roundrect
			(at 0.998 -3.351 270)
			(size 0.7 0.2)
			(layers "F.Cu" "F.Mask" "F.Paste")
			(roundrect_rratio 0.25)
			(net 816 "/USB DP Alt mode/USBC1_CC2")
			(pinfunction "C2_CC2")
			(pintype "bidirectional")
		)
		(pad "48" smd roundrect
			(at 0.598 -3.351 270)
			(size 0.7 0.2)
			(layers "F.Cu" "F.Mask" "F.Paste")
			(roundrect_rratio 0.25)
			(net 975 "/USB Debug, PD/USBC0_5V_PEN")
			(pinfunction "PP_EXT1")
			(pintype "bidirectional")
		)
		(pad "49" smd roundrect
			(at 0.2 -3.351 270)
			(size 0.7 0.2)
			(layers "F.Cu" "F.Mask" "F.Paste")
			(roundrect_rratio 0.25)
			(net 970 "/USB DP Alt mode/USBC1_5V_PEN")
			(pinfunction "PP_EXT2")
			(pintype "bidirectional")
		)
		(pad "50" smd roundrect
			(at -0.202 -3.351 270)
			(size 0.7 0.2)
			(layers "F.Cu" "F.Mask" "F.Paste")
			(roundrect_rratio 0.25)
			(net 1176 "unconnected-(U30B-C1_USB_P-Pad50)")
			(pinfunction "C1_USB_P")
			(pintype "bidirectional+no_connect")
		)
		(pad "51" smd roundrect
			(at -0.6 -3.351 270)
			(size 0.7 0.2)
			(layers "F.Cu" "F.Mask" "F.Paste")
			(roundrect_rratio 0.25)
			(net 1 "GND")
			(pinfunction "GND")
			(pintype "passive")
		)
		(pad "52" smd roundrect
			(at -1 -3.351 270)
			(size 0.7 0.2)
			(layers "F.Cu" "F.Mask" "F.Paste")
			(roundrect_rratio 0.25)
			(net 1148 "unconnected-(U30C-DRAIN2-Pad52)_1")
			(pinfunction "DRAIN2")
			(pintype "passive+no_connect")
		)
		(pad "53" smd roundrect
			(at -1.401 -3.351 270)
			(size 0.7 0.2)
			(layers "F.Cu" "F.Mask" "F.Paste")
			(roundrect_rratio 0.25)
			(net 1178 "unconnected-(U30B-C1_USB_N-Pad53)")
			(pinfunction "C1_USB_N")
			(pintype "bidirectional+no_connect")
		)
		(pad "54" smd roundrect
			(at -1.801 -3.351 270)
			(size 0.7 0.2)
			(layers "F.Cu" "F.Mask" "F.Paste")
			(roundrect_rratio 0.25)
			(net 1177 "unconnected-(U30C-C2_USB_P-Pad54)")
			(pinfunction "C2_USB_P")
			(pintype "bidirectional+no_connect")
		)
		(pad "55" smd roundrect
			(at -2.202 -3.351 270)
			(size 0.7 0.2)
			(layers "F.Cu" "F.Mask" "F.Paste")
			(roundrect_rratio 0.25)
			(net 1179 "unconnected-(U30C-C2_USB_N-Pad55)")
			(pinfunction "C2_USB_N")
			(pintype "bidirectional+no_connect")
		)
		(pad "56" smd roundrect
			(at -2.601 -3.351 270)
			(size 0.7 0.2)
			(layers "F.Cu" "F.Mask" "F.Paste")
			(roundrect_rratio 0.25)
			(net 1139 "unconnected-(U30C-DRAIN2-Pad52)")
			(pinfunction "DRAIN2")
			(pintype "passive+no_connect")
		)
		(pad "57" thru_hole circle
			(at -2.351 -2.327 180)
			(size 0.45 0.45)
			(drill 0.1)
			(layers "*.Cu")
			(remove_unused_layers no)
			(net 1152 "unconnected-(U30C-DRAIN2-Pad52)_5")
			(pinfunction "DRAIN2")
			(pintype "passive+no_connect")
		)
		(pad "57" thru_hole circle
			(at -2.351 -1.45 180)
			(size 0.45 0.45)
			(drill 0.1)
			(layers "*.Cu")
			(remove_unused_layers no)
			(net 1150 "unconnected-(U30C-DRAIN2-Pad52)_3")
			(pinfunction "DRAIN2")
			(pintype "passive+no_connect")
		)
		(pad "57" thru_hole circle
			(at -2.351 -0.576 180)
			(size 0.45 0.45)
			(drill 0.1)
			(layers "*.Cu")
			(remove_unused_layers no)
			(net 1154 "unconnected-(U30C-DRAIN2-Pad52)_7")
			(pinfunction "DRAIN2")
			(pintype "passive+no_connect")
		)
		(pad "57" smd roundrect
			(at -1.875 -1.45 270)
			(size 2.6 1.75)
			(layers "F.Cu" "F.Mask")
			(roundrect_rratio 0.05714285714)
			(net 1151 "unconnected-(U30C-DRAIN2-Pad52)_4")
			(pinfunction "DRAIN2")
			(pintype "passive+no_connect")
			(solder_mask_margin 0.05)
		)
		(pad "57" thru_hole circle
			(at -1.401 -2.327 180)
			(size 0.45 0.45)
			(drill 0.1)
			(layers "*.Cu")
			(remove_unused_layers no)
			(net 1159 "unconnected-(U30C-DRAIN2-Pad52)_8")
			(pinfunction "DRAIN2")
			(pintype "passive+no_connect")
		)
		(pad "57" thru_hole circle
			(at -1.401 -1.45 180)
			(size 0.45 0.45)
			(drill 0.1)
			(layers "*.Cu")
			(remove_unused_layers no)
			(net 1153 "unconnected-(U30C-DRAIN2-Pad52)_6")
			(pinfunction "DRAIN2")
			(pintype "passive+no_connect")
		)
		(pad "57" thru_hole circle
			(at -1.401 -0.577 180)
			(size 0.45 0.45)
			(drill 0.1)
			(layers "*.Cu")
			(remove_unused_layers no)
			(net 1160 "unconnected-(U30C-DRAIN2-Pad52)_9")
			(pinfunction "DRAIN2")
			(pintype "passive+no_connect")
		)
		(pad "58" thru_hole circle
			(at -2.351 0.598 180)
			(size 0.45 0.45)
			(drill 0.1)
			(layers "*.Cu")
			(remove_unused_layers no)
			(net 1140 "unconnected-(U30B-DRAIN1-Pad15)")
			(pinfunction "DRAIN1")
			(pintype "passive+no_connect")
		)
		(pad "58" thru_hole circle
			(at -2.351 1.475 180)
			(size 0.45 0.45)
			(drill 0.1)
			(layers "*.Cu")
			(remove_unused_layers no)
			(net 1143 "unconnected-(U30B-DRAIN1-Pad15)_1")
			(pinfunction "DRAIN1")
			(pintype "passive+no_connect")
		)
		(pad "58" thru_hole circle
			(at -2.351 2.35 180)
			(size 0.45 0.45)
			(drill 0.1)
			(layers "*.Cu")
			(remove_unused_layers no)
			(net 1147 "unconnected-(U30B-DRAIN1-Pad15)_5")
			(pinfunction "DRAIN1")
			(pintype "passive+no_connect")
		)
		(pad "58" smd roundrect
			(at -1.875 1.475 270)
			(size 2.55 1.75)
			(layers "F.Cu" "F.Mask")
			(roundrect_rratio 0.05714285714)
			(net 1156 "unconnected-(U30B-DRAIN1-Pad15)_7")
			(pinfunction "DRAIN1")
			(pintype "passive+no_connect")
			(solder_mask_margin 0.05)
		)
		(pad "58" thru_hole circle
			(at -1.401 0.598 180)
			(size 0.45 0.45)
			(drill 0.1)
			(layers "*.Cu")
			(remove_unused_layers no)
			(net 1146 "unconnected-(U30B-DRAIN1-Pad15)_4")
			(pinfunction "DRAIN1")
			(pintype "passive+no_connect")
		)
		(pad "58" thru_hole circle
			(at -1.401 1.475 180)
			(size 0.45 0.45)
			(drill 0.1)
			(layers "*.Cu")
			(remove_unused_layers no)
			(net 1155 "unconnected-(U30B-DRAIN1-Pad15)_6")
			(pinfunction "DRAIN1")
			(pintype "passive+no_connect")
		)
		(pad "58" thru_hole circle
			(at -1.401 2.349 180)
			(size 0.45 0.45)
			(drill 0.1)
			(layers "*.Cu")
			(remove_unused_layers no)
			(net 1158 "unconnected-(U30B-DRAIN1-Pad15)_9")
			(pinfunction "DRAIN1")
			(pintype "passive+no_connect")
		)
		(pad "59" thru_hole circle
			(at -0.152 1.322 180)
			(size 0.45 0.45)
			(drill 0.1)
			(layers "*.Cu")
			(remove_unused_layers no)
			(net 1 "GND")
			(pinfunction "GND_EP")
			(pintype "power_in")
		)
		(pad "59" thru_hole circle
			(at -0.15 -1.321 180)
			(size 0.45 0.45)
			(drill 0.1)
			(layers "*.Cu")
			(remove_unused_layers no)
			(net 1 "GND")
			(pinfunction "GND_EP")
			(pintype "power_in")
		)
		(pad "59" thru_hole circle
			(at -0.15 0 180)
			(size 0.45 0.45)
			(drill 0.1)
			(layers "*.Cu")
			(remove_unused_layers no)
			(net 1 "GND")
			(pinfunction "GND_EP")
			(pintype "power_in")
		)
		(pad "59" thru_hole circle
			(at 1.048 -2.504 180)
			(size 0.45 0.45)
			(drill 0.1)
			(layers "*.Cu")
			(remove_unused_layers no)
			(net 1 "GND")
			(pinfunction "GND_EP")
			(pintype "power_in")
		)
		(pad "59" thru_hole circle
			(at 1.048 -1.327 180)
			(size 0.45 0.45)
			(drill 0.1)
			(layers "*.Cu")
			(remove_unused_layers no)
			(net 1 "GND")
			(pinfunction "GND_EP")
			(pintype "power_in")
		)
		(pad "59" thru_hole circle
			(at 1.048 1.322 180)
			(size 0.45 0.45)
			(drill 0.1)
			(layers "*.Cu")
			(remove_unused_layers no)
			(net 1 "GND")
			(pinfunction "GND_EP")
			(pintype "power_in")
		)
		(pad "59" thru_hole circle
			(at 1.048 2.496 180)
			(size 0.45 0.45)
			(drill 0.1)
			(layers "*.Cu")
			(remove_unused_layers no)
			(net 1 "GND")
			(pinfunction "GND_EP")
			(pintype "power_in")
		)
		(pad "59" thru_hole circle
			(at 1.05 0 180)
			(size 0.45 0.45)
			(drill 0.1)
			(layers "*.Cu")
			(remove_unused_layers no)
			(net 1 "GND")
			(pinfunction "GND_EP")
			(pintype "power_in")
		)
		(pad "59" smd roundrect
			(at 1.05 0 270)
			(size 5.5 3.4)
			(layers "F.Cu" "F.Mask")
			(roundrect_rratio 0.02941176471)
			(net 1 "GND")
			(pinfunction "GND_EP")
			(pintype "power_in")
			(solder_mask_margin 0.05)
		)
		(pad "59" thru_hole circle
			(at 2.248 -1.327 180)
			(size 0.45 0.45)
			(drill 0.1)
			(layers "*.Cu")
			(remove_unused_layers no)
			(net 1 "GND")
			(pinfunction "GND_EP")
			(pintype "power_in")
		)
		(pad "59" thru_hole circle
			(at 2.248 -0.001 180)
			(size 0.45 0.45)
			(drill 0.1)
			(layers "*.Cu")
			(remove_unused_layers no)
			(net 1 "GND")
			(pinfunction "GND_EP")
			(pintype "power_in")
		)
		(pad "59" thru_hole circle
			(at 2.248 1.322 180)
			(size 0.45 0.45)
			(drill 0.1)
			(layers "*.Cu")
			(remove_unused_layers no)
			(net 1 "GND")
			(pinfunction "GND_EP")
			(pintype "power_in")
		)
	)
	(footprint "antmicro-footprints:C_0603_1608Metric_EIA"
		(layer "F.Cu")
		(at 177.75 113.59 -90)
		(descr "Capacitor SMD 0603, IPC-7351 Density Level A")
		(tags "Capacitor 0603")
		(property "Reference" "C66"
			(at 1.01 7.45 90)
			(layer "F.SilkS")
			(effects
				(font
					(size 0.7 0.7)
					(thickness 0.15)
				)
				(justify left bottom)
			)
		)
		(property "Value" "C_22u_16V_0603"
			(at -1.42757 1.770288 90)
			(layer "F.Fab")
			(effects
				(font
					(size 0.7 0.7)
					(thickness 0.15)
				)
				(justify right top)
			)
		)
		(property "Datasheet" "https://product.samsungsem.com/mlcc/CL10A226MO7JZN.do"
			(at 0 0 90)
			(layer "F.Fab")
			(hide yes)
			(effects
				(font
					(size 1.27 1.27)
					(thickness 0.15)
				)
			)
		)
		(property "Description" "SMD Multilayer Ceramic Capacitor"
			(at 0 0 90)
			(layer "F.Fab")
			(hide yes)
			(effects
				(font
					(size 1.27 1.27)
					(thickness 0.15)
				)
			)
		)
		(property "Manufacturer" "Samsung Electro-Mechanics"
			(at 0 0 270)
			(unlocked yes)
			(layer "F.Fab")
			(hide yes)
			(effects
				(font
					(size 1 1)
					(thickness 0.15)
				)
			)
		)
		(property "MPN" "CL10A226MO7JZNC"
			(at 0 0 270)
			(unlocked yes)
			(layer "F.Fab")
			(hide yes)
			(effects
				(font
					(size 1 1)
					(thickness 0.15)
				)
			)
		)
		(property "Val" "22u"
			(at 0 0 270)
			(unlocked yes)
			(layer "F.Fab")
			(hide yes)
			(effects
				(font
					(size 1 1)
					(thickness 0.15)
				)
			)
		)
		(property "License" "Apache-2.0"
			(at 0 0 270)
			(unlocked yes)
			(layer "F.Fab")
			(hide yes)
			(effects
				(font
					(size 1 1)
					(thickness 0.15)
				)
			)
		)
		(property "Author" "Antmicro"
			(at 0 0 270)
			(unlocked yes)
			(layer "F.Fab")
			(hide yes)
			(effects
				(font
					(size 1 1)
					(thickness 0.15)
				)
			)
		)
		(property "Voltage" "16V"
			(at 0 0 270)
			(unlocked yes)
			(layer "F.Fab")
			(hide yes)
			(effects
				(font
					(size 1 1)
					(thickness 0.15)
				)
			)
		)
		(property "Dielectric" ""
			(at 0 0 270)
			(unlocked yes)
			(layer "F.Fab")
			(hide yes)
			(effects
				(font
					(size 1 1)
					(thickness 0.15)
				)
			)
		)
		(sheetname "/DCDC/")
		(sheetfile "dcdc.kicad_sch")
		(attr smd)
		(fp_line
			(start -0.15 0.55)
			(end 0.15 0.55)
			(stroke
				(width 0.15)
				(type solid)
			)
			(layer "F.SilkS")
		)
		(fp_line
			(start -0.15 -0.55)
			(end 0.15 -0.55)
			(stroke
				(width 0.15)
				(type solid)
			)
			(layer "F.SilkS")
		)
		(fp_rect
			(start -1.25 -0.65)
			(end 1.25 0.65)
			(stroke
				(width 0.05)
				(type solid)
			)
			(fill no)
			(layer "F.CrtYd")
		)
		(fp_rect
			(start -0.8 -0.45)
			(end 0.8 0.45)
			(stroke
				(width 0.15)
				(type solid)
			)
			(fill no)
			(layer "F.Fab")
		)
		(fp_text user "License: Apache-2.0"
			(at -1.682 5.895 90)
			(layer "F.Fab")
			(effects
				(font
					(size 0.7 0.7)
					(thickness 0.15)
				)
				(justify right top)
			)
		)
		(fp_text user "${REFERENCE}"
			(at -1.682 3.895 90)
			(layer "F.Fab")
			(effects
				(font
					(size 0.7 0.7)
					(thickness 0.15)
				)
				(justify right top)
			)
		)
		(fp_text user "Author: Antmicro"
			(at -1.682 4.894 90)
			(layer "F.Fab")
			(effects
				(font
					(size 0.7 0.7)
					(thickness 0.15)
				)
				(justify right top)
			)
		)
		(pad "1" smd roundrect
			(at -0.7 0 270)
			(size 0.8 1.1)
			(layers "F.Cu" "F.Mask" "F.Paste")
			(roundrect_rratio 0.2)
			(net 1 "GND")
			(pintype "passive")
		)
		(pad "2" smd roundrect
			(at 0.7 0 270)
			(size 0.8 1.1)
			(layers "F.Cu" "F.Mask" "F.Paste")
			(roundrect_rratio 0.2)
			(net 253 "/DCDC/5V_OUT")
			(pintype "passive")
		)
	)
	(footprint "antmicro-footprints:R_0402_1005Metric"
		(layer "F.Cu")
		(at 138.73 135.05 180)
		(descr "Resistor SMD 0402")
		(tags "resistor SMD 0402")
		(property "Reference" "R56"
			(at -1.122484 -0.772697 0)
			(layer "F.SilkS")
			(effects
				(font
					(size 0.7 0.7)
					(thickness 0.15)
				)
				(justify right top)
			)
		)
		(property "Value" "R_470R_0402"
			(at -1.011843 1.772047 0)
			(layer "F.Fab")
			(effects
				(font
					(size 0.7 0.7)
					(thickness 0.15)
				)
				(justify right top)
			)
		)
		(property "Datasheet" "https://www.bourns.com/docs/product-datasheets/cr.pdf"
			(at 0 0 0)
			(layer "F.Fab")
			(hide yes)
			(effects
				(font
					(size 1.27 1.27)
					(thickness 0.15)
				)
			)
		)
		(property "Description" "SMD Chip Resistor, 470 ohm, ± 1%, 62.5 mW, 0402 [1005 Metric], Thick Film, General Purpose"
			(at 0 0 0)
			(layer "F.Fab")
			(hide yes)
			(effects
				(font
					(size 1.27 1.27)
					(thickness 0.15)
				)
			)
		)
		(property "MPN" "CR0402-FX-4700GLF"
			(at 0 0 180)
			(unlocked yes)
			(layer "F.Fab")
			(hide yes)
			(effects
				(font
					(size 1 1)
					(thickness 0.15)
				)
			)
		)
		(property "Manufacturer" "Bourns"
			(at 0 0 180)
			(unlocked yes)
			(layer "F.Fab")
			(hide yes)
			(effects
				(font
					(size 1 1)
					(thickness 0.15)
				)
			)
		)
		(property "License" "Apache-2.0"
			(at 0 0 180)
			(unlocked yes)
			(layer "F.Fab")
			(hide yes)
			(effects
				(font
					(size 1 1)
					(thickness 0.15)
				)
			)
		)
		(property "Author" "Antmicro"
			(at 0 0 180)
			(unlocked yes)
			(layer "F.Fab")
			(hide yes)
			(effects
				(font
					(size 1 1)
					(thickness 0.15)
				)
			)
		)
		(property "Val" "470R"
			(at 0 0 180)
			(unlocked yes)
			(layer "F.Fab")
			(hide yes)
			(effects
				(font
					(size 1 1)
					(thickness 0.15)
				)
			)
		)
		(property "Tolerance" "1%"
			(at 0 0 180)
			(unlocked yes)
			(layer "F.Fab")
			(hide yes)
			(effects
				(font
					(size 1 1)
					(thickness 0.15)
				)
			)
		)
		(sheetname "/SoM_Power/")
		(sheetfile "som_power.kicad_sch")
		(attr smd)
		(fp_rect
			(start -0.925 -0.47)
			(end 0.925 0.47)
			(stroke
				(width 0.05)
				(type default)
			)
			(fill no)
			(layer "F.CrtYd")
		)
		(fp_rect
			(start -0.5 -0.25)
			(end 0.5 0.25)
			(stroke
				(width 0.15)
				(type solid)
			)
			(fill no)
			(layer "F.Fab")
		)
		(fp_text user "License: Apache-2.0"
			(at -0.95 5.169 0)
			(layer "F.Fab")
			(effects
				(font
					(size 0.7 0.7)
					(thickness 0.15)
				)
				(justify right top)
			)
		)
		(fp_text user "Author: Antmicro"
			(at -0.95 4.169 0)
			(layer "F.Fab")
			(effects
				(font
					(size 0.7 0.7)
					(thickness 0.15)
				)
				(justify right top)
			)
		)
		(fp_text user "${REFERENCE}"
			(at -0.95 3.168 0)
			(layer "F.Fab")
			(effects
				(font
					(size 0.7 0.7)
					(thickness 0.15)
				)
				(justify right top)
			)
		)
		(pad "1" smd roundrect
			(at -0.48 0 180)
			(size 0.59 0.64)
			(layers "F.Cu" "F.Mask" "F.Paste")
			(roundrect_rratio 0.25)
			(net 885 "Net-(Q10-D)")
			(pintype "passive")
		)
		(pad "2" smd roundrect
			(at 0.48 0 180)
			(size 0.59 0.64)
			(layers "F.Cu" "F.Mask" "F.Paste")
			(roundrect_rratio 0.25)
			(net 5 "+5V")
			(pintype "passive")
		)
	)
	(footprint "antmicro-footprints:USON-10_2.5x1mm_P0.5mm"
		(layer "F.Cu")
		(at 203.487 111.3)
		(descr "USON-10 2.5x1mm_ Pitch 0.5mm")
		(tags "USON-10 2.5x1mm Pitch 0.5mm")
		(property "Reference" "U4"
			(at 0.018 -1.7 0)
			(layer "F.SilkS")
			(effects
				(font
					(size 0.7 0.7)
					(thickness 0.15)
				)
				(justify left bottom)
			)
		)
		(property "Value" "TPD4E05U06QDQARQ1"
			(at 0.018 2.499 0)
			(layer "F.Fab")
			(effects
				(font
					(size 0.7 0.7)
					(thickness 0.15)
				)
				(justify left bottom)
			)
		)
		(property "Datasheet" "https://www.ti.com/lit/ds/symlink/tpd4e05u06-q1.pdf?HQS=dis-mous-null-mousermode-dsf-pf-null-wwe&ts=1663591265741&ref_url=https%253A%252F%252Fwww.mouser.com%252F"
			(at 0 0 0)
			(layer "F.Fab")
			(hide yes)
			(effects
				(font
					(size 1.27 1.27)
					(thickness 0.15)
				)
			)
		)
		(property "Description" "TVS diode array, 12 kV, USON-10, 5.5 V, 0.5 pF"
			(at 0 0 0)
			(layer "F.Fab")
			(hide yes)
			(effects
				(font
					(size 1.27 1.27)
					(thickness 0.15)
				)
			)
		)
		(property "Manufacturer" "Texas Instruments"
			(at 0 0 0)
			(unlocked yes)
			(layer "F.Fab")
			(hide yes)
			(effects
				(font
					(size 1 1)
					(thickness 0.15)
				)
			)
		)
		(property "MPN" "TPD4E05U06QDQARQ1"
			(at 0 0 0)
			(unlocked yes)
			(layer "F.Fab")
			(hide yes)
			(effects
				(font
					(size 1 1)
					(thickness 0.15)
				)
			)
		)
		(property "Author" "Antmicro"
			(at 0 0 0)
			(unlocked yes)
			(layer "F.Fab")
			(hide yes)
			(effects
				(font
					(size 1 1)
					(thickness 0.15)
				)
			)
		)
		(property "License" "Apache-2.0"
			(at 0 0 0)
			(unlocked yes)
			(layer "F.Fab")
			(hide yes)
			(effects
				(font
					(size 1 1)
					(thickness 0.15)
				)
			)
		)
		(sheetname "/SoM_Power/")
		(sheetfile "som_power.kicad_sch")
		(attr smd exclude_from_pos_files exclude_from_bom dnp)
		(fp_line
			(start 0.498 -1.401)
			(end -0.5 -1.401)
			(stroke
				(width 0.15)
				(type solid)
			)
			(layer "F.SilkS")
		)
		(fp_line
			(start 0.498 1.398)
			(end -0.5 1.398)
			(stroke
				(width 0.15)
				(type solid)
			)
			(layer "F.SilkS")
		)
		(fp_circle
			(center -0.68 -1.27)
			(end -0.63 -1.27)
			(stroke
				(width 0.15)
				(type solid)
			)
			(fill yes)
			(layer "F.SilkS")
		)
		(fp_rect
			(start -0.8 -1.5)
			(end 0.8 1.499)
			(stroke
				(width 0.05)
				(type solid)
			)
			(fill no)
			(layer "F.CrtYd")
		)
		(fp_line
			(start -0.5 -1)
			(end -0.5 1.249)
			(stroke
				(width 0.15)
				(type solid)
			)
			(layer "F.Fab")
		)
		(fp_line
			(start -0.5 1.249)
			(end 0.498 1.249)
			(stroke
				(width 0.15)
				(type solid)
			)
			(layer "F.Fab")
		)
		(fp_line
			(start -0.25 -1.25)
			(end -0.5 -1)
			(stroke
				(width 0.15)
				(type solid)
			)
			(layer "F.Fab")
		)
		(fp_line
			(start 0.498 -1.25)
			(end -0.25 -1.25)
			(stroke
				(width 0.15)
				(type solid)
			)
			(layer "F.Fab")
		)
		(fp_line
			(start 0.498 -1.25)
			(end 0.498 1.249)
			(stroke
				(width 0.15)
				(type solid)
			)
			(layer "F.Fab")
		)
		(fp_text user "Author: Antmicro"
			(at -0.802 5.7 0)
			(layer "F.Fab")
			(effects
				(font
					(size 0.7 0.7)
					(thickness 0.15)
				)
				(justify left bottom)
			)
		)
		(fp_text user "${REFERENCE}"
			(at -0.802 4.498 0)
			(layer "F.Fab")
			(effects
				(font
					(size 0.7 0.7)
					(thickness 0.15)
				)
				(justify left bottom)
			)
		)
		(fp_text user "License: Apache-2.0"
			(at -0.802 6.9 0)
			(layer "F.Fab")
			(effects
				(font
					(size 0.7 0.7)
					(thickness 0.15)
				)
				(justify left bottom)
			)
		)
		(pad "1" smd roundrect
			(at -0.387 -1 270)
			(size 0.25 0.55)
			(layers "F.Cu" "F.Mask" "F.Paste")
			(roundrect_rratio 0.25)
			(net 610 "/SoM_Power/~{PWR_BTN}")
			(pintype "passive")
		)
		(pad "2" smd roundrect
			(at -0.387 -0.5 270)
			(size 0.25 0.55)
			(layers "F.Cu" "F.Mask" "F.Paste")
			(roundrect_rratio 0.25)
			(net 702 "/SoM_Power/~{SYS_RESET}")
			(pintype "passive")
		)
		(pad "3" smd roundrect
			(at -0.387 0 270)
			(size 0.4 0.55)
			(layers "F.Cu" "F.Mask" "F.Paste")
			(roundrect_rratio 0.25)
			(net 1 "GND")
			(pintype "power_in")
		)
		(pad "4" smd roundrect
			(at -0.387 0.498 270)
			(size 0.25 0.55)
			(layers "F.Cu" "F.Mask" "F.Paste")
			(roundrect_rratio 0.25)
			(net 495 "/SoM_Power/~{FORCE_RECOVERY}")
			(pintype "passive")
		)
		(pad "5" smd roundrect
			(at -0.387 0.998 270)
			(size 0.25 0.55)
			(layers "F.Cu" "F.Mask" "F.Paste")
			(roundrect_rratio 0.25)
			(net 1398 "unconnected-(U4-Pad5)")
			(pintype "passive+no_connect")
		)
		(pad "6" smd roundrect
			(at 0.385 0.998 270)
			(size 0.25 0.55)
			(layers "F.Cu" "F.Mask" "F.Paste")
			(roundrect_rratio 0.25)
			(net 1399 "unconnected-(U4-Pad5)_1")
			(pintype "passive+no_connect")
		)
		(pad "7" smd roundrect
			(at 0.385 0.498 270)
			(size 0.25 0.55)
			(layers "F.Cu" "F.Mask" "F.Paste")
			(roundrect_rratio 0.25)
			(net 495 "/SoM_Power/~{FORCE_RECOVERY}")
			(pintype "passive")
		)
		(pad "8" smd roundrect
			(at 0.385 0 270)
			(size 0.4 0.55)
			(layers "F.Cu" "F.Mask" "F.Paste")
			(roundrect_rratio 0.25)
			(net 1 "GND")
			(pintype "passive")
		)
		(pad "9" smd roundrect
			(at 0.385 -0.5 270)
			(size 0.25 0.55)
			(layers "F.Cu" "F.Mask" "F.Paste")
			(roundrect_rratio 0.25)
			(net 702 "/SoM_Power/~{SYS_RESET}")
			(pintype "passive")
		)
		(pad "10" smd roundrect
			(at 0.385 -1 270)
			(size 0.25 0.55)
			(layers "F.Cu" "F.Mask" "F.Paste")
			(roundrect_rratio 0.25)
			(net 610 "/SoM_Power/~{PWR_BTN}")
			(pintype "passive")
		)
	)
	(footprint "antmicro-footprints:R_0402_1005Metric"
		(layer "F.Cu")
		(at 171.254468 133.12 90)
		(descr "Resistor SMD 0402")
		(tags "resistor SMD 0402")
		(property "Reference" "R316"
			(at -1.28 3.545532 90)
			(layer "F.SilkS")
			(effects
				(font
					(size 0.7 0.7)
					(thickness 0.15)
				)
				(justify left bottom)
			)
		)
		(property "Value" "R_27R_0402"
			(at -1.011843 1.772047 90)
			(layer "F.Fab")
			(effects
				(font
					(size 0.7 0.7)
					(thickness 0.15)
				)
				(justify left bottom)
			)
		)
		(property "Datasheet" "https://www.bourns.com/docs/product-datasheets/cr.pdf"
			(at 0 0 90)
			(layer "F.Fab")
			(hide yes)
			(effects
				(font
					(size 1.27 1.27)
					(thickness 0.15)
				)
			)
		)
		(property "Description" "SMD Chip Resistor, 27 ohm, ± 1%, 63 mW, 0402 [1005 Metric], Thick Film, General Purpose"
			(at 0 0 90)
			(layer "F.Fab")
			(hide yes)
			(effects
				(font
					(size 1.27 1.27)
					(thickness 0.15)
				)
			)
		)
		(property "MPN" "CR0402-FX-27R0GLF"
			(at 0 0 90)
			(unlocked yes)
			(layer "F.Fab")
			(hide yes)
			(effects
				(font
					(size 1 1)
					(thickness 0.15)
				)
			)
		)
		(property "Manufacturer" "Bourns"
			(at 0 0 90)
			(unlocked yes)
			(layer "F.Fab")
			(hide yes)
			(effects
				(font
					(size 1 1)
					(thickness 0.15)
				)
			)
		)
		(property "License" "Apache-2.0"
			(at 0 0 90)
			(unlocked yes)
			(layer "F.Fab")
			(hide yes)
			(effects
				(font
					(size 1 1)
					(thickness 0.15)
				)
			)
		)
		(property "Author" "Antmicro"
			(at 0 0 90)
			(unlocked yes)
			(layer "F.Fab")
			(hide yes)
			(effects
				(font
					(size 1 1)
					(thickness 0.15)
				)
			)
		)
		(property "Val" "27R"
			(at 0 0 90)
			(unlocked yes)
			(layer "F.Fab")
			(hide yes)
			(effects
				(font
					(size 1 1)
					(thickness 0.15)
				)
			)
		)
		(property "Tolerance" "1%"
			(at 0 0 90)
			(unlocked yes)
			(layer "F.Fab")
			(hide yes)
			(effects
				(font
					(size 1 1)
					(thickness 0.15)
				)
			)
		)
		(sheetname "/DCDC/")
		(sheetfile "dcdc.kicad_sch")
		(attr smd)
		(fp_rect
			(start -0.925 -0.47)
			(end 0.925 0.47)
			(stroke
				(width 0.05)
				(type default)
			)
			(fill no)
			(layer "F.CrtYd")
		)
		(fp_rect
			(start -0.5 -0.25)
			(end 0.5 0.25)
			(stroke
				(width 0.15)
				(type solid)
			)
			(fill no)
			(layer "F.Fab")
		)
		(fp_text user "License: Apache-2.0"
			(at -0.95 5.169 90)
			(layer "F.Fab")
			(effects
				(font
					(size 0.7 0.7)
					(thickness 0.15)
				)
				(justify left bottom)
			)
		)
		(fp_text user "Author: Antmicro"
			(at -0.95 4.169 90)
			(layer "F.Fab")
			(effects
				(font
					(size 0.7 0.7)
					(thickness 0.15)
				)
				(justify left bottom)
			)
		)
		(fp_text user "${REFERENCE}"
			(at -0.95 3.168 90)
			(layer "F.Fab")
			(effects
				(font
					(size 0.7 0.7)
					(thickness 0.15)
				)
				(justify left bottom)
			)
		)
		(pad "1" smd roundrect
			(at -0.48 0 90)
			(size 0.59 0.64)
			(layers "F.Cu" "F.Mask" "F.Paste")
			(roundrect_rratio 0.25)
			(net 1282 "Net-(U60-IN+)")
			(pintype "passive")
		)
		(pad "2" smd roundrect
			(at 0.48 0 90)
			(size 0.59 0.64)
			(layers "F.Cu" "F.Mask" "F.Paste")
			(roundrect_rratio 0.25)
			(net 567 "/DCDC/3V3_OUT")
			(pintype "passive")
		)
	)
	(footprint "antmicro-footprints:Vishay_PowerPAK_1212-8_Single"
		(layer "F.Cu")
		(at 211.214 72.51 180)
		(descr "PowerPAK 1212-8 Single")
		(tags "Vishay PowerPAK 1212-8 Single")
		(property "Reference" "Q41"
			(at 2.914 1.91 90)
			(layer "F.SilkS")
			(effects
				(font
					(size 0.7 0.7)
					(thickness 0.15)
				)
				(justify right top)
			)
		)
		(property "Value" "SISS05DN-T1-GE3"
			(at 0 2.7 0)
			(layer "F.Fab")
			(effects
				(font
					(size 0.7 0.7)
					(thickness 0.15)
				)
				(justify right top)
			)
		)
		(property "Datasheet" "https://www.vishay.com/docs/77029/siss05dn.pdf"
			(at 0 0 0)
			(layer "F.Fab")
			(hide yes)
			(effects
				(font
					(size 1.27 1.27)
					(thickness 0.15)
				)
			)
		)
		(property "Description" "Power MOSFET, P Channel, 30 V, 108 A, 0.0035 ohm, PowerPAK 1212, Surface Mount"
			(at 0 0 0)
			(layer "F.Fab")
			(hide yes)
			(effects
				(font
					(size 1.27 1.27)
					(thickness 0.15)
				)
			)
		)
		(property "MPN" "SISS05DN-T1-GE3"
			(at 0 0 180)
			(unlocked yes)
			(layer "F.Fab")
			(hide yes)
			(effects
				(font
					(size 1 1)
					(thickness 0.15)
				)
			)
		)
		(property "Manufacturer" "Vishay"
			(at 0 0 180)
			(unlocked yes)
			(layer "F.Fab")
			(hide yes)
			(effects
				(font
					(size 1 1)
					(thickness 0.15)
				)
			)
		)
		(property "Author" "Antmicro"
			(at 0 0 180)
			(unlocked yes)
			(layer "F.Fab")
			(hide yes)
			(effects
				(font
					(size 1 1)
					(thickness 0.15)
				)
			)
		)
		(property "License" "Apache-2.0"
			(at 0 0 180)
			(unlocked yes)
			(layer "F.Fab")
			(hide yes)
			(effects
				(font
					(size 1 1)
					(thickness 0.15)
				)
			)
		)
		(sheetname "/Power/")
		(sheetfile "power.kicad_sch")
		(attr smd)
		(fp_line
			(start 1.648 -1.651)
			(end 1.648 -1.317)
			(stroke
				(width 0.15)
				(type solid)
			)
			(layer "F.SilkS")
		)
		(fp_line
			(start 1.634 1.3)
			(end 1.634 1.634)
			(stroke
				(width 0.15)
				(type solid)
			)
			(layer "F.SilkS")
		)
		(fp_line
			(start -1.635 1.634)
			(end 1.634 1.634)
			(stroke
				(width 0.15)
				(type solid)
			)
			(layer "F.SilkS")
		)
		(fp_line
			(start -1.635 1.3)
			(end -1.635 1.634)
			(stroke
				(width 0.15)
				(type solid)
			)
			(layer "F.SilkS")
		)
		(fp_line
			(start -1.651 -1.651)
			(end 1.648 -1.651)
			(stroke
				(width 0.15)
				(type solid)
			)
			(layer "F.SilkS")
		)
		(fp_line
			(start -1.651 -1.651)
			(end -1.651 -1.317)
			(stroke
				(width 0.15)
				(type solid)
			)
			(layer "F.SilkS")
		)
		(fp_circle
			(center -1.9 -1.4)
			(end -1.85 -1.4)
			(stroke
				(width 0.15)
				(type solid)
			)
			(fill yes)
			(layer "F.SilkS")
		)
		(fp_rect
			(start -2 -1.8)
			(end 2 1.798)
			(stroke
				(width 0.05)
				(type solid)
			)
			(fill no)
			(layer "F.CrtYd")
		)
		(fp_line
			(start -1.6425 -1.4175)
			(end -1.4175 -1.6425)
			(stroke
				(width 0.15)
				(type solid)
			)
			(layer "F.Fab")
		)
		(fp_rect
			(start -1.651 -1.651)
			(end 1.648 1.648)
			(stroke
				(width 0.15)
				(type solid)
			)
			(fill no)
			(layer "F.Fab")
		)
		(fp_text user "License: Apache-2.0"
			(at -8 7.1 0)
			(layer "F.Fab")
			(effects
				(font
					(size 0.7 0.7)
					(thickness 0.15)
				)
				(justify right top)
			)
		)
		(fp_text user "${REFERENCE}"
			(at -8 4.7 0)
			(layer "F.Fab")
			(effects
				(font
					(size 0.7 0.7)
					(thickness 0.15)
				)
				(justify right top)
			)
		)
		(fp_text user "Author: Antmicro"
			(at -8 5.9 0)
			(layer "F.Fab")
			(effects
				(font
					(size 0.7 0.7)
					(thickness 0.15)
				)
				(justify right top)
			)
		)
		(pad "1" smd rect
			(at -1.436 -0.99 180)
			(size 0.99 0.405)
			(layers "F.Cu" "F.Mask" "F.Paste")
			(net 1383 "VCC_NO_OVP")
			(pinfunction "S")
			(pintype "passive")
		)
		(pad "2" smd rect
			(at -1.436 -0.332 180)
			(size 0.99 0.405)
			(layers "F.Cu" "F.Mask" "F.Paste")
			(net 1383 "VCC_NO_OVP")
			(pinfunction "S")
			(pintype "passive")
		)
		(pad "3" smd rect
			(at -1.436 0.33 180)
			(size 0.99 0.405)
			(layers "F.Cu" "F.Mask" "F.Paste")
			(net 1383 "VCC_NO_OVP")
			(pinfunction "S")
			(pintype "passive")
		)
		(pad "4" smd rect
			(at -1.436 0.988 180)
			(size 0.99 0.405)
			(layers "F.Cu" "F.Mask" "F.Paste")
			(net 1385 "Net-(Q41-G)")
			(pinfunction "G")
			(pintype "input")
		)
		(pad "5" smd custom
			(at 0.557 0 180)
			(size 1.725 2.235)
			(layers "F.Cu" "F.Mask" "F.Paste")
			(net 13 "VCC")
			(pinfunction "D")
			(pintype "passive")
			(zone_connect 2)
			(options
				(clearance outline)
				(anchor rect)
			)
			(primitives
				(gr_poly
					(pts
						(xy 0.8625 0.1275) (xy 0.8625 -0.1275) (xy 1.3725 -0.1275) (xy 1.3725 -0.5325) (xy 0.8625 -0.5325)
						(xy 0.8625 -0.7875) (xy 1.3725 -0.7875) (xy 1.3725 -1.195) (xy 0.6125 -1.195) (xy 0.6125 1.195)
						(xy 1.3725 1.195) (xy 1.3725 0.7875) (xy 0.8625 0.7875) (xy 0.8625 0.5325) (xy 1.3725 0.5325)
						(xy 1.3725 0.1275)
					)
					(width 0)
					(fill yes)
				)
			)
		)
	)
	(footprint "antmicro-footprints:LED_0603_1608Metric_G"
		(layer "F.Cu")
		(at 222.13 73.444951 180)
		(descr "LED SMD 0603 Green")
		(tags "LED SMD 0603 Green")
		(property "Reference" "D20"
			(at 0.68 -2.955049 180)
			(layer "F.SilkS")
			(effects
				(font
					(size 0.7 0.7)
					(thickness 0.15)
				)
				(justify left bottom)
			)
		)
		(property "Value" "LED_G_0603_LTST-C190GKT"
			(at -0.001 1.599 180)
			(layer "F.Fab")
			(effects
				(font
					(size 0.7 0.7)
					(thickness 0.15)
				)
				(justify left bottom)
			)
		)
		(property "Datasheet" "https://media.digikey.com/pdf/Data%20Sheets/Lite-On%20PDFs/LTST-C190GKT.pdf"
			(at 0 0 180)
			(layer "F.Fab")
			(hide yes)
			(effects
				(font
					(size 1.27 1.27)
					(thickness 0.15)
				)
			)
		)
		(property "Description" "LED, Green, SMD, 0603, 20 mA, 2.1 V, 569 nm"
			(at 0 0 180)
			(layer "F.Fab")
			(hide yes)
			(effects
				(font
					(size 1.27 1.27)
					(thickness 0.15)
				)
			)
		)
		(property "MPN" "LTST-C190GKT"
			(at 0 0 180)
			(unlocked yes)
			(layer "F.Fab")
			(hide yes)
			(effects
				(font
					(size 1 1)
					(thickness 0.15)
				)
			)
		)
		(property "Manufacturer" "Lite-On"
			(at 0 0 180)
			(unlocked yes)
			(layer "F.Fab")
			(hide yes)
			(effects
				(font
					(size 1 1)
					(thickness 0.15)
				)
			)
		)
		(property "Author" "Antmicro"
			(at 0 0 180)
			(unlocked yes)
			(layer "F.Fab")
			(hide yes)
			(effects
				(font
					(size 1 1)
					(thickness 0.15)
				)
			)
		)
		(property "License" "Apache-2.0"
			(at 0 0 180)
			(unlocked yes)
			(layer "F.Fab")
			(hide yes)
			(effects
				(font
					(size 1 1)
					(thickness 0.15)
				)
			)
		)
		(property "Color" "Green"
			(at 0 0 180)
			(unlocked yes)
			(layer "F.Fab")
			(hide yes)
			(effects
				(font
					(size 1 1)
					(thickness 0.15)
				)
			)
		)
		(sheetname "/USB Debug, PD/")
		(sheetfile "usb_debug_pd.kicad_sch")
		(attr smd)
		(fp_line
			(start 0.22 0.35)
			(end -0.22 0.35)
			(stroke
				(width 0.15)
				(type solid)
			)
			(layer "F.SilkS")
		)
		(fp_line
			(start 0.22 -0.35)
			(end -0.22 -0.35)
			(stroke
				(width 0.15)
				(type solid)
			)
			(layer "F.SilkS")
		)
		(fp_line
			(start 0.105328 0.201008)
			(end 0.105328 -0.198992)
			(stroke
				(width 0.1)
				(type solid)
			)
			(layer "F.SilkS")
		)
		(fp_line
			(start 0.105328 0.201008)
			(end -0.094672 0.001008)
			(stroke
				(width 0.1)
				(type solid)
			)
			(layer "F.SilkS")
		)
		(fp_line
			(start 0.105328 0.001008)
			(end 0.24 0.001)
			(stroke
				(width 0.1)
				(type solid)
			)
			(layer "F.SilkS")
		)
		(fp_line
			(start -0.094672 0.201008)
			(end -0.094672 -0.198992)
			(stroke
				(width 0.1)
				(type solid)
			)
			(layer "F.SilkS")
		)
		(fp_line
			(start -0.094672 0.001008)
			(end 0.105328 -0.198992)
			(stroke
				(width 0.1)
				(type solid)
			)
			(layer "F.SilkS")
		)
		(fp_line
			(start -0.094672 0.001008)
			(end -0.24 0.001008)
			(stroke
				(width 0.1)
				(type solid)
			)
			(layer "F.SilkS")
		)
		(fp_line
			(start -1.18 -0.319)
			(end -1.18 0.321)
			(stroke
				(width 0.15)
				(type solid)
			)
			(layer "F.SilkS")
		)
		(fp_rect
			(start 1.25 0.65)
			(end -1.25 -0.65)
			(stroke
				(width 0.05)
				(type solid)
			)
			(fill no)
			(layer "F.CrtYd")
		)
		(fp_line
			(start 0.599 0)
			(end 0.201 0)
			(stroke
				(width 0.15)
				(type solid)
			)
			(layer "F.Fab")
		)
		(fp_line
			(start 0.201 0.2)
			(end 0.201 0)
			(stroke
				(width 0.15)
				(type solid)
			)
			(layer "F.Fab")
		)
		(fp_line
			(start 0.201 0)
			(end 0.201 -0.202)
			(stroke
				(width 0.15)
				(type solid)
			)
			(layer "F.Fab")
		)
		(fp_line
			(start 0.201 -0.202)
			(end -0.101 0)
			(stroke
				(width 0.15)
				(type solid)
			)
			(layer "F.Fab")
		)
		(fp_line
			(start -0.101 0)
			(end 0.201 0.2)
			(stroke
				(width 0.15)
				(type solid)
			)
			(layer "F.Fab")
		)
		(fp_line
			(start -0.199 0.2)
			(end -0.199 0.1)
			(stroke
				(width 0.15)
				(type solid)
			)
			(layer "F.Fab")
		)
		(fp_line
			(start -0.199 0)
			(end -0.597 0)
			(stroke
				(width 0.15)
				(type solid)
			)
			(layer "F.Fab")
		)
		(fp_line
			(start -0.199 -0.202)
			(end -0.199 0.1)
			(stroke
				(width 0.15)
				(type solid)
			)
			(layer "F.Fab")
		)
		(fp_rect
			(start 0.848 0.4)
			(end -0.85 -0.402)
			(stroke
				(width 0.15)
				(type solid)
			)
			(fill no)
			(layer "F.Fab")
		)
		(fp_text user "${REFERENCE}"
			(at -1.4224 5.999 180)
			(layer "F.Fab")
			(effects
				(font
					(size 0.7 0.7)
					(thickness 0.15)
				)
				(justify left bottom)
			)
		)
		(fp_text user "License: Apache-2.0"
			(at -1.4224 3.599 180)
			(layer "F.Fab")
			(effects
				(font
					(size 0.7 0.7)
					(thickness 0.15)
				)
				(justify left bottom)
			)
		)
		(fp_text user "Author: Antmicro"
			(at -1.4224 4.799 180)
			(layer "F.Fab")
			(effects
				(font
					(size 0.7 0.7)
					(thickness 0.15)
				)
				(justify left bottom)
			)
		)
		(pad "1" smd roundrect
			(at -0.7 0)
			(size 0.8 1)
			(layers "F.Cu" "F.Mask" "F.Paste")
			(roundrect_rratio 0.2)
			(net 536 "/USB Debug, PD/FTDI_LED_TX")
			(pinfunction "C")
			(pintype "passive")
		)
		(pad "2" smd roundrect
			(at 0.7 0)
			(size 0.8 1)
			(layers "F.Cu" "F.Mask" "F.Paste")
			(roundrect_rratio 0.2)
			(net 535 "Net-(D20-A)")
			(pinfunction "A")
			(pintype "passive")
		)
	)
	(footprint "antmicro-footprints:SOT-523"
		(layer "F.Cu")
		(at 160.3 62.8 90)
		(property "Reference" "Q36"
			(at -2.1 -1.3 180)
			(layer "F.SilkS")
			(effects
				(font
					(size 0.7 0.7)
					(thickness 0.15)
				)
				(justify left bottom)
			)
		)
		(property "Value" "DMG1012T-7"
			(at 0.1 1.824 90)
			(layer "F.Fab")
			(effects
				(font
					(size 0.7 0.7)
					(thickness 0.15)
				)
				(justify left bottom)
			)
		)
		(property "Datasheet" "https://www.diodes.com/assets/Datasheets/ds31783.pdf"
			(at 0 0 90)
			(layer "F.Fab")
			(hide yes)
			(effects
				(font
					(size 1.27 1.27)
					(thickness 0.15)
				)
			)
		)
		(property "Description" "Power MOSFET, N Channel, 20 V, 630 mA, 0.3 ohm, SOT-523, Surface Mount"
			(at 0 0 90)
			(layer "F.Fab")
			(hide yes)
			(effects
				(font
					(size 1.27 1.27)
					(thickness 0.15)
				)
			)
		)
		(property "MPN" "DMG1012T-7"
			(at 0 0 90)
			(unlocked yes)
			(layer "F.Fab")
			(hide yes)
			(effects
				(font
					(size 1 1)
					(thickness 0.15)
				)
			)
		)
		(property "Manufacturer" "Diodes Incorporated"
			(at 0 0 90)
			(unlocked yes)
			(layer "F.Fab")
			(hide yes)
			(effects
				(font
					(size 1 1)
					(thickness 0.15)
				)
			)
		)
		(property "Author" "Antmicro"
			(at 0 0 90)
			(unlocked yes)
			(layer "F.Fab")
			(hide yes)
			(effects
				(font
					(size 1 1)
					(thickness 0.15)
				)
			)
		)
		(property "License" "Apache-2.0"
			(at 0 0 90)
			(unlocked yes)
			(layer "F.Fab")
			(hide yes)
			(effects
				(font
					(size 1 1)
					(thickness 0.15)
				)
			)
		)
		(sheetname "/SoM_IO2/")
		(sheetfile "som_io2.kicad_sch")
		(attr smd exclude_from_pos_files exclude_from_bom dnp)
		(fp_line
			(start -0.277 -0.551)
			(end -0.277 -0.750001)
			(stroke
				(width 0.15)
				(type solid)
			)
			(layer "F.SilkS")
		)
		(fp_line
			(start -0.725 -0.551)
			(end -0.277 -0.551)
			(stroke
				(width 0.15)
				(type solid)
			)
			(layer "F.SilkS")
		)
		(fp_line
			(start -0.927 -0.350999)
			(end -0.725 -0.551)
			(stroke
				(width 0.15)
				(type solid)
			)
			(layer "F.SilkS")
		)
		(fp_line
			(start -0.927 -0.050999)
			(end -0.927 -0.350999)
			(stroke
				(width 0.15)
				(type solid)
			)
			(layer "F.SilkS")
		)
		(fp_circle
			(center -0.9652 0.9652)
			(end -0.915201 0.9652)
			(stroke
				(width 0.15)
				(type solid)
			)
			(fill yes)
			(layer "F.SilkS")
		)
		(fp_line
			(start 1.1 -1.159999)
			(end 1.1 1.15)
			(stroke
				(width 0.05)
				(type solid)
			)
			(layer "F.CrtYd")
		)
		(fp_line
			(start -1.12 -1.159999)
			(end 1.1 -1.159999)
			(stroke
				(width 0.05)
				(type solid)
			)
			(layer "F.CrtYd")
		)
		(fp_line
			(start -1.12 -1.159999)
			(end -1.12 1.15)
			(stroke
				(width 0.05)
				(type solid)
			)
			(layer "F.CrtYd")
		)
		(fp_line
			(start -1.12 1.15)
			(end 1.1 1.15)
			(stroke
				(width 0.05)
				(type solid)
			)
			(layer "F.CrtYd")
		)
		(fp_line
			(start 0.8 -0.425)
			(end -0.652 -0.425)
			(stroke
				(width 0.15)
				(type solid)
			)
			(layer "F.Fab")
		)
		(fp_line
			(start 0.8 -0.425)
			(end 0.8 0.424)
			(stroke
				(width 0.15)
				(type solid)
			)
			(layer "F.Fab")
		)
		(fp_line
			(start -0.652 -0.425)
			(end -0.802 -0.276)
			(stroke
				(width 0.15)
				(type solid)
			)
			(layer "F.Fab")
		)
		(fp_line
			(start -0.802 -0.276)
			(end -0.802 0.424)
			(stroke
				(width 0.15)
				(type solid)
			)
			(layer "F.Fab")
		)
		(fp_line
			(start 0.8 0.424)
			(end -0.802 0.424)
			(stroke
				(width 0.15)
				(type solid)
			)
			(layer "F.Fab")
		)
		(fp_circle
			(center -0.9652 0.9652)
			(end -0.9144 0.9652)
			(stroke
				(width 0.15)
				(type solid)
			)
			(fill no)
			(layer "F.Fab")
		)
		(fp_text user "${REFERENCE}"
			(at -1.12 3.824 90)
			(layer "F.Fab")
			(effects
				(font
					(size 0.7 0.7)
					(thickness 0.15)
				)
				(justify left bottom)
			)
		)
		(fp_text user "License: Apache-2.0"
			(at -1.12 5.024 90)
			(layer "F.Fab")
			(effects
				(font
					(size 0.7 0.7)
					(thickness 0.15)
				)
				(justify left bottom)
			)
		)
		(fp_text user "Author: Antmicro"
			(at -1.12 6.224 90)
			(layer "F.Fab")
			(effects
				(font
					(size 0.7 0.7)
					(thickness 0.15)
				)
				(justify left bottom)
			)
		)
		(pad "1" smd rect
			(at -0.5 0.65 90)
			(size 0.4 0.51)
			(layers "F.Cu" "F.Mask" "F.Paste")
			(net 870 "/SoM_IO2/TC_JTAG_TRST_N")
			(pinfunction "G")
			(pintype "input")
		)
		(pad "2" smd rect
			(at 0.498 0.65 90)
			(size 0.4 0.51)
			(layers "F.Cu" "F.Mask" "F.Paste")
			(net 1 "GND")
			(pinfunction "S")
			(pintype "passive")
		)
		(pad "3" smd rect
			(at 0 -0.652001 90)
			(size 0.4 0.51)
			(layers "F.Cu" "F.Mask" "F.Paste")
			(net 1299 "Net-(Q28-G)")
			(pinfunction "D")
			(pintype "passive")
		)
	)
	(footprint "antmicro-footprints:R_0402_1005Metric"
		(layer "F.Cu")
		(at 132.465349 61.976557)
		(descr "Resistor SMD 0402")
		(tags "resistor SMD 0402")
		(property "Reference" "R309"
			(at 0.844651 1.333443 0)
			(layer "F.SilkS")
			(effects
				(font
					(size 0.7 0.7)
					(thickness 0.15)
				)
				(justify left bottom)
			)
		)
		(property "Value" "R_499k_0402"
			(at -1.011843 1.772046 0)
			(layer "F.Fab")
			(effects
				(font
					(size 0.7 0.7)
					(thickness 0.15)
				)
				(justify left bottom)
			)
		)
		(property "Datasheet" "https://www.mouser.com/datasheet/2/54/cr-1858361.pdf"
			(at 0 0 0)
			(layer "F.Fab")
			(hide yes)
			(effects
				(font
					(size 1.27 1.27)
					(thickness 0.15)
				)
			)
		)
		(property "Description" "SMD Chip Resistor, 499 kohm, ± 1%, 63 mW, 0402 [1005 Metric], Thick Film, General Purpose"
			(at 0 0 0)
			(layer "F.Fab")
			(hide yes)
			(effects
				(font
					(size 1.27 1.27)
					(thickness 0.15)
				)
			)
		)
		(property "MPN" "CR0402-FX-4993GLF"
			(at 0 0 0)
			(unlocked yes)
			(layer "F.Fab")
			(hide yes)
			(effects
				(font
					(size 1 1)
					(thickness 0.15)
				)
			)
		)
		(property "Manufacturer" "Bourns"
			(at 0 0 0)
			(unlocked yes)
			(layer "F.Fab")
			(hide yes)
			(effects
				(font
					(size 1 1)
					(thickness 0.15)
				)
			)
		)
		(property "License" "Apache-2.0"
			(at 0 0 0)
			(unlocked yes)
			(layer "F.Fab")
			(hide yes)
			(effects
				(font
					(size 1 1)
					(thickness 0.15)
				)
			)
		)
		(property "Author" "Antmicro"
			(at 0 0 0)
			(unlocked yes)
			(layer "F.Fab")
			(hide yes)
			(effects
				(font
					(size 1 1)
					(thickness 0.15)
				)
			)
		)
		(property "Val" "499k"
			(at 0 0 0)
			(unlocked yes)
			(layer "F.Fab")
			(hide yes)
			(effects
				(font
					(size 1 1)
					(thickness 0.15)
				)
			)
		)
		(property "Tolerance" "1%"
			(at 0 0 0)
			(unlocked yes)
			(layer "F.Fab")
			(hide yes)
			(effects
				(font
					(size 1 1)
					(thickness 0.15)
				)
			)
		)
		(sheetname "/DCDC/")
		(sheetfile "dcdc.kicad_sch")
		(attr smd exclude_from_pos_files exclude_from_bom dnp)
		(fp_poly
			(pts
				(xy -0.925 -0.47) (xy -0.925 0.47) (xy 0.925 0.47) (xy 0.925 -0.47)
			)
			(stroke
				(width 0.05)
				(type default)
			)
			(fill no)
			(layer "F.CrtYd")
		)
		(fp_poly
			(pts
				(xy -0.5 -0.25) (xy -0.5 0.25) (xy 0.5 0.25) (xy 0.5 -0.25)
			)
			(stroke
				(width 0.15)
				(type solid)
			)
			(fill no)
			(layer "F.Fab")
		)
		(fp_text user "${REFERENCE}"
			(at -0.95 3.168 0)
			(layer "F.Fab")
			(effects
				(font
					(size 0.7 0.7)
					(thickness 0.15)
				)
				(justify left bottom)
			)
		)
		(fp_text user "Author: Antmicro"
			(at -0.95 4.169 0)
			(layer "F.Fab")
			(effects
				(font
					(size 0.7 0.7)
					(thickness 0.15)
				)
				(justify left bottom)
			)
		)
		(fp_text user "License: Apache-2.0"
			(at -0.949999 5.169 0)
			(layer "F.Fab")
			(effects
				(font
					(size 0.7 0.7)
					(thickness 0.15)
				)
				(justify left bottom)
			)
		)
		(pad "1" smd roundrect
			(at -0.48 0)
			(size 0.59 0.64)
			(layers "F.Cu" "F.Mask" "F.Paste")
			(roundrect_rratio 0.25)
			(net 1306 "/DCDC/5V_{AON}_MODE1")
			(pintype "passive")
		)
		(pad "2" smd roundrect
			(at 0.48 0)
			(size 0.59 0.64)
			(layers "F.Cu" "F.Mask" "F.Paste")
			(roundrect_rratio 0.25)
			(net 1274 "/DCDC/5V_{AON}_VDD")
			(pintype "passive")
		)
	)
	(footprint "antmicro-footprints:TP_SMD_0.75mm"
		(layer "F.Cu")
		(at 64.91 58.24 90)
		(property "Reference" "TP28"
			(at 1.54 -2.26 90)
			(layer "F.SilkS")
			(effects
				(font
					(size 0.7 0.7)
					(thickness 0.15)
				)
				(justify left bottom)
			)
		)
		(property "Value" "TP_0.75mm_SMD"
			(at 0 1.2 90)
			(layer "F.Fab")
			(effects
				(font
					(size 0.7 0.7)
					(thickness 0.15)
				)
				(justify left bottom)
			)
		)
		(property "Description" "SMT test point"
			(at 0 0 90)
			(layer "F.Fab")
			(hide yes)
			(effects
				(font
					(size 1.27 1.27)
					(thickness 0.15)
				)
			)
		)
		(property "MPN" ""
			(at 0 0 90)
			(unlocked yes)
			(layer "F.Fab")
			(hide yes)
			(effects
				(font
					(size 1 1)
					(thickness 0.15)
				)
			)
		)
		(property "Manufacturer" ""
			(at 0 0 90)
			(unlocked yes)
			(layer "F.Fab")
			(hide yes)
			(effects
				(font
					(size 1 1)
					(thickness 0.15)
				)
			)
		)
		(property "Author" "Antmicro"
			(at 0 0 90)
			(unlocked yes)
			(layer "F.Fab")
			(hide yes)
			(effects
				(font
					(size 1 1)
					(thickness 0.15)
				)
			)
		)
		(property "License" "Apache-2.0"
			(at 0 0 90)
			(unlocked yes)
			(layer "F.Fab")
			(hide yes)
			(effects
				(font
					(size 1 1)
					(thickness 0.15)
				)
			)
		)
		(sheetname "/CSI/")
		(sheetfile "csi.kicad_sch")
		(attr exclude_from_pos_files exclude_from_bom)
		(fp_circle
			(center 0 0)
			(end 0.475 0)
			(stroke
				(width 0.05)
				(type default)
			)
			(fill no)
			(layer "F.CrtYd")
		)
		(fp_text user "Author: Antmicro"
			(at -0.4 3.901 90)
			(layer "F.Fab")
			(effects
				(font
					(size 0.7 0.7)
					(thickness 0.15)
				)
				(justify left bottom)
			)
		)
		(fp_text user "${REFERENCE}"
			(at -0.4 2.7 90)
			(layer "F.Fab")
			(effects
				(font
					(size 0.7 0.7)
					(thickness 0.15)
				)
				(justify left bottom)
			)
		)
		(fp_text user "License: Apache-2.0"
			(at -0.4 5.101 90)
			(layer "F.Fab")
			(effects
				(font
					(size 0.7 0.7)
					(thickness 0.15)
				)
				(justify left bottom)
			)
		)
		(pad "1" smd circle
			(at 0 0 90)
			(size 0.75 0.75)
			(layers "F.Cu" "F.Mask")
			(net 1052 "/CSI/MUX_I2C_7_SCL")
			(pinfunction "1")
			(pintype "passive")
		)
	)
	(footprint "antmicro-footprints:C_0402_1005Metric"
		(layer "F.Cu")
		(at 193.8 82.4)
		(descr "Capacitor SMD 0402")
		(tags "capacitor SMD 0402")
		(property "Reference" "C122"
			(at -1.5 -0.6 0)
			(layer "F.SilkS")
			(effects
				(font
					(size 0.7 0.7)
					(thickness 0.15)
				)
				(justify left bottom)
			)
		)
		(property "Value" "C_100n_0402"
			(at -1.022927 2.155213 0)
			(layer "F.Fab")
			(effects
				(font
					(size 0.7 0.7)
					(thickness 0.15)
				)
				(justify left bottom)
			)
		)
		(property "Datasheet" "https://www.murata.com/products/productdetail?partno=GRM155R61H104KE14%23"
			(at 0 0 0)
			(layer "F.Fab")
			(hide yes)
			(effects
				(font
					(size 1.27 1.27)
					(thickness 0.15)
				)
			)
		)
		(property "Description" "SMD Multilayer Ceramic Capacitor, 0.1 µF, 50 V, 0402 [1005 Metric], ± 10%, X5R, GRM Series"
			(at 0 0 0)
			(layer "F.Fab")
			(hide yes)
			(effects
				(font
					(size 1.27 1.27)
					(thickness 0.15)
				)
			)
		)
		(property "Manufacturer" "Murata"
			(at 0 0 0)
			(unlocked yes)
			(layer "F.Fab")
			(hide yes)
			(effects
				(font
					(size 1 1)
					(thickness 0.15)
				)
			)
		)
		(property "MPN" "GRM155R61H104KE14D"
			(at 0 0 0)
			(unlocked yes)
			(layer "F.Fab")
			(hide yes)
			(effects
				(font
					(size 1 1)
					(thickness 0.15)
				)
			)
		)
		(property "Val" "100n"
			(at 0 0 0)
			(unlocked yes)
			(layer "F.Fab")
			(hide yes)
			(effects
				(font
					(size 1 1)
					(thickness 0.15)
				)
			)
		)
		(property "License" "Apache-2.0"
			(at 0 0 0)
			(unlocked yes)
			(layer "F.Fab")
			(hide yes)
			(effects
				(font
					(size 1 1)
					(thickness 0.15)
				)
			)
		)
		(property "Author" "Antmicro"
			(at 0 0 0)
			(unlocked yes)
			(layer "F.Fab")
			(hide yes)
			(effects
				(font
					(size 1 1)
					(thickness 0.15)
				)
			)
		)
		(property "Voltage" "50V"
			(at 0 0 0)
			(unlocked yes)
			(layer "F.Fab")
			(hide yes)
			(effects
				(font
					(size 1 1)
					(thickness 0.15)
				)
			)
		)
		(property "Dielectric" "X5R"
			(at 0 0 0)
			(unlocked yes)
			(layer "F.Fab")
			(hide yes)
			(effects
				(font
					(size 1 1)
					(thickness 0.15)
				)
			)
		)
		(sheetname "/USB Debug, PD/")
		(sheetfile "usb_debug_pd.kicad_sch")
		(attr smd)
		(fp_poly
			(pts
				(xy -0.925 -0.47) (xy -0.925 0.47) (xy 0.925 0.47) (xy 0.925 -0.47)
			)
			(stroke
				(width 0.05)
				(type default)
			)
			(fill no)
			(layer "F.CrtYd")
		)
		(fp_line
			(start -0.494 -0.25)
			(end 0.504 -0.25)
			(stroke
				(width 0.15)
				(type solid)
			)
			(layer "F.Fab")
		)
		(fp_line
			(start -0.494 0.248)
			(end -0.494 -0.25)
			(stroke
				(width 0.15)
				(type solid)
			)
			(layer "F.Fab")
		)
		(fp_line
			(start 0.504 -0.25)
			(end 0.504 0.248)
			(stroke
				(width 0.15)
				(type solid)
			)
			(layer "F.Fab")
		)
		(fp_line
			(start 0.504 0.248)
			(end -0.494 0.248)
			(stroke
				(width 0.15)
				(type solid)
			)
			(layer "F.Fab")
		)
		(fp_text user "${REFERENCE}"
			(at -0.939 4.599 0)
			(layer "F.Fab")
			(effects
				(font
					(size 0.7 0.7)
					(thickness 0.15)
				)
				(justify left bottom)
			)
		)
		(fp_text user "Author: Antmicro"
			(at -0.939 3.399 0)
			(layer "F.Fab")
			(effects
				(font
					(size 0.7 0.7)
					(thickness 0.15)
				)
				(justify left bottom)
			)
		)
		(fp_text user "License: Apache-2.0"
			(at -0.939 5.799 0)
			(layer "F.Fab")
			(effects
				(font
					(size 0.7 0.7)
					(thickness 0.15)
				)
				(justify left bottom)
			)
		)
		(pad "1" smd roundrect
			(at -0.48 0)
			(size 0.59 0.64)
			(layers "F.Cu" "F.Mask" "F.Paste")
			(roundrect_rratio 0.25)
			(net 1 "GND")
			(pintype "passive")
		)
		(pad "2" smd roundrect
			(at 0.48 0)
			(size 0.59 0.64)
			(layers "F.Cu" "F.Mask" "F.Paste")
			(roundrect_rratio 0.25)
			(net 271 "FLASH_PWR")
			(pintype "passive")
		)
	)
	(footprint "antmicro-footprints:LED_0603_1608Metric_G"
		(layer "F.Cu")
		(at 222.13 74.869951 180)
		(descr "LED SMD 0603 Green")
		(tags "LED SMD 0603 Green")
		(property "Reference" "D21"
			(at 0.69 -2.520049 180)
			(layer "F.SilkS")
			(effects
				(font
					(size 0.7 0.7)
					(thickness 0.15)
				)
				(justify left bottom)
			)
		)
		(property "Value" "LED_G_0603_LTST-C190GKT"
			(at -0.001 1.599 180)
			(layer "F.Fab")
			(effects
				(font
					(size 0.7 0.7)
					(thickness 0.15)
				)
				(justify left bottom)
			)
		)
		(property "Datasheet" "https://media.digikey.com/pdf/Data%20Sheets/Lite-On%20PDFs/LTST-C190GKT.pdf"
			(at 0 0 180)
			(layer "F.Fab")
			(hide yes)
			(effects
				(font
					(size 1.27 1.27)
					(thickness 0.15)
				)
			)
		)
		(property "Description" "LED, Green, SMD, 0603, 20 mA, 2.1 V, 569 nm"
			(at 0 0 180)
			(layer "F.Fab")
			(hide yes)
			(effects
				(font
					(size 1.27 1.27)
					(thickness 0.15)
				)
			)
		)
		(property "MPN" "LTST-C190GKT"
			(at 0 0 180)
			(unlocked yes)
			(layer "F.Fab")
			(hide yes)
			(effects
				(font
					(size 1 1)
					(thickness 0.15)
				)
			)
		)
		(property "Manufacturer" "Lite-On"
			(at 0 0 180)
			(unlocked yes)
			(layer "F.Fab")
			(hide yes)
			(effects
				(font
					(size 1 1)
					(thickness 0.15)
				)
			)
		)
		(property "Author" "Antmicro"
			(at 0 0 180)
			(unlocked yes)
			(layer "F.Fab")
			(hide yes)
			(effects
				(font
					(size 1 1)
					(thickness 0.15)
				)
			)
		)
		(property "License" "Apache-2.0"
			(at 0 0 180)
			(unlocked yes)
			(layer "F.Fab")
			(hide yes)
			(effects
				(font
					(size 1 1)
					(thickness 0.15)
				)
			)
		)
		(property "Color" "Green"
			(at 0 0 180)
			(unlocked yes)
			(layer "F.Fab")
			(hide yes)
			(effects
				(font
					(size 1 1)
					(thickness 0.15)
				)
			)
		)
		(sheetname "/USB Debug, PD/")
		(sheetfile "usb_debug_pd.kicad_sch")
		(attr smd)
		(fp_line
			(start 0.22 0.35)
			(end -0.22 0.35)
			(stroke
				(width 0.15)
				(type solid)
			)
			(layer "F.SilkS")
		)
		(fp_line
			(start 0.22 -0.35)
			(end -0.22 -0.35)
			(stroke
				(width 0.15)
				(type solid)
			)
			(layer "F.SilkS")
		)
		(fp_line
			(start 0.105328 0.201008)
			(end 0.105328 -0.198992)
			(stroke
				(width 0.1)
				(type solid)
			)
			(layer "F.SilkS")
		)
		(fp_line
			(start 0.105328 0.201008)
			(end -0.094672 0.001008)
			(stroke
				(width 0.1)
				(type solid)
			)
			(layer "F.SilkS")
		)
		(fp_line
			(start 0.105328 0.001008)
			(end 0.24 0.001)
			(stroke
				(width 0.1)
				(type solid)
			)
			(layer "F.SilkS")
		)
		(fp_line
			(start -0.094672 0.201008)
			(end -0.094672 -0.198992)
			(stroke
				(width 0.1)
				(type solid)
			)
			(layer "F.SilkS")
		)
		(fp_line
			(start -0.094672 0.001008)
			(end 0.105328 -0.198992)
			(stroke
				(width 0.1)
				(type solid)
			)
			(layer "F.SilkS")
		)
		(fp_line
			(start -0.094672 0.001008)
			(end -0.24 0.001008)
			(stroke
				(width 0.1)
				(type solid)
			)
			(layer "F.SilkS")
		)
		(fp_line
			(start -1.18 -0.319)
			(end -1.18 0.321)
			(stroke
				(width 0.15)
				(type solid)
			)
			(layer "F.SilkS")
		)
		(fp_rect
			(start 1.25 0.65)
			(end -1.25 -0.65)
			(stroke
				(width 0.05)
				(type solid)
			)
			(fill no)
			(layer "F.CrtYd")
		)
		(fp_line
			(start 0.599 0)
			(end 0.201 0)
			(stroke
				(width 0.15)
				(type solid)
			)
			(layer "F.Fab")
		)
		(fp_line
			(start 0.201 0.2)
			(end 0.201 0)
			(stroke
				(width 0.15)
				(type solid)
			)
			(layer "F.Fab")
		)
		(fp_line
			(start 0.201 0)
			(end 0.201 -0.202)
			(stroke
				(width 0.15)
				(type solid)
			)
			(layer "F.Fab")
		)
		(fp_line
			(start 0.201 -0.202)
			(end -0.101 0)
			(stroke
				(width 0.15)
				(type solid)
			)
			(layer "F.Fab")
		)
		(fp_line
			(start -0.101 0)
			(end 0.201 0.2)
			(stroke
				(width 0.15)
				(type solid)
			)
			(layer "F.Fab")
		)
		(fp_line
			(start -0.199 0.2)
			(end -0.199 0.1)
			(stroke
				(width 0.15)
				(type solid)
			)
			(layer "F.Fab")
		)
		(fp_line
			(start -0.199 0)
			(end -0.597 0)
			(stroke
				(width 0.15)
				(type solid)
			)
			(layer "F.Fab")
		)
		(fp_line
			(start -0.199 -0.202)
			(end -0.199 0.1)
			(stroke
				(width 0.15)
				(type solid)
			)
			(layer "F.Fab")
		)
		(fp_rect
			(start 0.848 0.4)
			(end -0.85 -0.402)
			(stroke
				(width 0.15)
				(type solid)
			)
			(fill no)
			(layer "F.Fab")
		)
		(fp_text user "${REFERENCE}"
			(at -1.4224 5.999 180)
			(layer "F.Fab")
			(effects
				(font
					(size 0.7 0.7)
					(thickness 0.15)
				)
				(justify left bottom)
			)
		)
		(fp_text user "Author: Antmicro"
			(at -1.4224 4.799 180)
			(layer "F.Fab")
			(effects
				(font
					(size 0.7 0.7)
					(thickness 0.15)
				)
				(justify left bottom)
			)
		)
		(fp_text user "License: Apache-2.0"
			(at -1.4224 3.599 180)
			(layer "F.Fab")
			(effects
				(font
					(size 0.7 0.7)
					(thickness 0.15)
				)
				(justify left bottom)
			)
		)
		(pad "1" smd roundrect
			(at -0.7 0)
			(size 0.8 1)
			(layers "F.Cu" "F.Mask" "F.Paste")
			(roundrect_rratio 0.2)
			(net 537 "/USB Debug, PD/FTDI_LED_RX")
			(pinfunction "C")
			(pintype "passive")
		)
		(pad "2" smd roundrect
			(at 0.7 0)
			(size 0.8 1)
			(layers "F.Cu" "F.Mask" "F.Paste")
			(roundrect_rratio 0.2)
			(net 538 "Net-(D21-A)")
			(pinfunction "A")
			(pintype "passive")
		)
	)
	(footprint "antmicro-footprints:C_0402_1005Metric"
		(layer "F.Cu")
		(at 208.86 134.8 90)
		(descr "Capacitor SMD 0402")
		(tags "capacitor SMD 0402")
		(property "Reference" "C256"
			(at -1.6 13.92 90)
			(layer "F.SilkS")
			(effects
				(font
					(size 0.7 0.7)
					(thickness 0.15)
				)
				(justify left bottom)
			)
		)
		(property "Value" "C_100n_0402"
			(at -1.022927 2.155213 90)
			(layer "F.Fab")
			(effects
				(font
					(size 0.7 0.7)
					(thickness 0.15)
				)
				(justify left bottom)
			)
		)
		(property "Datasheet" "https://www.murata.com/products/productdetail?partno=GRM155R61H104KE14%23"
			(at 0 0 90)
			(layer "F.Fab")
			(hide yes)
			(effects
				(font
					(size 1.27 1.27)
					(thickness 0.15)
				)
			)
		)
		(property "Description" "SMD Multilayer Ceramic Capacitor, 0.1 µF, 50 V, 0402 [1005 Metric], ± 10%, X5R, GRM Series"
			(at 0 0 90)
			(layer "F.Fab")
			(hide yes)
			(effects
				(font
					(size 1.27 1.27)
					(thickness 0.15)
				)
			)
		)
		(property "Manufacturer" "Murata"
			(at 0 0 90)
			(unlocked yes)
			(layer "F.Fab")
			(hide yes)
			(effects
				(font
					(size 1 1)
					(thickness 0.15)
				)
			)
		)
		(property "MPN" "GRM155R61H104KE14D"
			(at 0 0 90)
			(unlocked yes)
			(layer "F.Fab")
			(hide yes)
			(effects
				(font
					(size 1 1)
					(thickness 0.15)
				)
			)
		)
		(property "Val" "100n"
			(at 0 0 90)
			(unlocked yes)
			(layer "F.Fab")
			(hide yes)
			(effects
				(font
					(size 1 1)
					(thickness 0.15)
				)
			)
		)
		(property "License" "Apache-2.0"
			(at 0 0 90)
			(unlocked yes)
			(layer "F.Fab")
			(hide yes)
			(effects
				(font
					(size 1 1)
					(thickness 0.15)
				)
			)
		)
		(property "Author" "Antmicro"
			(at 0 0 90)
			(unlocked yes)
			(layer "F.Fab")
			(hide yes)
			(effects
				(font
					(size 1 1)
					(thickness 0.15)
				)
			)
		)
		(property "Voltage" "50V"
			(at 0 0 90)
			(unlocked yes)
			(layer "F.Fab")
			(hide yes)
			(effects
				(font
					(size 1 1)
					(thickness 0.15)
				)
			)
		)
		(property "Dielectric" "X5R"
			(at 0 0 90)
			(unlocked yes)
			(layer "F.Fab")
			(hide yes)
			(effects
				(font
					(size 1 1)
					(thickness 0.15)
				)
			)
		)
		(sheetname "/USB Hub/")
		(sheetfile "usb_hub.kicad_sch")
		(attr smd)
		(fp_rect
			(start -0.925 -0.47)
			(end 0.925 0.47)
			(stroke
				(width 0.05)
				(type default)
			)
			(fill no)
			(layer "F.CrtYd")
		)
		(fp_line
			(start 0.504 -0.25)
			(end 0.504 0.248)
			(stroke
				(width 0.15)
				(type solid)
			)
			(layer "F.Fab")
		)
		(fp_line
			(start -0.494 -0.25)
			(end 0.504 -0.25)
			(stroke
				(width 0.15)
				(type solid)
			)
			(layer "F.Fab")
		)
		(fp_line
			(start 0.504 0.248)
			(end -0.494 0.248)
			(stroke
				(width 0.15)
				(type solid)
			)
			(layer "F.Fab")
		)
		(fp_line
			(start -0.494 0.248)
			(end -0.494 -0.25)
			(stroke
				(width 0.15)
				(type solid)
			)
			(layer "F.Fab")
		)
		(fp_text user "${REFERENCE}"
			(at -0.939 4.599 90)
			(layer "F.Fab")
			(effects
				(font
					(size 0.7 0.7)
					(thickness 0.15)
				)
				(justify left bottom)
			)
		)
		(fp_text user "License: Apache-2.0"
			(at -0.939 5.799 90)
			(layer "F.Fab")
			(effects
				(font
					(size 0.7 0.7)
					(thickness 0.15)
				)
				(justify left bottom)
			)
		)
		(fp_text user "Author: Antmicro"
			(at -0.939 3.399 90)
			(layer "F.Fab")
			(effects
				(font
					(size 0.7 0.7)
					(thickness 0.15)
				)
				(justify left bottom)
			)
		)
		(pad "1" smd roundrect
			(at -0.48 0 90)
			(size 0.59 0.64)
			(layers "F.Cu" "F.Mask" "F.Paste")
			(roundrect_rratio 0.25)
			(net 662 "/SoM_IO2/USBSS2.TX-")
			(pintype "passive")
		)
		(pad "2" smd roundrect
			(at 0.48 0 90)
			(size 0.59 0.64)
			(layers "F.Cu" "F.Mask" "F.Paste")
			(roundrect_rratio 0.25)
			(net 1135 "/USB Hub/USBSS_RX_N")
			(pintype "passive")
		)
	)
	(footprint "antmicro-footprints:C_0805_2012Metric"
		(layer "F.Cu")
		(at 171.38 79.81 90)
		(descr "Capacitor SMD 0805")
		(tags "capacitor SMD 0805")
		(property "Reference" "C292"
			(at -4.67 0.23 90)
			(layer "F.SilkS")
			(effects
				(font
					(size 0.7 0.7)
					(thickness 0.15)
				)
				(justify left bottom)
			)
		)
		(property "Value" "C_22u_25V_0805"
			(at -2.055717 1.963152 90)
			(layer "F.Fab")
			(effects
				(font
					(size 0.7 0.7)
					(thickness 0.15)
				)
				(justify left bottom)
			)
		)
		(property "Datasheet" "https://product.samsungsem.com/mlcc/CL21A226MAYNNN.do"
			(at 0 0 90)
			(layer "F.Fab")
			(hide yes)
			(effects
				(font
					(size 1.27 1.27)
					(thickness 0.15)
				)
			)
		)
		(property "Description" "SMT Multilayer Ceramic Capacitor, 22uF, +/-20%, 25V, X5R, 0805 [2012 Metric]"
			(at 0 0 90)
			(layer "F.Fab")
			(hide yes)
			(effects
				(font
					(size 1.27 1.27)
					(thickness 0.15)
				)
			)
		)
		(property "MPN" "CL21A226MAYNNNE"
			(at 0 0 90)
			(unlocked yes)
			(layer "F.Fab")
			(hide yes)
			(effects
				(font
					(size 1 1)
					(thickness 0.15)
				)
			)
		)
		(property "Manufacturer" "Samsung Electro-Mechanics"
			(at 0 0 90)
			(unlocked yes)
			(layer "F.Fab")
			(hide yes)
			(effects
				(font
					(size 1 1)
					(thickness 0.15)
				)
			)
		)
		(property "License" "Apache-2.0"
			(at 0 0 90)
			(unlocked yes)
			(layer "F.Fab")
			(hide yes)
			(effects
				(font
					(size 1 1)
					(thickness 0.15)
				)
			)
		)
		(property "Author" "Antmicro"
			(at 0 0 90)
			(unlocked yes)
			(layer "F.Fab")
			(hide yes)
			(effects
				(font
					(size 1 1)
					(thickness 0.15)
				)
			)
		)
		(property "Val" "22u"
			(at 0 0 90)
			(unlocked yes)
			(layer "F.Fab")
			(hide yes)
			(effects
				(font
					(size 1 1)
					(thickness 0.15)
				)
			)
		)
		(property "Voltage" "25V"
			(at 0 0 90)
			(unlocked yes)
			(layer "F.Fab")
			(hide yes)
			(effects
				(font
					(size 1 1)
					(thickness 0.15)
				)
			)
		)
		(property "Dielectric" "X5R"
			(at 0 0 90)
			(unlocked yes)
			(layer "F.Fab")
			(hide yes)
			(effects
				(font
					(size 1 1)
					(thickness 0.15)
				)
			)
		)
		(property "Public" "False"
			(at 0 0 90)
			(unlocked yes)
			(layer "F.Fab")
			(hide yes)
			(effects
				(font
					(size 1 1)
					(thickness 0.15)
				)
			)
		)
		(component_classes
			(class "DCDC_20V")
		)
		(sheetname "/DCDC/")
		(sheetfile "dcdc.kicad_sch")
		(attr smd)
		(fp_line
			(start -0.3 -0.7)
			(end 0.3 -0.7)
			(stroke
				(width 0.15)
				(type solid)
			)
			(layer "F.SilkS")
		)
		(fp_line
			(start -0.3 0.7)
			(end 0.3 0.7)
			(stroke
				(width 0.15)
				(type solid)
			)
			(layer "F.SilkS")
		)
		(fp_rect
			(start 1.95 -0.9)
			(end -1.95 0.9)
			(stroke
				(width 0.05)
				(type default)
			)
			(fill no)
			(layer "F.CrtYd")
		)
		(fp_rect
			(start -0.95 -0.675)
			(end 0.95 0.675)
			(stroke
				(width 0.15)
				(type solid)
			)
			(fill no)
			(layer "F.Fab")
		)
		(fp_text user "Author: Antmicro"
			(at -1.9 5.947 90)
			(layer "F.Fab")
			(effects
				(font
					(size 0.7 0.7)
					(thickness 0.15)
				)
				(justify left bottom)
			)
		)
		(fp_text user "License: Apache-2.0"
			(at -1.9 4.947 90)
			(layer "F.Fab")
			(effects
				(font
					(size 0.7 0.7)
					(thickness 0.15)
				)
				(justify left bottom)
			)
		)
		(fp_text user "${REFERENCE}"
			(at -1.9 3.947 90)
			(layer "F.Fab")
			(effects
				(font
					(size 0.7 0.7)
					(thickness 0.15)
				)
				(justify left bottom)
			)
		)
		(pad "1" smd roundrect
			(at -1.1 0 90)
			(size 1.2 1.3)
			(layers "F.Cu" "F.Mask" "F.Paste")
			(roundrect_rratio 0.25)
			(net 1 "GND")
			(pintype "passive")
		)
		(pad "2" smd roundrect
			(at 1.1 0 90)
			(size 1.2 1.3)
			(layers "F.Cu" "F.Mask" "F.Paste")
			(roundrect_rratio 0.25)
			(net 1105 "/DCDC/20V_OUT")
			(pintype "passive")
		)
	)
	(footprint "antmicro-footprints:C_0805_2012Metric"
		(layer "F.Cu")
		(at 170.86 146.32 -90)
		(descr "Capacitor SMD 0805")
		(tags "capacitor SMD 0805")
		(property "Reference" "C235"
			(at 1.89 -0.56 90)
			(layer "F.SilkS")
			(effects
				(font
					(size 0.7 0.7)
					(thickness 0.15)
				)
				(justify right top)
			)
		)
		(property "Value" "C_22u_25V_0805"
			(at -2.055717 1.963152 90)
			(layer "F.Fab")
			(effects
				(font
					(size 0.7 0.7)
					(thickness 0.15)
				)
				(justify right top)
			)
		)
		(property "Datasheet" "https://product.samsungsem.com/mlcc/CL21A226MAYNNN.do"
			(at 0 0 90)
			(layer "F.Fab")
			(hide yes)
			(effects
				(font
					(size 1.27 1.27)
					(thickness 0.15)
				)
			)
		)
		(property "Description" "SMT Multilayer Ceramic Capacitor, 22uF, +/-20%, 25V, X5R, 0805 [2012 Metric]"
			(at 0 0 90)
			(layer "F.Fab")
			(hide yes)
			(effects
				(font
					(size 1.27 1.27)
					(thickness 0.15)
				)
			)
		)
		(property "Manufacturer" "Samsung Electro-Mechanics"
			(at 0 0 270)
			(unlocked yes)
			(layer "F.Fab")
			(hide yes)
			(effects
				(font
					(size 1 1)
					(thickness 0.15)
				)
			)
		)
		(property "MPN" "CL21A226MAYNNNE"
			(at 0 0 270)
			(unlocked yes)
			(layer "F.Fab")
			(hide yes)
			(effects
				(font
					(size 1 1)
					(thickness 0.15)
				)
			)
		)
		(property "Val" "22u"
			(at 0 0 270)
			(unlocked yes)
			(layer "F.Fab")
			(hide yes)
			(effects
				(font
					(size 1 1)
					(thickness 0.15)
				)
			)
		)
		(property "License" "Apache-2.0"
			(at 0 0 270)
			(unlocked yes)
			(layer "F.Fab")
			(hide yes)
			(effects
				(font
					(size 1 1)
					(thickness 0.15)
				)
			)
		)
		(property "Author" "Antmicro"
			(at 0 0 270)
			(unlocked yes)
			(layer "F.Fab")
			(hide yes)
			(effects
				(font
					(size 1 1)
					(thickness 0.15)
				)
			)
		)
		(property "Voltage" "25V"
			(at 0 0 270)
			(unlocked yes)
			(layer "F.Fab")
			(hide yes)
			(effects
				(font
					(size 1 1)
					(thickness 0.15)
				)
			)
		)
		(property "Dielectric" "X5R"
			(at 0 0 270)
			(unlocked yes)
			(layer "F.Fab")
			(hide yes)
			(effects
				(font
					(size 1 1)
					(thickness 0.15)
				)
			)
		)
		(property "Public" "False"
			(at 0 0 270)
			(unlocked yes)
			(layer "F.Fab")
			(hide yes)
			(effects
				(font
					(size 1 1)
					(thickness 0.15)
				)
			)
		)
		(sheetname "/DCDC/")
		(sheetfile "dcdc.kicad_sch")
		(attr smd)
		(fp_line
			(start -0.3 0.7)
			(end 0.3 0.7)
			(stroke
				(width 0.15)
				(type solid)
			)
			(layer "F.SilkS")
		)
		(fp_line
			(start -0.3 -0.7)
			(end 0.3 -0.7)
			(stroke
				(width 0.15)
				(type solid)
			)
			(layer "F.SilkS")
		)
		(fp_rect
			(start 1.95 -0.9)
			(end -1.95 0.9)
			(stroke
				(width 0.05)
				(type default)
			)
			(fill no)
			(layer "F.CrtYd")
		)
		(fp_rect
			(start -0.95 -0.675)
			(end 0.95 0.675)
			(stroke
				(width 0.15)
				(type solid)
			)
			(fill no)
			(layer "F.Fab")
		)
		(fp_text user "Author: Antmicro"
			(at -1.9 5.947 90)
			(layer "F.Fab")
			(effects
				(font
					(size 0.7 0.7)
					(thickness 0.15)
				)
				(justify right top)
			)
		)
		(fp_text user "${REFERENCE}"
			(at -1.9 3.947 90)
			(layer "F.Fab")
			(effects
				(font
					(size 0.7 0.7)
					(thickness 0.15)
				)
				(justify right top)
			)
		)
		(fp_text user "License: Apache-2.0"
			(at -1.9 4.947 90)
			(layer "F.Fab")
			(effects
				(font
					(size 0.7 0.7)
					(thickness 0.15)
				)
				(justify right top)
			)
		)
		(pad "1" smd roundrect
			(at -1.1 0 270)
			(size 1.2 1.3)
			(layers "F.Cu" "F.Mask" "F.Paste")
			(roundrect_rratio 0.25)
			(net 1 "GND")
			(pintype "passive")
		)
		(pad "2" smd roundrect
			(at 1.1 0 270)
			(size 1.2 1.3)
			(layers "F.Cu" "F.Mask" "F.Paste")
			(roundrect_rratio 0.25)
			(net 880 "/DCDC/12V_OUT")
			(pintype "passive")
		)
	)
	(footprint "antmicro-footprints:R_0402_1005Metric"
		(layer "F.Cu")
		(at 161.99 62.8 90)
		(descr "Resistor SMD 0402")
		(tags "resistor SMD 0402")
		(property "Reference" "R342"
			(at -1.4 1.51 90)
			(layer "F.SilkS")
			(effects
				(font
					(size 0.7 0.7)
					(thickness 0.15)
				)
				(justify left bottom)
			)
		)
		(property "Value" "R_10k_0402"
			(at -1.011843 1.772046 90)
			(layer "F.Fab")
			(effects
				(font
					(size 0.7 0.7)
					(thickness 0.15)
				)
				(justify left bottom)
			)
		)
		(property "Datasheet" "https://www.bourns.com/docs/product-datasheets/cr.pdf"
			(at 0 0 90)
			(layer "F.Fab")
			(hide yes)
			(effects
				(font
					(size 1.27 1.27)
					(thickness 0.15)
				)
			)
		)
		(property "Description" "SMD Chip Resistor, 10 kohm, ± 1%, 62.5 mW, 0402 [1005 Metric], Thick Film, General Purpose"
			(at 0 0 90)
			(layer "F.Fab")
			(hide yes)
			(effects
				(font
					(size 1.27 1.27)
					(thickness 0.15)
				)
			)
		)
		(property "MPN" "CR0402-FX-1002GLF"
			(at 0 0 90)
			(unlocked yes)
			(layer "F.Fab")
			(hide yes)
			(effects
				(font
					(size 1 1)
					(thickness 0.15)
				)
			)
		)
		(property "Manufacturer" "Bourns"
			(at 0 0 90)
			(unlocked yes)
			(layer "F.Fab")
			(hide yes)
			(effects
				(font
					(size 1 1)
					(thickness 0.15)
				)
			)
		)
		(property "License" "Apache-2.0"
			(at 0 0 90)
			(unlocked yes)
			(layer "F.Fab")
			(hide yes)
			(effects
				(font
					(size 1 1)
					(thickness 0.15)
				)
			)
		)
		(property "Author" "Antmicro"
			(at 0 0 90)
			(unlocked yes)
			(layer "F.Fab")
			(hide yes)
			(effects
				(font
					(size 1 1)
					(thickness 0.15)
				)
			)
		)
		(property "Val" "10k"
			(at 0 0 90)
			(unlocked yes)
			(layer "F.Fab")
			(hide yes)
			(effects
				(font
					(size 1 1)
					(thickness 0.15)
				)
			)
		)
		(property "Tolerance" "1%"
			(at 0 0 90)
			(unlocked yes)
			(layer "F.Fab")
			(hide yes)
			(effects
				(font
					(size 1 1)
					(thickness 0.15)
				)
			)
		)
		(sheetname "/SoM_IO2/")
		(sheetfile "som_io2.kicad_sch")
		(attr smd exclude_from_pos_files exclude_from_bom dnp)
		(fp_poly
			(pts
				(xy -0.925 -0.47) (xy 0.925 -0.47) (xy 0.925 0.47) (xy -0.925 0.47)
			)
			(stroke
				(width 0.05)
				(type default)
			)
			(fill no)
			(layer "F.CrtYd")
		)
		(fp_poly
			(pts
				(xy -0.5 -0.25) (xy 0.5 -0.25) (xy 0.5 0.25) (xy -0.5 0.25)
			)
			(stroke
				(width 0.15)
				(type solid)
			)
			(fill no)
			(layer "F.Fab")
		)
		(fp_text user "${REFERENCE}"
			(at -0.95 3.168 90)
			(layer "F.Fab")
			(effects
				(font
					(size 0.7 0.7)
					(thickness 0.15)
				)
				(justify left bottom)
			)
		)
		(fp_text user "Author: Antmicro"
			(at -0.95 4.169 90)
			(layer "F.Fab")
			(effects
				(font
					(size 0.7 0.7)
					(thickness 0.15)
				)
				(justify left bottom)
			)
		)
		(fp_text user "License: Apache-2.0"
			(at -0.949999 5.169 90)
			(layer "F.Fab")
			(effects
				(font
					(size 0.7 0.7)
					(thickness 0.15)
				)
				(justify left bottom)
			)
		)
		(pad "1" smd roundrect
			(at -0.48 0 90)
			(size 0.59 0.64)
			(layers "F.Cu" "F.Mask" "F.Paste")
			(roundrect_rratio 0.25)
			(net 870 "/SoM_IO2/TC_JTAG_TRST_N")
			(pintype "passive")
		)
		(pad "2" smd roundrect
			(at 0.48 0 90)
			(size 0.59 0.64)
			(layers "F.Cu" "F.Mask" "F.Paste")
			(roundrect_rratio 0.25)
			(net 269 "/SoM_IO2/TC_VCC")
			(pintype "passive")
		)
	)
	(footprint "antmicro-footprints:TP_SMD_0.75mm"
		(layer "F.Cu")
		(at 72 128.45)
		(property "Reference" "TP111"
			(at -0.2 -4.65 270)
			(layer "F.SilkS")
			(effects
				(font
					(size 0.7 0.7)
					(thickness 0.15)
				)
				(justify right top)
			)
		)
		(property "Value" "TP_0.75mm_SMD"
			(at 0 1.2 180)
			(layer "F.Fab")
			(effects
				(font
					(size 0.7 0.7)
					(thickness 0.15)
				)
				(justify right top)
			)
		)
		(property "Description" "SMT test point"
			(at 0 0 180)
			(layer "F.Fab")
			(hide yes)
			(effects
				(font
					(size 1.27 1.27)
					(thickness 0.15)
				)
			)
		)
		(property "MPN" ""
			(at 0 0 0)
			(unlocked yes)
			(layer "F.Fab")
			(hide yes)
			(effects
				(font
					(size 1 1)
					(thickness 0.15)
				)
			)
		)
		(property "Manufacturer" ""
			(at 0 0 0)
			(unlocked yes)
			(layer "F.Fab")
			(hide yes)
			(effects
				(font
					(size 1 1)
					(thickness 0.15)
				)
			)
		)
		(property "Author" "Antmicro"
			(at 0 0 0)
			(unlocked yes)
			(layer "F.Fab")
			(hide yes)
			(effects
				(font
					(size 1 1)
					(thickness 0.15)
				)
			)
		)
		(property "License" "Apache-2.0"
			(at 0 0 0)
			(unlocked yes)
			(layer "F.Fab")
			(hide yes)
			(effects
				(font
					(size 1 1)
					(thickness 0.15)
				)
			)
		)
		(sheetname "/Expansion connector/")
		(sheetfile "expansion_connector.kicad_sch")
		(attr exclude_from_pos_files exclude_from_bom)
		(fp_circle
			(center 0 0)
			(end 0.475 0)
			(stroke
				(width 0.05)
				(type default)
			)
			(fill no)
			(layer "F.CrtYd")
		)
		(fp_text user "License: Apache-2.0"
			(at -0.4 5.101 180)
			(layer "F.Fab")
			(effects
				(font
					(size 0.7 0.7)
					(thickness 0.15)
				)
				(justify right top)
			)
		)
		(fp_text user "Author: Antmicro"
			(at -0.4 3.901 180)
			(layer "F.Fab")
			(effects
				(font
					(size 0.7 0.7)
					(thickness 0.15)
				)
				(justify right top)
			)
		)
		(fp_text user "${REFERENCE}"
			(at -0.4 2.7 180)
			(layer "F.Fab")
			(effects
				(font
					(size 0.7 0.7)
					(thickness 0.15)
				)
				(justify right top)
			)
		)
		(pad "1" smd circle
			(at 0 0)
			(size 0.75 0.75)
			(layers "F.Cu" "F.Mask")
			(net 360 "Net-(J18-PadK40)")
			(pinfunction "1")
			(pintype "passive")
		)
	)
	(footprint "antmicro-footprints:C_0402_1005Metric"
		(layer "F.Cu")
		(at 157.33 141.88 180)
		(descr "Capacitor SMD 0402")
		(tags "capacitor SMD 0402")
		(property "Reference" "C206"
			(at -1.37 3.78 0)
			(layer "F.SilkS")
			(effects
				(font
					(size 0.7 0.7)
					(thickness 0.15)
				)
				(justify right top)
			)
		)
		(property "Value" "C_100n_0402"
			(at -1.022927 2.155213 0)
			(layer "F.Fab")
			(effects
				(font
					(size 0.7 0.7)
					(thickness 0.15)
				)
				(justify right top)
			)
		)
		(property "Datasheet" "https://www.murata.com/products/productdetail?partno=GRM155R61H104KE14%23"
			(at 0 0 0)
			(layer "F.Fab")
			(hide yes)
			(effects
				(font
					(size 1.27 1.27)
					(thickness 0.15)
				)
			)
		)
		(property "Description" "SMD Multilayer Ceramic Capacitor, 0.1 µF, 50 V, 0402 [1005 Metric], ± 10%, X5R, GRM Series"
			(at 0 0 0)
			(layer "F.Fab")
			(hide yes)
			(effects
				(font
					(size 1.27 1.27)
					(thickness 0.15)
				)
			)
		)
		(property "Manufacturer" "Murata"
			(at 0 0 180)
			(unlocked yes)
			(layer "F.Fab")
			(hide yes)
			(effects
				(font
					(size 1 1)
					(thickness 0.15)
				)
			)
		)
		(property "MPN" "GRM155R61H104KE14D"
			(at 0 0 180)
			(unlocked yes)
			(layer "F.Fab")
			(hide yes)
			(effects
				(font
					(size 1 1)
					(thickness 0.15)
				)
			)
		)
		(property "Val" "100n"
			(at 0 0 180)
			(unlocked yes)
			(layer "F.Fab")
			(hide yes)
			(effects
				(font
					(size 1 1)
					(thickness 0.15)
				)
			)
		)
		(property "License" "Apache-2.0"
			(at 0 0 180)
			(unlocked yes)
			(layer "F.Fab")
			(hide yes)
			(effects
				(font
					(size 1 1)
					(thickness 0.15)
				)
			)
		)
		(property "Author" "Antmicro"
			(at 0 0 180)
			(unlocked yes)
			(layer "F.Fab")
			(hide yes)
			(effects
				(font
					(size 1 1)
					(thickness 0.15)
				)
			)
		)
		(property "Voltage" "50V"
			(at 0 0 180)
			(unlocked yes)
			(layer "F.Fab")
			(hide yes)
			(effects
				(font
					(size 1 1)
					(thickness 0.15)
				)
			)
		)
		(property "Dielectric" "X5R"
			(at 0 0 180)
			(unlocked yes)
			(layer "F.Fab")
			(hide yes)
			(effects
				(font
					(size 1 1)
					(thickness 0.15)
				)
			)
		)
		(sheetname "/Peripherals/")
		(sheetfile "peripherals.kicad_sch")
		(attr smd)
		(fp_rect
			(start -0.925 -0.47)
			(end 0.925 0.47)
			(stroke
				(width 0.05)
				(type default)
			)
			(fill no)
			(layer "F.CrtYd")
		)
		(fp_line
			(start 0.504 0.248)
			(end -0.494 0.248)
			(stroke
				(width 0.15)
				(type solid)
			)
			(layer "F.Fab")
		)
		(fp_line
			(start 0.504 -0.25)
			(end 0.504 0.248)
			(stroke
				(width 0.15)
				(type solid)
			)
			(layer "F.Fab")
		)
		(fp_line
			(start -0.494 0.248)
			(end -0.494 -0.25)
			(stroke
				(width 0.15)
				(type solid)
			)
			(layer "F.Fab")
		)
		(fp_line
			(start -0.494 -0.25)
			(end 0.504 -0.25)
			(stroke
				(width 0.15)
				(type solid)
			)
			(layer "F.Fab")
		)
		(fp_text user "${REFERENCE}"
			(at -0.939 4.599 0)
			(layer "F.Fab")
			(effects
				(font
					(size 0.7 0.7)
					(thickness 0.15)
				)
				(justify right top)
			)
		)
		(fp_text user "Author: Antmicro"
			(at -0.939 3.399 0)
			(layer "F.Fab")
			(effects
				(font
					(size 0.7 0.7)
					(thickness 0.15)
				)
				(justify right top)
			)
		)
		(fp_text user "License: Apache-2.0"
			(at -0.939 5.799 0)
			(layer "F.Fab")
			(effects
				(font
					(size 0.7 0.7)
					(thickness 0.15)
				)
				(justify right top)
			)
		)
		(pad "1" smd roundrect
			(at -0.48 0 180)
			(size 0.59 0.64)
			(layers "F.Cu" "F.Mask" "F.Paste")
			(roundrect_rratio 0.25)
			(net 1 "GND")
			(pintype "passive")
		)
		(pad "2" smd roundrect
			(at 0.48 0 180)
			(size 0.59 0.64)
			(layers "F.Cu" "F.Mask" "F.Paste")
			(roundrect_rratio 0.25)
			(net 5 "+5V")
			(pintype "passive")
		)
	)
	(footprint "antmicro-footprints:D_SOD-123"
		(layer "F.Cu")
		(at 224.75 73.5 -90)
		(property "Reference" "D2"
			(at 0 -1.099999 90)
			(layer "F.SilkS")
			(effects
				(font
					(size 0.7 0.7)
					(thickness 0.15)
				)
				(justify right top)
			)
		)
		(property "Value" "PTVS26VS1UR,115"
			(at 0 1.95 90)
			(layer "F.Fab")
			(effects
				(font
					(size 0.7 0.7)
					(thickness 0.15)
				)
				(justify right top)
			)
		)
		(property "Datasheet" "https://www.mouser.com/datasheet/2/916/PTVSXS1UR_SER-1545507.pdf"
			(at 0 0 90)
			(layer "F.Fab")
			(hide yes)
			(effects
				(font
					(size 1.27 1.27)
					(thickness 0.15)
				)
			)
		)
		(property "Description" "Unidirectional TVS, 8 kV,  SOD-123F, 26 V, 400 W"
			(at 0 0 90)
			(layer "F.Fab")
			(hide yes)
			(effects
				(font
					(size 1.27 1.27)
					(thickness 0.15)
				)
			)
		)
		(property "Manufacturer" "Nexperia"
			(at 0 0 90)
			(unlocked yes)
			(layer "F.Fab")
			(hide yes)
			(effects
				(font
					(size 1 1)
					(thickness 0.15)
				)
			)
		)
		(property "MPN" "PTVS26VS1UR,115"
			(at 0 0 90)
			(unlocked yes)
			(layer "F.Fab")
			(hide yes)
			(effects
				(font
					(size 1 1)
					(thickness 0.15)
				)
			)
		)
		(property "Author" "Antmicro"
			(at 0 0 90)
			(unlocked yes)
			(layer "F.Fab")
			(hide yes)
			(effects
				(font
					(size 1 1)
					(thickness 0.15)
				)
			)
		)
		(property "License" "Apache-2.0"
			(at 0 0 90)
			(unlocked yes)
			(layer "F.Fab")
			(hide yes)
			(effects
				(font
					(size 1 1)
					(thickness 0.15)
				)
			)
		)
		(sheetname "/Power/")
		(sheetfile "power.kicad_sch")
		(attr smd)
		(fp_line
			(start 1.1 0.8875)
			(end 1.45 0.8875)
			(stroke
				(width 0.15)
				(type solid)
			)
			(layer "F.SilkS")
		)
		(fp_line
			(start -1.45 0.8625)
			(end -1.45 0.5875)
			(stroke
				(width 0.15)
				(type solid)
			)
			(layer "F.SilkS")
		)
		(fp_line
			(start -1.1 0.8625)
			(end -1.45 0.8625)
			(stroke
				(width 0.15)
				(type solid)
			)
			(layer "F.SilkS")
		)
		(fp_line
			(start 1.45 0.6125)
			(end 1.45 0.8875)
			(stroke
				(width 0.15)
				(type solid)
			)
			(layer "F.SilkS")
		)
		(fp_line
			(start -0.925 -0.5)
			(end -0.925 0.5)
			(stroke
				(width 0.15)
				(type solid)
			)
			(layer "F.SilkS")
		)
		(fp_line
			(start -1.45 -0.6)
			(end -1.45 -0.875)
			(stroke
				(width 0.15)
				(type solid)
			)
			(layer "F.SilkS")
		)
		(fp_line
			(start -1.1 -0.875)
			(end -1.45 -0.875)
			(stroke
				(width 0.15)
				(type solid)
			)
			(layer "F.SilkS")
		)
		(fp_line
			(start 1.1 -0.875)
			(end 1.45 -0.875)
			(stroke
				(width 0.15)
				(type solid)
			)
			(layer "F.SilkS")
		)
		(fp_line
			(start 1.45 -0.875)
			(end 1.45 -0.6)
			(stroke
				(width 0.15)
				(type solid)
			)
			(layer "F.SilkS")
		)
		(fp_poly
			(pts
				(xy -2.275 -1.05) (xy 2.275 -1.05) (xy 2.275 1.05) (xy -2.275 1.05)
			)
			(stroke
				(width 0.05)
				(type solid)
			)
			(fill no)
			(layer "F.CrtYd")
		)
		(fp_line
			(start -1.325 0.848)
			(end 1.324 0.848)
			(stroke
				(width 0.15)
				(type solid)
			)
			(layer "F.Fab")
		)
		(fp_line
			(start -1.325 -0.85)
			(end -1.325 0.848)
			(stroke
				(width 0.15)
				(type solid)
			)
			(layer "F.Fab")
		)
		(fp_line
			(start -1.325 -0.85)
			(end 1.324 -0.85)
			(stroke
				(width 0.15)
				(type solid)
			)
			(layer "F.Fab")
		)
		(fp_line
			(start 1.324 -0.85)
			(end 1.324 0.848)
			(stroke
				(width 0.15)
				(type solid)
			)
			(layer "F.Fab")
		)
		(fp_text user "License: Apache-2.0"
			(at -2.36 5.85 90)
			(layer "F.Fab")
			(effects
				(font
					(size 0.7 0.7)
					(thickness 0.15)
				)
				(justify right top)
			)
		)
		(fp_text user "${REFERENCE}"
			(at -2.36 3.299999 90)
			(layer "F.Fab")
			(effects
				(font
					(size 0.7 0.7)
					(thickness 0.15)
				)
				(justify right top)
			)
		)
		(fp_text user "Author: Antmicro"
			(at -2.36 4.6 90)
			(layer "F.Fab")
			(effects
				(font
					(size 0.7 0.7)
					(thickness 0.15)
				)
				(justify right top)
			)
		)
		(pad "1" smd roundrect
			(at -1.625 -0.001001 270)
			(size 0.9 0.95)
			(layers "F.Cu" "F.Mask" "F.Paste")
			(roundrect_rratio 0.15)
			(net 3 "VCC_IN")
			(pinfunction "C")
			(pintype "passive")
		)
		(pad "2" smd roundrect
			(at 1.625 -0.001001 270)
			(size 0.9 0.95)
			(layers "F.Cu" "F.Mask" "F.Paste")
			(roundrect_rratio 0.15)
			(net 1 "GND")
			(pinfunction "A")
			(pintype "passive")
		)
	)
	(footprint "antmicro-footprints:USON-10_2.5x1mm_P0.5mm"
		(layer "F.Cu")
		(at 221.369 102.36)
		(descr "USON-10 2.5x1mm_ Pitch 0.5mm")
		(tags "USON-10 2.5x1mm Pitch 0.5mm")
		(property "Reference" "U58"
			(at 1.861 1 90)
			(layer "F.SilkS")
			(effects
				(font
					(size 0.7 0.7)
					(thickness 0.15)
				)
				(justify left bottom)
			)
		)
		(property "Value" "TPD4E05U06QDQARQ1"
			(at 0.018 2.499 0)
			(layer "F.Fab")
			(effects
				(font
					(size 0.7 0.7)
					(thickness 0.15)
				)
				(justify left bottom)
			)
		)
		(property "Datasheet" "https://www.ti.com/lit/ds/symlink/tpd4e05u06-q1.pdf?HQS=dis-mous-null-mousermode-dsf-pf-null-wwe&ts=1663591265741&ref_url=https%253A%252F%252Fwww.mouser.com%252F"
			(at 0 0 0)
			(layer "F.Fab")
			(hide yes)
			(effects
				(font
					(size 1.27 1.27)
					(thickness 0.15)
				)
			)
		)
		(property "Description" "TVS diode array, 12 kV, USON-10, 5.5 V, 0.5 pF"
			(at 0 0 0)
			(layer "F.Fab")
			(hide yes)
			(effects
				(font
					(size 1.27 1.27)
					(thickness 0.15)
				)
			)
		)
		(property "Manufacturer" "Texas Instruments"
			(at 0 0 0)
			(unlocked yes)
			(layer "F.Fab")
			(hide yes)
			(effects
				(font
					(size 1 1)
					(thickness 0.15)
				)
			)
		)
		(property "MPN" "TPD4E05U06QDQARQ1"
			(at 0 0 0)
			(unlocked yes)
			(layer "F.Fab")
			(hide yes)
			(effects
				(font
					(size 1 1)
					(thickness 0.15)
				)
			)
		)
		(property "Author" "Antmicro"
			(at 0 0 0)
			(unlocked yes)
			(layer "F.Fab")
			(hide yes)
			(effects
				(font
					(size 1 1)
					(thickness 0.15)
				)
			)
		)
		(property "License" "Apache-2.0"
			(at 0 0 0)
			(unlocked yes)
			(layer "F.Fab")
			(hide yes)
			(effects
				(font
					(size 1 1)
					(thickness 0.15)
				)
			)
		)
		(sheetname "/Recovery USB/")
		(sheetfile "recovery_usb.kicad_sch")
		(attr smd)
		(fp_line
			(start 0.498 -1.401)
			(end -0.5 -1.401)
			(stroke
				(width 0.15)
				(type solid)
			)
			(layer "F.SilkS")
		)
		(fp_line
			(start 0.498 1.398)
			(end -0.5 1.398)
			(stroke
				(width 0.15)
				(type solid)
			)
			(layer "F.SilkS")
		)
		(fp_circle
			(center -0.68 -1.27)
			(end -0.63 -1.27)
			(stroke
				(width 0.15)
				(type solid)
			)
			(fill yes)
			(layer "F.SilkS")
		)
		(fp_rect
			(start -0.8 -1.5)
			(end 0.8 1.499)
			(stroke
				(width 0.05)
				(type solid)
			)
			(fill no)
			(layer "F.CrtYd")
		)
		(fp_line
			(start -0.5 -1)
			(end -0.5 1.249)
			(stroke
				(width 0.15)
				(type solid)
			)
			(layer "F.Fab")
		)
		(fp_line
			(start -0.5 1.249)
			(end 0.498 1.249)
			(stroke
				(width 0.15)
				(type solid)
			)
			(layer "F.Fab")
		)
		(fp_line
			(start -0.25 -1.25)
			(end -0.5 -1)
			(stroke
				(width 0.15)
				(type solid)
			)
			(layer "F.Fab")
		)
		(fp_line
			(start 0.498 -1.25)
			(end -0.25 -1.25)
			(stroke
				(width 0.15)
				(type solid)
			)
			(layer "F.Fab")
		)
		(fp_line
			(start 0.498 -1.25)
			(end 0.498 1.249)
			(stroke
				(width 0.15)
				(type solid)
			)
			(layer "F.Fab")
		)
		(fp_text user "License: Apache-2.0"
			(at -0.802 6.9 0)
			(layer "F.Fab")
			(effects
				(font
					(size 0.7 0.7)
					(thickness 0.15)
				)
				(justify left bottom)
			)
		)
		(fp_text user "${REFERENCE}"
			(at -0.802 4.498 0)
			(layer "F.Fab")
			(effects
				(font
					(size 0.7 0.7)
					(thickness 0.15)
				)
				(justify left bottom)
			)
		)
		(fp_text user "Author: Antmicro"
			(at -0.802 5.7 0)
			(layer "F.Fab")
			(effects
				(font
					(size 0.7 0.7)
					(thickness 0.15)
				)
				(justify left bottom)
			)
		)
		(pad "1" smd roundrect
			(at -0.387 -1 270)
			(size 0.25 0.55)
			(layers "F.Cu" "F.Mask" "F.Paste")
			(roundrect_rratio 0.25)
			(net 766 "/Recovery USB/USB0.D+")
			(pintype "passive")
		)
		(pad "2" smd roundrect
			(at -0.387 -0.5 270)
			(size 0.25 0.55)
			(layers "F.Cu" "F.Mask" "F.Paste")
			(roundrect_rratio 0.25)
			(net 698 "/Recovery USB/USB0.D-")
			(pintype "passive")
		)
		(pad "3" smd roundrect
			(at -0.387 0 270)
			(size 0.4 0.55)
			(layers "F.Cu" "F.Mask" "F.Paste")
			(roundrect_rratio 0.25)
			(net 1 "GND")
			(pintype "power_in")
		)
		(pad "4" smd roundrect
			(at -0.387 0.498 270)
			(size 0.25 0.55)
			(layers "F.Cu" "F.Mask" "F.Paste")
			(roundrect_rratio 0.25)
			(net 801 "/Recovery USB/USBC2_CC2")
			(pintype "passive")
		)
		(pad "5" smd roundrect
			(at -0.387 0.998 270)
			(size 0.25 0.55)
			(layers "F.Cu" "F.Mask" "F.Paste")
			(roundrect_rratio 0.25)
			(net 806 "/Recovery USB/USBC2_CC1")
			(pintype "passive")
		)
		(pad "6" smd roundrect
			(at 0.385 0.998 270)
			(size 0.25 0.55)
			(layers "F.Cu" "F.Mask" "F.Paste")
			(roundrect_rratio 0.25)
			(net 806 "/Recovery USB/USBC2_CC1")
			(pintype "passive")
		)
		(pad "7" smd roundrect
			(at 0.385 0.498 270)
			(size 0.25 0.55)
			(layers "F.Cu" "F.Mask" "F.Paste")
			(roundrect_rratio 0.25)
			(net 801 "/Recovery USB/USBC2_CC2")
			(pintype "passive")
		)
		(pad "8" smd roundrect
			(at 0.385 0 270)
			(size 0.4 0.55)
			(layers "F.Cu" "F.Mask" "F.Paste")
			(roundrect_rratio 0.25)
			(net 1 "GND")
			(pintype "passive")
		)
		(pad "9" smd roundrect
			(at 0.385 -0.5 270)
			(size 0.25 0.55)
			(layers "F.Cu" "F.Mask" "F.Paste")
			(roundrect_rratio 0.25)
			(net 698 "/Recovery USB/USB0.D-")
			(pintype "passive")
		)
		(pad "10" smd roundrect
			(at 0.385 -1 270)
			(size 0.25 0.55)
			(layers "F.Cu" "F.Mask" "F.Paste")
			(roundrect_rratio 0.25)
			(net 766 "/Recovery USB/USB0.D+")
			(pintype "passive")
		)
	)
	(footprint "antmicro-footprints:R_0402_1005Metric"
		(layer "F.Cu")
		(at 74.5 78.8 90)
		(descr "Resistor SMD 0402")
		(tags "resistor SMD 0402")
		(property "Reference" "R350"
			(at -1.8 -0.7 90)
			(layer "F.SilkS")
			(effects
				(font
					(size 0.7 0.7)
					(thickness 0.15)
				)
				(justify left bottom)
			)
		)
		(property "Value" "R_100R_0402"
			(at -1.011843 1.772046 90)
			(layer "F.Fab")
			(effects
				(font
					(size 0.7 0.7)
					(thickness 0.15)
				)
				(justify left bottom)
			)
		)
		(property "Datasheet" "https://www.bourns.com/docs/product-datasheets/cr.pdf"
			(at 0 0 90)
			(layer "F.Fab")
			(hide yes)
			(effects
				(font
					(size 1.27 1.27)
					(thickness 0.15)
				)
			)
		)
		(property "Description" "SMD Chip Resistor, 100 ohm, ± 1%, 62.5 mW, 0402 [1005 Metric], Thick Film, General Purpose"
			(at 0 0 90)
			(layer "F.Fab")
			(hide yes)
			(effects
				(font
					(size 1.27 1.27)
					(thickness 0.15)
				)
			)
		)
		(property "MPN" "CR0402-FX-1000GLF"
			(at 0 0 90)
			(unlocked yes)
			(layer "F.Fab")
			(hide yes)
			(effects
				(font
					(size 1 1)
					(thickness 0.15)
				)
			)
		)
		(property "Manufacturer" "Bourns"
			(at 0 0 90)
			(unlocked yes)
			(layer "F.Fab")
			(hide yes)
			(effects
				(font
					(size 1 1)
					(thickness 0.15)
				)
			)
		)
		(property "License" "Apache-2.0"
			(at 0 0 90)
			(unlocked yes)
			(layer "F.Fab")
			(hide yes)
			(effects
				(font
					(size 1 1)
					(thickness 0.15)
				)
			)
		)
		(property "Author" "Antmicro"
			(at 0 0 90)
			(unlocked yes)
			(layer "F.Fab")
			(hide yes)
			(effects
				(font
					(size 1 1)
					(thickness 0.15)
				)
			)
		)
		(property "Val" "100R"
			(at 0 0 90)
			(unlocked yes)
			(layer "F.Fab")
			(hide yes)
			(effects
				(font
					(size 1 1)
					(thickness 0.15)
				)
			)
		)
		(property "Tolerance" "1%"
			(at 0 0 90)
			(unlocked yes)
			(layer "F.Fab")
			(hide yes)
			(effects
				(font
					(size 1 1)
					(thickness 0.15)
				)
			)
		)
		(sheetname "/Expansion connector/")
		(sheetfile "expansion_connector.kicad_sch")
		(attr smd)
		(fp_poly
			(pts
				(xy -0.925 -0.47) (xy 0.925 -0.47) (xy 0.925 0.47) (xy -0.925 0.47)
			)
			(stroke
				(width 0.05)
				(type default)
			)
			(fill no)
			(layer "F.CrtYd")
		)
		(fp_poly
			(pts
				(xy -0.5 -0.25) (xy 0.5 -0.25) (xy 0.5 0.25) (xy -0.5 0.25)
			)
			(stroke
				(width 0.15)
				(type solid)
			)
			(fill no)
			(layer "F.Fab")
		)
		(fp_text user "${REFERENCE}"
			(at -0.95 3.168 90)
			(layer "F.Fab")
			(effects
				(font
					(size 0.7 0.7)
					(thickness 0.15)
				)
				(justify left bottom)
			)
		)
		(fp_text user "License: Apache-2.0"
			(at -0.949999 5.169 90)
			(layer "F.Fab")
			(effects
				(font
					(size 0.7 0.7)
					(thickness 0.15)
				)
				(justify left bottom)
			)
		)
		(fp_text user "Author: Antmicro"
			(at -0.95 4.169 90)
			(layer "F.Fab")
			(effects
				(font
					(size 0.7 0.7)
					(thickness 0.15)
				)
				(justify left bottom)
			)
		)
		(pad "1" smd roundrect
			(at -0.48 0 90)
			(size 0.59 0.64)
			(layers "F.Cu" "F.Mask" "F.Paste")
			(roundrect_rratio 0.25)
			(net 761 "Net-(J18-PadH02)")
			(pintype "passive")
		)
		(pad "2" smd roundrect
			(at 0.48 0 90)
			(size 0.59 0.64)
			(layers "F.Cu" "F.Mask" "F.Paste")
			(roundrect_rratio 0.25)
			(net 319 "/Expansion connector/FMC_PRSNT_M2C_L")
			(pintype "passive")
		)
	)
	(footprint "antmicro-footprints:C_0603_1608Metric_EIA"
		(layer "F.Cu")
		(at 174.9 130.18 -90)
		(descr "Capacitor SMD 0603, IPC-7351 Density Level A")
		(tags "Capacitor 0603")
		(property "Reference" "C73"
			(at -4.28 9.4 90)
			(layer "F.SilkS")
			(effects
				(font
					(size 0.7 0.7)
					(thickness 0.15)
				)
				(justify right top)
			)
		)
		(property "Value" "C_22u_16V_0603"
			(at -1.42757 1.770288 90)
			(layer "F.Fab")
			(effects
				(font
					(size 0.7 0.7)
					(thickness 0.15)
				)
				(justify right top)
			)
		)
		(property "Datasheet" "https://product.samsungsem.com/mlcc/CL10A226MO7JZN.do"
			(at 0 0 90)
			(layer "F.Fab")
			(hide yes)
			(effects
				(font
					(size 1.27 1.27)
					(thickness 0.15)
				)
			)
		)
		(property "Description" "SMD Multilayer Ceramic Capacitor"
			(at 0 0 90)
			(layer "F.Fab")
			(hide yes)
			(effects
				(font
					(size 1.27 1.27)
					(thickness 0.15)
				)
			)
		)
		(property "Manufacturer" "Samsung Electro-Mechanics"
			(at 0 0 270)
			(unlocked yes)
			(layer "F.Fab")
			(hide yes)
			(effects
				(font
					(size 1 1)
					(thickness 0.15)
				)
			)
		)
		(property "MPN" "CL10A226MO7JZNC"
			(at 0 0 270)
			(unlocked yes)
			(layer "F.Fab")
			(hide yes)
			(effects
				(font
					(size 1 1)
					(thickness 0.15)
				)
			)
		)
		(property "Val" "22u"
			(at 0 0 270)
			(unlocked yes)
			(layer "F.Fab")
			(hide yes)
			(effects
				(font
					(size 1 1)
					(thickness 0.15)
				)
			)
		)
		(property "License" "Apache-2.0"
			(at 0 0 270)
			(unlocked yes)
			(layer "F.Fab")
			(hide yes)
			(effects
				(font
					(size 1 1)
					(thickness 0.15)
				)
			)
		)
		(property "Author" "Antmicro"
			(at 0 0 270)
			(unlocked yes)
			(layer "F.Fab")
			(hide yes)
			(effects
				(font
					(size 1 1)
					(thickness 0.15)
				)
			)
		)
		(property "Voltage" "16V"
			(at 0 0 270)
			(unlocked yes)
			(layer "F.Fab")
			(hide yes)
			(effects
				(font
					(size 1 1)
					(thickness 0.15)
				)
			)
		)
		(property "Dielectric" ""
			(at 0 0 270)
			(unlocked yes)
			(layer "F.Fab")
			(hide yes)
			(effects
				(font
					(size 1 1)
					(thickness 0.15)
				)
			)
		)
		(sheetname "/DCDC/")
		(sheetfile "dcdc.kicad_sch")
		(attr smd)
		(fp_line
			(start -0.15 0.55)
			(end 0.15 0.55)
			(stroke
				(width 0.15)
				(type solid)
			)
			(layer "F.SilkS")
		)
		(fp_line
			(start -0.15 -0.55)
			(end 0.15 -0.55)
			(stroke
				(width 0.15)
				(type solid)
			)
			(layer "F.SilkS")
		)
		(fp_rect
			(start -1.25 -0.65)
			(end 1.25 0.65)
			(stroke
				(width 0.05)
				(type solid)
			)
			(fill no)
			(layer "F.CrtYd")
		)
		(fp_rect
			(start -0.8 -0.45)
			(end 0.8 0.45)
			(stroke
				(width 0.15)
				(type solid)
			)
			(fill no)
			(layer "F.Fab")
		)
		(fp_text user "Author: Antmicro"
			(at -1.682 4.894 90)
			(layer "F.Fab")
			(effects
				(font
					(size 0.7 0.7)
					(thickness 0.15)
				)
				(justify right top)
			)
		)
		(fp_text user "${REFERENCE}"
			(at -1.682 3.895 90)
			(layer "F.Fab")
			(effects
				(font
					(size 0.7 0.7)
					(thickness 0.15)
				)
				(justify right top)
			)
		)
		(fp_text user "License: Apache-2.0"
			(at -1.682 5.895 90)
			(layer "F.Fab")
			(effects
				(font
					(size 0.7 0.7)
					(thickness 0.15)
				)
				(justify right top)
			)
		)
		(pad "1" smd roundrect
			(at -0.7 0 270)
			(size 0.8 1.1)
			(layers "F.Cu" "F.Mask" "F.Paste")
			(roundrect_rratio 0.2)
			(net 1 "GND")
			(pintype "passive")
		)
		(pad "2" smd roundrect
			(at 0.7 0 270)
			(size 0.8 1.1)
			(layers "F.Cu" "F.Mask" "F.Paste")
			(roundrect_rratio 0.2)
			(net 567 "/DCDC/3V3_OUT")
			(pintype "passive")
		)
	)
	(footprint "antmicro-footprints:C_0603_1608Metric_EIA"
		(layer "F.Cu")
		(at 142.4 128.15 -90)
		(descr "Capacitor SMD 0603, IPC-7351 Density Level A")
		(tags "Capacitor 0603")
		(property "Reference" "C31"
			(at -3.5 0.3 90)
			(layer "F.SilkS")
			(effects
				(font
					(size 0.7 0.7)
					(thickness 0.15)
				)
				(justify right top)
			)
		)
		(property "Value" "C_22u_16V_0603"
			(at -1.42757 1.770288 90)
			(layer "F.Fab")
			(effects
				(font
					(size 0.7 0.7)
					(thickness 0.15)
				)
				(justify right top)
			)
		)
		(property "Datasheet" "https://product.samsungsem.com/mlcc/CL10A226MO7JZN.do"
			(at 0 0 90)
			(layer "F.Fab")
			(hide yes)
			(effects
				(font
					(size 1.27 1.27)
					(thickness 0.15)
				)
			)
		)
		(property "Description" "SMD Multilayer Ceramic Capacitor"
			(at 0 0 90)
			(layer "F.Fab")
			(hide yes)
			(effects
				(font
					(size 1.27 1.27)
					(thickness 0.15)
				)
			)
		)
		(property "MPN" "CL10A226MO7JZNC"
			(at 0 0 270)
			(unlocked yes)
			(layer "F.Fab")
			(hide yes)
			(effects
				(font
					(size 1 1)
					(thickness 0.15)
				)
			)
		)
		(property "Manufacturer" "Samsung Electro-Mechanics"
			(at 0 0 270)
			(unlocked yes)
			(layer "F.Fab")
			(hide yes)
			(effects
				(font
					(size 1 1)
					(thickness 0.15)
				)
			)
		)
		(property "License" "Apache-2.0"
			(at 0 0 270)
			(unlocked yes)
			(layer "F.Fab")
			(hide yes)
			(effects
				(font
					(size 1 1)
					(thickness 0.15)
				)
			)
		)
		(property "Author" "Antmicro"
			(at 0 0 270)
			(unlocked yes)
			(layer "F.Fab")
			(hide yes)
			(effects
				(font
					(size 1 1)
					(thickness 0.15)
				)
			)
		)
		(property "Val" "22u"
			(at 0 0 270)
			(unlocked yes)
			(layer "F.Fab")
			(hide yes)
			(effects
				(font
					(size 1 1)
					(thickness 0.15)
				)
			)
		)
		(property "Voltage" "16V"
			(at 0 0 270)
			(unlocked yes)
			(layer "F.Fab")
			(hide yes)
			(effects
				(font
					(size 1 1)
					(thickness 0.15)
				)
			)
		)
		(property "Dielectric" ""
			(at 0 0 270)
			(unlocked yes)
			(layer "F.Fab")
			(hide yes)
			(effects
				(font
					(size 1 1)
					(thickness 0.15)
				)
			)
		)
		(property "Public" "False"
			(at 0 0 270)
			(unlocked yes)
			(layer "F.Fab")
			(hide yes)
			(effects
				(font
					(size 1 1)
					(thickness 0.15)
				)
			)
		)
		(component_classes
			(class "DCDC_1V8")
		)
		(sheetname "/DCDC/")
		(sheetfile "dcdc.kicad_sch")
		(attr smd)
		(fp_line
			(start -0.15 0.55)
			(end 0.15 0.55)
			(stroke
				(width 0.15)
				(type solid)
			)
			(layer "F.SilkS")
		)
		(fp_line
			(start -0.15 -0.55)
			(end 0.15 -0.55)
			(stroke
				(width 0.15)
				(type solid)
			)
			(layer "F.SilkS")
		)
		(fp_rect
			(start -1.25 -0.65)
			(end 1.25 0.65)
			(stroke
				(width 0.05)
				(type solid)
			)
			(fill no)
			(layer "F.CrtYd")
		)
		(fp_rect
			(start -0.8 -0.45)
			(end 0.8 0.45)
			(stroke
				(width 0.15)
				(type solid)
			)
			(fill no)
			(layer "F.Fab")
		)
		(fp_text user "${REFERENCE}"
			(at -1.682 3.895 90)
			(layer "F.Fab")
			(effects
				(font
					(size 0.7 0.7)
					(thickness 0.15)
				)
				(justify right top)
			)
		)
		(fp_text user "License: Apache-2.0"
			(at -1.682 5.895 90)
			(layer "F.Fab")
			(effects
				(font
					(size 0.7 0.7)
					(thickness 0.15)
				)
				(justify right top)
			)
		)
		(fp_text user "Author: Antmicro"
			(at -1.682 4.894 90)
			(layer "F.Fab")
			(effects
				(font
					(size 0.7 0.7)
					(thickness 0.15)
				)
				(justify right top)
			)
		)
		(pad "1" smd roundrect
			(at -0.7 0 270)
			(size 0.8 1.1)
			(layers "F.Cu" "F.Mask" "F.Paste")
			(roundrect_rratio 0.2)
			(net 1 "GND")
			(pintype "passive")
		)
		(pad "2" smd roundrect
			(at 0.7 0 270)
			(size 0.8 1.1)
			(layers "F.Cu" "F.Mask" "F.Paste")
			(roundrect_rratio 0.2)
			(net 5 "+5V")
			(pintype "passive")
		)
	)
	(footprint "antmicro-footprints:C_0402_1005Metric"
		(layer "F.Cu")
		(at 211 105.275)
		(descr "Capacitor SMD 0402")
		(tags "capacitor SMD 0402")
		(property "Reference" "C154"
			(at -3.77 0.4 0)
			(layer "F.SilkS")
			(effects
				(font
					(size 0.7 0.7)
					(thickness 0.15)
				)
				(justify left bottom)
			)
		)
		(property "Value" "C_100n_0402"
			(at -1.022927 2.155213 0)
			(layer "F.Fab")
			(effects
				(font
					(size 0.7 0.7)
					(thickness 0.15)
				)
				(justify left bottom)
			)
		)
		(property "Datasheet" "https://www.murata.com/products/productdetail?partno=GRM155R61H104KE14%23"
			(at 0 0 0)
			(layer "F.Fab")
			(hide yes)
			(effects
				(font
					(size 1.27 1.27)
					(thickness 0.15)
				)
			)
		)
		(property "Description" "SMD Multilayer Ceramic Capacitor, 0.1 µF, 50 V, 0402 [1005 Metric], ± 10%, X5R, GRM Series"
			(at 0 0 0)
			(layer "F.Fab")
			(hide yes)
			(effects
				(font
					(size 1.27 1.27)
					(thickness 0.15)
				)
			)
		)
		(property "Manufacturer" "Murata"
			(at 0 0 0)
			(unlocked yes)
			(layer "F.Fab")
			(hide yes)
			(effects
				(font
					(size 1 1)
					(thickness 0.15)
				)
			)
		)
		(property "MPN" "GRM155R61H104KE14D"
			(at 0 0 0)
			(unlocked yes)
			(layer "F.Fab")
			(hide yes)
			(effects
				(font
					(size 1 1)
					(thickness 0.15)
				)
			)
		)
		(property "Val" "100n"
			(at 0 0 0)
			(unlocked yes)
			(layer "F.Fab")
			(hide yes)
			(effects
				(font
					(size 1 1)
					(thickness 0.15)
				)
			)
		)
		(property "License" "Apache-2.0"
			(at 0 0 0)
			(unlocked yes)
			(layer "F.Fab")
			(hide yes)
			(effects
				(font
					(size 1 1)
					(thickness 0.15)
				)
			)
		)
		(property "Author" "Antmicro"
			(at 0 0 0)
			(unlocked yes)
			(layer "F.Fab")
			(hide yes)
			(effects
				(font
					(size 1 1)
					(thickness 0.15)
				)
			)
		)
		(property "Voltage" "50V"
			(at 0 0 0)
			(unlocked yes)
			(layer "F.Fab")
			(hide yes)
			(effects
				(font
					(size 1 1)
					(thickness 0.15)
				)
			)
		)
		(property "Dielectric" "X5R"
			(at 0 0 0)
			(unlocked yes)
			(layer "F.Fab")
			(hide yes)
			(effects
				(font
					(size 1 1)
					(thickness 0.15)
				)
			)
		)
		(sheetname "/Recovery USB/")
		(sheetfile "recovery_usb.kicad_sch")
		(attr smd)
		(fp_rect
			(start -0.925 -0.47)
			(end 0.925 0.47)
			(stroke
				(width 0.05)
				(type default)
			)
			(fill no)
			(layer "F.CrtYd")
		)
		(fp_line
			(start -0.494 -0.25)
			(end 0.504 -0.25)
			(stroke
				(width 0.15)
				(type solid)
			)
			(layer "F.Fab")
		)
		(fp_line
			(start -0.494 0.248)
			(end -0.494 -0.25)
			(stroke
				(width 0.15)
				(type solid)
			)
			(layer "F.Fab")
		)
		(fp_line
			(start 0.504 -0.25)
			(end 0.504 0.248)
			(stroke
				(width 0.15)
				(type solid)
			)
			(layer "F.Fab")
		)
		(fp_line
			(start 0.504 0.248)
			(end -0.494 0.248)
			(stroke
				(width 0.15)
				(type solid)
			)
			(layer "F.Fab")
		)
		(fp_text user "Author: Antmicro"
			(at -0.939 3.399 0)
			(layer "F.Fab")
			(effects
				(font
					(size 0.7 0.7)
					(thickness 0.15)
				)
				(justify left bottom)
			)
		)
		(fp_text user "${REFERENCE}"
			(at -0.939 4.599 0)
			(layer "F.Fab")
			(effects
				(font
					(size 0.7 0.7)
					(thickness 0.15)
				)
				(justify left bottom)
			)
		)
		(fp_text user "License: Apache-2.0"
			(at -0.939 5.799 0)
			(layer "F.Fab")
			(effects
				(font
					(size 0.7 0.7)
					(thickness 0.15)
				)
				(justify left bottom)
			)
		)
		(pad "1" smd roundrect
			(at -0.48 0)
			(size 0.59 0.64)
			(layers "F.Cu" "F.Mask" "F.Paste")
			(roundrect_rratio 0.25)
			(net 598 "/Recovery USB/USBSS0.RX+")
			(pintype "passive")
		)
		(pad "2" smd roundrect
			(at 0.48 0)
			(size 0.59 0.64)
			(layers "F.Cu" "F.Mask" "F.Paste")
			(roundrect_rratio 0.25)
			(net 1128 "/Recovery USB/USBSS_RX_N")
			(pintype "passive")
		)
	)
	(footprint "antmicro-footprints:C_0402_1005Metric"
		(layer "F.Cu")
		(at 218.8 131.8 180)
		(descr "Capacitor SMD 0402")
		(tags "capacitor SMD 0402")
		(property "Reference" "C83"
			(at -0.9 2.4 0)
			(layer "F.SilkS")
			(effects
				(font
					(size 0.7 0.7)
					(thickness 0.15)
				)
				(justify right top)
			)
		)
		(property "Value" "C_100n_0402"
			(at -1.022927 2.155213 0)
			(layer "F.Fab")
			(effects
				(font
					(size 0.7 0.7)
					(thickness 0.15)
				)
				(justify right top)
			)
		)
		(property "Datasheet" "https://www.murata.com/products/productdetail?partno=GRM155R61H104KE14%23"
			(at 0 0 0)
			(layer "F.Fab")
			(hide yes)
			(effects
				(font
					(size 1.27 1.27)
					(thickness 0.15)
				)
			)
		)
		(property "Description" "SMD Multilayer Ceramic Capacitor, 0.1 µF, 50 V, 0402 [1005 Metric], ± 10%, X5R, GRM Series"
			(at 0 0 0)
			(layer "F.Fab")
			(hide yes)
			(effects
				(font
					(size 1.27 1.27)
					(thickness 0.15)
				)
			)
		)
		(property "Manufacturer" "Murata"
			(at 0 0 180)
			(unlocked yes)
			(layer "F.Fab")
			(hide yes)
			(effects
				(font
					(size 1 1)
					(thickness 0.15)
				)
			)
		)
		(property "MPN" "GRM155R61H104KE14D"
			(at 0 0 180)
			(unlocked yes)
			(layer "F.Fab")
			(hide yes)
			(effects
				(font
					(size 1 1)
					(thickness 0.15)
				)
			)
		)
		(property "Val" "100n"
			(at 0 0 180)
			(unlocked yes)
			(layer "F.Fab")
			(hide yes)
			(effects
				(font
					(size 1 1)
					(thickness 0.15)
				)
			)
		)
		(property "License" "Apache-2.0"
			(at 0 0 180)
			(unlocked yes)
			(layer "F.Fab")
			(hide yes)
			(effects
				(font
					(size 1 1)
					(thickness 0.15)
				)
			)
		)
		(property "Author" "Antmicro"
			(at 0 0 180)
			(unlocked yes)
			(layer "F.Fab")
			(hide yes)
			(effects
				(font
					(size 1 1)
					(thickness 0.15)
				)
			)
		)
		(property "Voltage" "50V"
			(at 0 0 180)
			(unlocked yes)
			(layer "F.Fab")
			(hide yes)
			(effects
				(font
					(size 1 1)
					(thickness 0.15)
				)
			)
		)
		(property "Dielectric" "X5R"
			(at 0 0 180)
			(unlocked yes)
			(layer "F.Fab")
			(hide yes)
			(effects
				(font
					(size 1 1)
					(thickness 0.15)
				)
			)
		)
		(sheetname "/USB Hub/")
		(sheetfile "usb_hub.kicad_sch")
		(attr smd)
		(fp_rect
			(start -0.925 -0.47)
			(end 0.925 0.47)
			(stroke
				(width 0.05)
				(type default)
			)
			(fill no)
			(layer "F.CrtYd")
		)
		(fp_line
			(start 0.504 0.248)
			(end -0.494 0.248)
			(stroke
				(width 0.15)
				(type solid)
			)
			(layer "F.Fab")
		)
		(fp_line
			(start 0.504 -0.25)
			(end 0.504 0.248)
			(stroke
				(width 0.15)
				(type solid)
			)
			(layer "F.Fab")
		)
		(fp_line
			(start -0.494 0.248)
			(end -0.494 -0.25)
			(stroke
				(width 0.15)
				(type solid)
			)
			(layer "F.Fab")
		)
		(fp_line
			(start -0.494 -0.25)
			(end 0.504 -0.25)
			(stroke
				(width 0.15)
				(type solid)
			)
			(layer "F.Fab")
		)
		(fp_text user "License: Apache-2.0"
			(at -0.939 5.799 0)
			(layer "F.Fab")
			(effects
				(font
					(size 0.7 0.7)
					(thickness 0.15)
				)
				(justify right top)
			)
		)
		(fp_text user "${REFERENCE}"
			(at -0.939 4.599 0)
			(layer "F.Fab")
			(effects
				(font
					(size 0.7 0.7)
					(thickness 0.15)
				)
				(justify right top)
			)
		)
		(fp_text user "Author: Antmicro"
			(at -0.939 3.399 0)
			(layer "F.Fab")
			(effects
				(font
					(size 0.7 0.7)
					(thickness 0.15)
				)
				(justify right top)
			)
		)
		(pad "1" smd roundrect
			(at -0.48 0 180)
			(size 0.59 0.64)
			(layers "F.Cu" "F.Mask" "F.Paste")
			(roundrect_rratio 0.25)
			(net 91 "/USB Hub/USBC4_CONN_TX1_N")
			(pintype "passive")
		)
		(pad "2" smd roundrect
			(at 0.48 0 180)
			(size 0.59 0.64)
			(layers "F.Cu" "F.Mask" "F.Paste")
			(roundrect_rratio 0.25)
			(net 44 "/USB Hub/USBC4_TX_{1}-")
			(pintype "passive")
		)
	)
	(footprint "antmicro-footprints:C_0603_1608Metric_EIA"
		(layer "F.Cu")
		(at 141.82 56.3 180)
		(descr "Capacitor SMD 0603, IPC-7351 Density Level A")
		(tags "Capacitor 0603")
		(property "Reference" "C62"
			(at -1.05 -0.73 0)
			(layer "F.SilkS")
			(effects
				(font
					(size 0.7 0.7)
					(thickness 0.15)
				)
				(justify right top)
			)
		)
		(property "Value" "C_22u_16V_0603"
			(at -1.42757 1.770288 0)
			(layer "F.Fab")
			(effects
				(font
					(size 0.7 0.7)
					(thickness 0.15)
				)
				(justify right top)
			)
		)
		(property "Datasheet" "https://product.samsungsem.com/mlcc/CL10A226MO7JZN.do"
			(at 0 0 0)
			(layer "F.Fab")
			(hide yes)
			(effects
				(font
					(size 1.27 1.27)
					(thickness 0.15)
				)
			)
		)
		(property "Description" "SMD Multilayer Ceramic Capacitor"
			(at 0 0 0)
			(layer "F.Fab")
			(hide yes)
			(effects
				(font
					(size 1.27 1.27)
					(thickness 0.15)
				)
			)
		)
		(property "Manufacturer" "Samsung Electro-Mechanics"
			(at 0 0 180)
			(unlocked yes)
			(layer "F.Fab")
			(hide yes)
			(effects
				(font
					(size 1 1)
					(thickness 0.15)
				)
			)
		)
		(property "MPN" "CL10A226MO7JZNC"
			(at 0 0 180)
			(unlocked yes)
			(layer "F.Fab")
			(hide yes)
			(effects
				(font
					(size 1 1)
					(thickness 0.15)
				)
			)
		)
		(property "Val" "22u"
			(at 0 0 180)
			(unlocked yes)
			(layer "F.Fab")
			(hide yes)
			(effects
				(font
					(size 1 1)
					(thickness 0.15)
				)
			)
		)
		(property "License" "Apache-2.0"
			(at 0 0 180)
			(unlocked yes)
			(layer "F.Fab")
			(hide yes)
			(effects
				(font
					(size 1 1)
					(thickness 0.15)
				)
			)
		)
		(property "Author" "Antmicro"
			(at 0 0 180)
			(unlocked yes)
			(layer "F.Fab")
			(hide yes)
			(effects
				(font
					(size 1 1)
					(thickness 0.15)
				)
			)
		)
		(property "Voltage" "16V"
			(at 0 0 180)
			(unlocked yes)
			(layer "F.Fab")
			(hide yes)
			(effects
				(font
					(size 1 1)
					(thickness 0.15)
				)
			)
		)
		(property "Dielectric" ""
			(at 0 0 180)
			(unlocked yes)
			(layer "F.Fab")
			(hide yes)
			(effects
				(font
					(size 1 1)
					(thickness 0.15)
				)
			)
		)
		(sheetname "/Power/")
		(sheetfile "power.kicad_sch")
		(attr smd)
		(fp_line
			(start -0.15 0.55)
			(end 0.15 0.55)
			(stroke
				(width 0.15)
				(type solid)
			)
			(layer "F.SilkS")
		)
		(fp_line
			(start -0.15 -0.55)
			(end 0.15 -0.55)
			(stroke
				(width 0.15)
				(type solid)
			)
			(layer "F.SilkS")
		)
		(fp_poly
			(pts
				(xy -1.25 -0.65) (xy 1.25 -0.65) (xy 1.25 0.65) (xy -1.25 0.65)
			)
			(stroke
				(width 0.05)
				(type solid)
			)
			(fill no)
			(layer "F.CrtYd")
		)
		(fp_poly
			(pts
				(xy -0.799999 -0.45) (xy 0.799999 -0.45) (xy 0.799999 0.45) (xy -0.799999 0.45)
			)
			(stroke
				(width 0.15)
				(type solid)
			)
			(fill no)
			(layer "F.Fab")
		)
		(fp_text user "License: Apache-2.0"
			(at -1.682 5.895 0)
			(layer "F.Fab")
			(effects
				(font
					(size 0.7 0.7)
					(thickness 0.15)
				)
				(justify right top)
			)
		)
		(fp_text user "${REFERENCE}"
			(at -1.682001 3.895 0)
			(layer "F.Fab")
			(effects
				(font
					(size 0.7 0.7)
					(thickness 0.15)
				)
				(justify right top)
			)
		)
		(fp_text user "Author: Antmicro"
			(at -1.682 4.894 0)
			(layer "F.Fab")
			(effects
				(font
					(size 0.7 0.7)
					(thickness 0.15)
				)
				(justify right top)
			)
		)
		(pad "1" smd roundrect
			(at -0.7 0 180)
			(size 0.8 1.1)
			(layers "F.Cu" "F.Mask" "F.Paste")
			(roundrect_rratio 0.2)
			(net 1 "GND")
			(pintype "passive")
		)
		(pad "2" smd roundrect
			(at 0.7 0 180)
			(size 0.8 1.1)
			(layers "F.Cu" "F.Mask" "F.Paste")
			(roundrect_rratio 0.2)
			(net 491 "+5V_AON")
			(pintype "passive")
		)
	)
	(footprint "antmicro-footprints:TP_SMD_0.75mm"
		(layer "F.Cu")
		(at 182 57.16 90)
		(property "Reference" "TP61"
			(at -1.99 -0.68625 90)
			(layer "F.SilkS")
			(hide yes)
			(effects
				(font
					(size 0.7 0.7)
					(thickness 0.15)
				)
				(justify left bottom)
			)
		)
		(property "Value" "TP_0.75mm_SMD"
			(at 0 1.2 90)
			(layer "F.Fab")
			(effects
				(font
					(size 0.7 0.7)
					(thickness 0.15)
				)
				(justify left bottom)
			)
		)
		(property "Description" "SMT test point"
			(at 0 0 90)
			(layer "F.Fab")
			(hide yes)
			(effects
				(font
					(size 1.27 1.27)
					(thickness 0.15)
				)
			)
		)
		(property "MPN" ""
			(at 0 0 90)
			(unlocked yes)
			(layer "F.Fab")
			(hide yes)
			(effects
				(font
					(size 1 1)
					(thickness 0.15)
				)
			)
		)
		(property "Manufacturer" ""
			(at 0 0 90)
			(unlocked yes)
			(layer "F.Fab")
			(hide yes)
			(effects
				(font
					(size 1 1)
					(thickness 0.15)
				)
			)
		)
		(property "Author" "Antmicro"
			(at 0 0 90)
			(unlocked yes)
			(layer "F.Fab")
			(hide yes)
			(effects
				(font
					(size 1 1)
					(thickness 0.15)
				)
			)
		)
		(property "License" "Apache-2.0"
			(at 0 0 90)
			(unlocked yes)
			(layer "F.Fab")
			(hide yes)
			(effects
				(font
					(size 1 1)
					(thickness 0.15)
				)
			)
		)
		(sheetname "/Power/")
		(sheetfile "power.kicad_sch")
		(attr exclude_from_pos_files exclude_from_bom)
		(fp_circle
			(center 0 0)
			(end 0.475 0)
			(stroke
				(width 0.05)
				(type default)
			)
			(fill no)
			(layer "F.CrtYd")
		)
		(fp_text user "Author: Antmicro"
			(at -0.4 3.901 90)
			(layer "F.Fab")
			(effects
				(font
					(size 0.7 0.7)
					(thickness 0.15)
				)
				(justify left bottom)
			)
		)
		(fp_text user "License: Apache-2.0"
			(at -0.4 5.101 90)
			(layer "F.Fab")
			(effects
				(font
					(size 0.7 0.7)
					(thickness 0.15)
				)
				(justify left bottom)
			)
		)
		(fp_text user "${REFERENCE}"
			(at -0.4 2.7 90)
			(layer "F.Fab")
			(effects
				(font
					(size 0.7 0.7)
					(thickness 0.15)
				)
				(justify left bottom)
			)
		)
		(pad "1" smd circle
			(at 0 0 90)
			(size 0.75 0.75)
			(layers "F.Cu" "F.Mask")
			(net 904 "+20V")
			(pinfunction "1")
			(pintype "passive")
		)
	)
	(footprint "antmicro-footprints:R_0402_1005Metric"
		(layer "F.Cu")
		(at 83.5 55.5)
		(descr "Resistor SMD 0402")
		(tags "resistor SMD 0402")
		(property "Reference" "R287"
			(at -1.5 -0.6 0)
			(layer "F.SilkS")
			(effects
				(font
					(size 0.7 0.7)
					(thickness 0.15)
				)
				(justify left bottom)
			)
		)
		(property "Value" "R_10k_0402"
			(at -1.011843 1.772047 0)
			(layer "F.Fab")
			(effects
				(font
					(size 0.7 0.7)
					(thickness 0.15)
				)
				(justify left bottom)
			)
		)
		(property "Datasheet" "https://www.bourns.com/docs/product-datasheets/cr.pdf"
			(at 0 0 0)
			(layer "F.Fab")
			(hide yes)
			(effects
				(font
					(size 1.27 1.27)
					(thickness 0.15)
				)
			)
		)
		(property "Description" "SMD Chip Resistor, 10 kohm, ± 1%, 62.5 mW, 0402 [1005 Metric], Thick Film, General Purpose"
			(at 0 0 0)
			(layer "F.Fab")
			(hide yes)
			(effects
				(font
					(size 1.27 1.27)
					(thickness 0.15)
				)
			)
		)
		(property "MPN" "CR0402-FX-1002GLF"
			(at 0 0 0)
			(unlocked yes)
			(layer "F.Fab")
			(hide yes)
			(effects
				(font
					(size 1 1)
					(thickness 0.15)
				)
			)
		)
		(property "Manufacturer" "Bourns"
			(at 0 0 0)
			(unlocked yes)
			(layer "F.Fab")
			(hide yes)
			(effects
				(font
					(size 1 1)
					(thickness 0.15)
				)
			)
		)
		(property "License" "Apache-2.0"
			(at 0 0 0)
			(unlocked yes)
			(layer "F.Fab")
			(hide yes)
			(effects
				(font
					(size 1 1)
					(thickness 0.15)
				)
			)
		)
		(property "Author" "Antmicro"
			(at 0 0 0)
			(unlocked yes)
			(layer "F.Fab")
			(hide yes)
			(effects
				(font
					(size 1 1)
					(thickness 0.15)
				)
			)
		)
		(property "Val" "10k"
			(at 0 0 0)
			(unlocked yes)
			(layer "F.Fab")
			(hide yes)
			(effects
				(font
					(size 1 1)
					(thickness 0.15)
				)
			)
		)
		(property "Tolerance" "1%"
			(at 0 0 0)
			(unlocked yes)
			(layer "F.Fab")
			(hide yes)
			(effects
				(font
					(size 1 1)
					(thickness 0.15)
				)
			)
		)
		(sheetname "/SoM_Power/")
		(sheetfile "som_power.kicad_sch")
		(attr smd)
		(fp_rect
			(start -0.925 -0.47)
			(end 0.925 0.47)
			(stroke
				(width 0.05)
				(type default)
			)
			(fill no)
			(layer "F.CrtYd")
		)
		(fp_rect
			(start -0.5 -0.25)
			(end 0.5 0.25)
			(stroke
				(width 0.15)
				(type solid)
			)
			(fill no)
			(layer "F.Fab")
		)
		(fp_text user "License: Apache-2.0"
			(at -0.95 5.169 0)
			(layer "F.Fab")
			(effects
				(font
					(size 0.7 0.7)
					(thickness 0.15)
				)
				(justify left bottom)
			)
		)
		(fp_text user "${REFERENCE}"
			(at -0.95 3.168 0)
			(layer "F.Fab")
			(effects
				(font
					(size 0.7 0.7)
					(thickness 0.15)
				)
				(justify left bottom)
			)
		)
		(fp_text user "Author: Antmicro"
			(at -0.95 4.169 0)
			(layer "F.Fab")
			(effects
				(font
					(size 0.7 0.7)
					(thickness 0.15)
				)
				(justify left bottom)
			)
		)
		(pad "1" smd roundrect
			(at -0.48 0)
			(size 0.59 0.64)
			(layers "F.Cu" "F.Mask" "F.Paste")
			(roundrect_rratio 0.25)
			(net 683 "/SoM_Power/~{SOM_PRSNT}")
			(pintype "passive")
		)
		(pad "2" smd roundrect
			(at 0.48 0)
			(size 0.59 0.64)
			(layers "F.Cu" "F.Mask" "F.Paste")
			(roundrect_rratio 0.25)
			(net 491 "+5V_AON")
			(pintype "passive")
		)
	)
	(footprint "antmicro-footprints:R_0402_1005Metric"
		(layer "F.Cu")
		(at 138.7 111.72 -90)
		(descr "Resistor SMD 0402")
		(tags "resistor SMD 0402")
		(property "Reference" "R403"
			(at 0.78 0.4 90)
			(layer "F.SilkS")
			(effects
				(font
					(size 0.7 0.7)
					(thickness 0.15)
				)
				(justify right top)
			)
		)
		(property "Value" "R_0R_0402"
			(at -1.011843 1.772047 90)
			(layer "F.Fab")
			(effects
				(font
					(size 0.7 0.7)
					(thickness 0.15)
				)
				(justify right top)
			)
		)
		(property "Datasheet" "https://industrial.panasonic.com/cdbs/www-data/pdf/RDA0000/AOA0000C301.pdf"
			(at 0 0 90)
			(layer "F.Fab")
			(hide yes)
			(effects
				(font
					(size 1.27 1.27)
					(thickness 0.15)
				)
			)
		)
		(property "Description" "SMD Chip Resistor, Jumper, 0 ohm, 100 mW, 0402 [1005 Metric], Thick Film, General Purpose"
			(at 0 0 90)
			(layer "F.Fab")
			(hide yes)
			(effects
				(font
					(size 1.27 1.27)
					(thickness 0.15)
				)
			)
		)
		(property "MPN" "ERJ2GE0R00X"
			(at 0 0 270)
			(unlocked yes)
			(layer "F.Fab")
			(hide yes)
			(effects
				(font
					(size 1 1)
					(thickness 0.15)
				)
			)
		)
		(property "Manufacturer" "Panasonic"
			(at 0 0 270)
			(unlocked yes)
			(layer "F.Fab")
			(hide yes)
			(effects
				(font
					(size 1 1)
					(thickness 0.15)
				)
			)
		)
		(property "License" "Apache-2.0"
			(at 0 0 270)
			(unlocked yes)
			(layer "F.Fab")
			(hide yes)
			(effects
				(font
					(size 1 1)
					(thickness 0.15)
				)
			)
		)
		(property "Author" "Antmicro"
			(at 0 0 270)
			(unlocked yes)
			(layer "F.Fab")
			(hide yes)
			(effects
				(font
					(size 1 1)
					(thickness 0.15)
				)
			)
		)
		(property "Val" "0R"
			(at 0 0 270)
			(unlocked yes)
			(layer "F.Fab")
			(hide yes)
			(effects
				(font
					(size 1 1)
					(thickness 0.15)
				)
			)
		)
		(property "Tolerance" "~"
			(at 0 0 270)
			(unlocked yes)
			(layer "F.Fab")
			(hide yes)
			(effects
				(font
					(size 1 1)
					(thickness 0.15)
				)
			)
		)
		(property "Current" "1A"
			(at 0 0 270)
			(unlocked yes)
			(layer "F.Fab")
			(hide yes)
			(effects
				(font
					(size 1 1)
					(thickness 0.15)
				)
			)
		)
		(sheetname "/Peripherals/")
		(sheetfile "peripherals.kicad_sch")
		(attr smd)
		(fp_rect
			(start -0.925 -0.47)
			(end 0.925 0.47)
			(stroke
				(width 0.05)
				(type default)
			)
			(fill no)
			(layer "F.CrtYd")
		)
		(fp_rect
			(start -0.5 -0.25)
			(end 0.5 0.25)
			(stroke
				(width 0.15)
				(type solid)
			)
			(fill no)
			(layer "F.Fab")
		)
		(fp_text user "${REFERENCE}"
			(at -0.95 3.168 90)
			(layer "F.Fab")
			(effects
				(font
					(size 0.7 0.7)
					(thickness 0.15)
				)
				(justify right top)
			)
		)
		(fp_text user "Author: Antmicro"
			(at -0.95 4.169 90)
			(layer "F.Fab")
			(effects
				(font
					(size 0.7 0.7)
					(thickness 0.15)
				)
				(justify right top)
			)
		)
		(fp_text user "License: Apache-2.0"
			(at -0.95 5.169 90)
			(layer "F.Fab")
			(effects
				(font
					(size 0.7 0.7)
					(thickness 0.15)
				)
				(justify right top)
			)
		)
		(pad "1" smd roundrect
			(at -0.48 0 270)
			(size 0.59 0.64)
			(layers "F.Cu" "F.Mask" "F.Paste")
			(roundrect_rratio 0.25)
			(net 1316 "/Peripherals/GPIOEX_P0_4")
			(pintype "passive")
		)
		(pad "2" smd roundrect
			(at 0.48 0 270)
			(size 0.59 0.64)
			(layers "F.Cu" "F.Mask" "F.Paste")
			(roundrect_rratio 0.25)
			(net 1100 "/Peripherals/TPM_RST")
			(pintype "passive")
		)
	)
	(footprint "antmicro-footprints:TP_SMD_0.75mm"
		(layer "F.Cu")
		(at 142.9 112.2)
		(property "Reference" "TP71"
			(at 0.5 2.9 90)
			(layer "F.SilkS")
			(effects
				(font
					(size 0.7 0.7)
					(thickness 0.15)
				)
				(justify left bottom)
			)
		)
		(property "Value" "TP_0.75mm_SMD"
			(at 0 1.2 0)
			(layer "F.Fab")
			(effects
				(font
					(size 0.7 0.7)
					(thickness 0.15)
				)
				(justify left bottom)
			)
		)
		(property "Description" "SMT test point"
			(at 0 0 0)
			(layer "F.Fab")
			(hide yes)
			(effects
				(font
					(size 1.27 1.27)
					(thickness 0.15)
				)
			)
		)
		(property "MPN" ""
			(at 0 0 0)
			(unlocked yes)
			(layer "F.Fab")
			(hide yes)
			(effects
				(font
					(size 1 1)
					(thickness 0.15)
				)
			)
		)
		(property "Manufacturer" ""
			(at 0 0 0)
			(unlocked yes)
			(layer "F.Fab")
			(hide yes)
			(effects
				(font
					(size 1 1)
					(thickness 0.15)
				)
			)
		)
		(property "Author" "Antmicro"
			(at 0 0 0)
			(unlocked yes)
			(layer "F.Fab")
			(hide yes)
			(effects
				(font
					(size 1 1)
					(thickness 0.15)
				)
			)
		)
		(property "License" "Apache-2.0"
			(at 0 0 0)
			(unlocked yes)
			(layer "F.Fab")
			(hide yes)
			(effects
				(font
					(size 1 1)
					(thickness 0.15)
				)
			)
		)
		(sheetname "/Peripherals/")
		(sheetfile "peripherals.kicad_sch")
		(attr exclude_from_pos_files exclude_from_bom)
		(fp_circle
			(center 0 0)
			(end 0.475 0)
			(stroke
				(width 0.05)
				(type default)
			)
			(fill no)
			(layer "F.CrtYd")
		)
		(fp_text user "${REFERENCE}"
			(at -0.4 2.7 0)
			(layer "F.Fab")
			(effects
				(font
					(size 0.7 0.7)
					(thickness 0.15)
				)
				(justify left bottom)
			)
		)
		(fp_text user "License: Apache-2.0"
			(at -0.4 5.101 0)
			(layer "F.Fab")
			(effects
				(font
					(size 0.7 0.7)
					(thickness 0.15)
				)
				(justify left bottom)
			)
		)
		(fp_text user "Author: Antmicro"
			(at -0.4 3.901 0)
			(layer "F.Fab")
			(effects
				(font
					(size 0.7 0.7)
					(thickness 0.15)
				)
				(justify left bottom)
			)
		)
		(pad "1" smd circle
			(at 0 0)
			(size 0.75 0.75)
			(layers "F.Cu" "F.Mask")
			(net 1378 "Net-(R406-Pad2)")
			(pinfunction "1")
			(pintype "passive")
		)
	)
	(footprint "antmicro-footprints:C_0402_1005Metric"
		(layer "F.Cu")
		(at 81.1 75.8 -90)
		(descr "Capacitor SMD 0402")
		(tags "capacitor SMD 0402")
		(property "Reference" "C342"
			(at 0.9 0.4 90)
			(layer "F.SilkS")
			(effects
				(font
					(size 0.7 0.7)
					(thickness 0.15)
				)
				(justify right top)
			)
		)
		(property "Value" "C_100n_0402"
			(at -1.022927 2.155213 90)
			(layer "F.Fab")
			(effects
				(font
					(size 0.7 0.7)
					(thickness 0.15)
				)
				(justify right top)
			)
		)
		(property "Datasheet" "https://www.murata.com/products/productdetail?partno=GRM155R61H104KE14%23"
			(at 0 0 90)
			(layer "F.Fab")
			(hide yes)
			(effects
				(font
					(size 1.27 1.27)
					(thickness 0.15)
				)
			)
		)
		(property "Description" "SMD Multilayer Ceramic Capacitor, 0.1 µF, 50 V, 0402 [1005 Metric], ± 10%, X5R, GRM Series"
			(at 0 0 90)
			(layer "F.Fab")
			(hide yes)
			(effects
				(font
					(size 1.27 1.27)
					(thickness 0.15)
				)
			)
		)
		(property "Manufacturer" "Murata"
			(at 0 0 270)
			(unlocked yes)
			(layer "F.Fab")
			(hide yes)
			(effects
				(font
					(size 1 1)
					(thickness 0.15)
				)
			)
		)
		(property "MPN" "GRM155R61H104KE14D"
			(at 0 0 270)
			(unlocked yes)
			(layer "F.Fab")
			(hide yes)
			(effects
				(font
					(size 1 1)
					(thickness 0.15)
				)
			)
		)
		(property "Val" "100n"
			(at 0 0 270)
			(unlocked yes)
			(layer "F.Fab")
			(hide yes)
			(effects
				(font
					(size 1 1)
					(thickness 0.15)
				)
			)
		)
		(property "License" "Apache-2.0"
			(at 0 0 270)
			(unlocked yes)
			(layer "F.Fab")
			(hide yes)
			(effects
				(font
					(size 1 1)
					(thickness 0.15)
				)
			)
		)
		(property "Author" "Antmicro"
			(at 0 0 270)
			(unlocked yes)
			(layer "F.Fab")
			(hide yes)
			(effects
				(font
					(size 1 1)
					(thickness 0.15)
				)
			)
		)
		(property "Voltage" "50V"
			(at 0 0 270)
			(unlocked yes)
			(layer "F.Fab")
			(hide yes)
			(effects
				(font
					(size 1 1)
					(thickness 0.15)
				)
			)
		)
		(property "Dielectric" "X5R"
			(at 0 0 270)
			(unlocked yes)
			(layer "F.Fab")
			(hide yes)
			(effects
				(font
					(size 1 1)
					(thickness 0.15)
				)
			)
		)
		(sheetname "/SoM_IO2/")
		(sheetfile "som_io2.kicad_sch")
		(attr smd)
		(fp_poly
			(pts
				(xy -0.925 -0.47) (xy 0.925 -0.47) (xy 0.925 0.47) (xy -0.925 0.47)
			)
			(stroke
				(width 0.05)
				(type default)
			)
			(fill no)
			(layer "F.CrtYd")
		)
		(fp_line
			(start -0.494 0.248)
			(end -0.494 -0.25)
			(stroke
				(width 0.15)
				(type solid)
			)
			(layer "F.Fab")
		)
		(fp_line
			(start 0.504 0.248)
			(end -0.494 0.248)
			(stroke
				(width 0.15)
				(type solid)
			)
			(layer "F.Fab")
		)
		(fp_line
			(start -0.494 -0.25)
			(end 0.504 -0.25)
			(stroke
				(width 0.15)
				(type solid)
			)
			(layer "F.Fab")
		)
		(fp_line
			(start 0.504 -0.25)
			(end 0.504 0.248)
			(stroke
				(width 0.15)
				(type solid)
			)
			(layer "F.Fab")
		)
		(fp_text user "${REFERENCE}"
			(at -0.939 4.599 90)
			(layer "F.Fab")
			(effects
				(font
					(size 0.7 0.7)
					(thickness 0.15)
				)
				(justify right top)
			)
		)
		(fp_text user "License: Apache-2.0"
			(at -0.939 5.799 90)
			(layer "F.Fab")
			(effects
				(font
					(size 0.7 0.7)
					(thickness 0.15)
				)
				(justify right top)
			)
		)
		(fp_text user "Author: Antmicro"
			(at -0.939 3.399 90)
			(layer "F.Fab")
			(effects
				(font
					(size 0.7 0.7)
					(thickness 0.15)
				)
				(justify right top)
			)
		)
		(pad "1" smd roundrect
			(at -0.48 0 270)
			(size 0.59 0.64)
			(layers "F.Cu" "F.Mask" "F.Paste")
			(roundrect_rratio 0.25)
			(net 1262 "/SoM_IO2/DP2.AUX_C+")
			(pintype "passive")
		)
		(pad "2" smd roundrect
			(at 0.48 0 270)
			(size 0.59 0.64)
			(layers "F.Cu" "F.Mask" "F.Paste")
			(roundrect_rratio 0.25)
			(net 572 "/Expansion connector/DP2.AUX+")
			(pintype "passive")
		)
	)
	(footprint "antmicro-footprints:LED_0603_1608Metric_G"
		(layer "F.Cu")
		(at 235.540532 121.71 180)
		(descr "LED SMD 0603 Green")
		(tags "LED SMD 0603 Green")
		(property "Reference" "D47"
			(at -1.059468 -0.799999 0)
			(layer "F.SilkS")
			(effects
				(font
					(size 0.7 0.7)
					(thickness 0.15)
				)
				(justify right top)
			)
		)
		(property "Value" "LED_G_0603_LTST-C190GKT"
			(at -0.001 1.599 0)
			(layer "F.Fab")
			(effects
				(font
					(size 0.7 0.7)
					(thickness 0.15)
				)
				(justify right top)
			)
		)
		(property "Datasheet" "https://media.digikey.com/pdf/Data%20Sheets/Lite-On%20PDFs/LTST-C190GKT.pdf"
			(at 0 0 0)
			(layer "F.Fab")
			(hide yes)
			(effects
				(font
					(size 1.27 1.27)
					(thickness 0.15)
				)
			)
		)
		(property "Description" "LED, Green, SMD, 0603, 20 mA, 2.1 V, 569 nm"
			(at 0 0 0)
			(layer "F.Fab")
			(hide yes)
			(effects
				(font
					(size 1.27 1.27)
					(thickness 0.15)
				)
			)
		)
		(property "MPN" "LTST-C190GKT"
			(at 0 0 180)
			(unlocked yes)
			(layer "F.Fab")
			(hide yes)
			(effects
				(font
					(size 1 1)
					(thickness 0.15)
				)
			)
		)
		(property "Manufacturer" "Lite-On"
			(at 0 0 180)
			(unlocked yes)
			(layer "F.Fab")
			(hide yes)
			(effects
				(font
					(size 1 1)
					(thickness 0.15)
				)
			)
		)
		(property "Author" "Antmicro"
			(at 0 0 180)
			(unlocked yes)
			(layer "F.Fab")
			(hide yes)
			(effects
				(font
					(size 1 1)
					(thickness 0.15)
				)
			)
		)
		(property "License" "Apache-2.0"
			(at 0 0 180)
			(unlocked yes)
			(layer "F.Fab")
			(hide yes)
			(effects
				(font
					(size 1 1)
					(thickness 0.15)
				)
			)
		)
		(property "Color" "Green"
			(at 0 0 180)
			(unlocked yes)
			(layer "F.Fab")
			(hide yes)
			(effects
				(font
					(size 1 1)
					(thickness 0.15)
				)
			)
		)
		(sheetname "/USB Hub/")
		(sheetfile "usb_hub.kicad_sch")
		(attr smd)
		(fp_line
			(start 0.22 0.35)
			(end -0.22 0.35)
			(stroke
				(width 0.15)
				(type solid)
			)
			(layer "F.SilkS")
		)
		(fp_line
			(start 0.22 -0.35)
			(end -0.22 -0.35)
			(stroke
				(width 0.15)
				(type solid)
			)
			(layer "F.SilkS")
		)
		(fp_line
			(start 0.105328 0.201008)
			(end 0.105329 -0.198992)
			(stroke
				(width 0.1)
				(type solid)
			)
			(layer "F.SilkS")
		)
		(fp_line
			(start 0.105328 0.201008)
			(end -0.094672 0.001008)
			(stroke
				(width 0.1)
				(type solid)
			)
			(layer "F.SilkS")
		)
		(fp_line
			(start 0.105328 0.001008)
			(end 0.240001 0.001)
			(stroke
				(width 0.1)
				(type solid)
			)
			(layer "F.SilkS")
		)
		(fp_line
			(start -0.094672 0.201008)
			(end -0.094672 -0.198992)
			(stroke
				(width 0.1)
				(type solid)
			)
			(layer "F.SilkS")
		)
		(fp_line
			(start -0.094672 0.001008)
			(end 0.105329 -0.198992)
			(stroke
				(width 0.1)
				(type solid)
			)
			(layer "F.SilkS")
		)
		(fp_line
			(start -0.094672 0.001008)
			(end -0.24 0.001008)
			(stroke
				(width 0.1)
				(type solid)
			)
			(layer "F.SilkS")
		)
		(fp_line
			(start -1.18 -0.319)
			(end -1.18 0.321)
			(stroke
				(width 0.15)
				(type solid)
			)
			(layer "F.SilkS")
		)
		(fp_poly
			(pts
				(xy 1.25 0.65) (xy -1.25 0.65) (xy -1.25 -0.65) (xy 1.25 -0.65)
			)
			(stroke
				(width 0.05)
				(type solid)
			)
			(fill no)
			(layer "F.CrtYd")
		)
		(fp_line
			(start 0.599 0)
			(end 0.200999 0)
			(stroke
				(width 0.15)
				(type solid)
			)
			(layer "F.Fab")
		)
		(fp_line
			(start 0.201 0.2)
			(end 0.200999 0)
			(stroke
				(width 0.15)
				(type solid)
			)
			(layer "F.Fab")
		)
		(fp_line
			(start 0.201 -0.202)
			(end -0.101 0)
			(stroke
				(width 0.15)
				(type solid)
			)
			(layer "F.Fab")
		)
		(fp_line
			(start 0.200999 0)
			(end 0.201 -0.202)
			(stroke
				(width 0.15)
				(type solid)
			)
			(layer "F.Fab")
		)
		(fp_line
			(start -0.101 0)
			(end 0.201 0.2)
			(stroke
				(width 0.15)
				(type solid)
			)
			(layer "F.Fab")
		)
		(fp_line
			(start -0.199 0.2)
			(end -0.199 0.1)
			(stroke
				(width 0.15)
				(type solid)
			)
			(layer "F.Fab")
		)
		(fp_line
			(start -0.199 0)
			(end -0.597 0)
			(stroke
				(width 0.15)
				(type solid)
			)
			(layer "F.Fab")
		)
		(fp_line
			(start -0.199 -0.202)
			(end -0.199 0.1)
			(stroke
				(width 0.15)
				(type solid)
			)
			(layer "F.Fab")
		)
		(fp_poly
			(pts
				(xy 0.848 0.4) (xy -0.85 0.4) (xy -0.85 -0.402) (xy 0.848 -0.401999)
			)
			(stroke
				(width 0.15)
				(type solid)
			)
			(fill no)
			(layer "F.Fab")
		)
		(fp_text user "License: Apache-2.0"
			(at -1.4224 3.599 0)
			(layer "F.Fab")
			(effects
				(font
					(size 0.7 0.7)
					(thickness 0.15)
				)
				(justify right top)
			)
		)
		(fp_text user "${REFERENCE}"
			(at -1.4224 5.999 0)
			(layer "F.Fab")
			(effects
				(font
					(size 0.7 0.7)
					(thickness 0.15)
				)
				(justify right top)
			)
		)
		(fp_text user "Author: Antmicro"
			(at -1.4224 4.799 0)
			(layer "F.Fab")
			(effects
				(font
					(size 0.7 0.7)
					(thickness 0.15)
				)
				(justify right top)
			)
		)
		(pad "1" smd roundrect
			(at -0.7 0)
			(size 0.8 1)
			(layers "F.Cu" "F.Mask" "F.Paste")
			(roundrect_rratio 0.2)
			(net 1 "GND")
			(pinfunction "C")
			(pintype "passive")
		)
		(pad "2" smd roundrect
			(at 0.7 0)
			(size 0.8 1)
			(layers "F.Cu" "F.Mask" "F.Paste")
			(roundrect_rratio 0.2)
			(net 1389 "Net-(D47-A)")
			(pinfunction "A")
			(pintype "passive")
		)
	)
	(footprint "antmicro-footprints:C_0402_1005Metric"
		(layer "F.Cu")
		(at 91.1 91.7)
		(descr "Capacitor SMD 0402")
		(tags "capacitor SMD 0402")
		(property "Reference" "C347"
			(at 1.1 0.500001 0)
			(layer "F.SilkS")
			(effects
				(font
					(size 0.7 0.7)
					(thickness 0.15)
				)
				(justify left bottom)
			)
		)
		(property "Value" "C_100n_0402"
			(at -1.022927 2.155213 0)
			(layer "F.Fab")
			(effects
				(font
					(size 0.7 0.7)
					(thickness 0.15)
				)
				(justify left bottom)
			)
		)
		(property "Datasheet" "https://www.murata.com/products/productdetail?partno=GRM155R61H104KE14%23"
			(at 0 0 0)
			(layer "F.Fab")
			(hide yes)
			(effects
				(font
					(size 1.27 1.27)
					(thickness 0.15)
				)
			)
		)
		(property "Description" "SMD Multilayer Ceramic Capacitor, 0.1 µF, 50 V, 0402 [1005 Metric], ± 10%, X5R, GRM Series"
			(at 0 0 0)
			(layer "F.Fab")
			(hide yes)
			(effects
				(font
					(size 1.27 1.27)
					(thickness 0.15)
				)
			)
		)
		(property "Manufacturer" "Murata"
			(at 0 0 0)
			(unlocked yes)
			(layer "F.Fab")
			(hide yes)
			(effects
				(font
					(size 1 1)
					(thickness 0.15)
				)
			)
		)
		(property "MPN" "GRM155R61H104KE14D"
			(at 0 0 0)
			(unlocked yes)
			(layer "F.Fab")
			(hide yes)
			(effects
				(font
					(size 1 1)
					(thickness 0.15)
				)
			)
		)
		(property "Val" "100n"
			(at 0 0 0)
			(unlocked yes)
			(layer "F.Fab")
			(hide yes)
			(effects
				(font
					(size 1 1)
					(thickness 0.15)
				)
			)
		)
		(property "License" "Apache-2.0"
			(at 0 0 0)
			(unlocked yes)
			(layer "F.Fab")
			(hide yes)
			(effects
				(font
					(size 1 1)
					(thickness 0.15)
				)
			)
		)
		(property "Author" "Antmicro"
			(at 0 0 0)
			(unlocked yes)
			(layer "F.Fab")
			(hide yes)
			(effects
				(font
					(size 1 1)
					(thickness 0.15)
				)
			)
		)
		(property "Voltage" "50V"
			(at 0 0 0)
			(unlocked yes)
			(layer "F.Fab")
			(hide yes)
			(effects
				(font
					(size 1 1)
					(thickness 0.15)
				)
			)
		)
		(property "Dielectric" "X5R"
			(at 0 0 0)
			(unlocked yes)
			(layer "F.Fab")
			(hide yes)
			(effects
				(font
					(size 1 1)
					(thickness 0.15)
				)
			)
		)
		(sheetname "/SoM_IO2/")
		(sheetfile "som_io2.kicad_sch")
		(attr smd)
		(fp_rect
			(start -0.925 -0.47)
			(end 0.925 0.47)
			(stroke
				(width 0.05)
				(type default)
			)
			(fill no)
			(layer "F.CrtYd")
		)
		(fp_line
			(start -0.494 -0.25)
			(end 0.504 -0.25)
			(stroke
				(width 0.15)
				(type solid)
			)
			(layer "F.Fab")
		)
		(fp_line
			(start -0.494 0.248)
			(end -0.494 -0.25)
			(stroke
				(width 0.15)
				(type solid)
			)
			(layer "F.Fab")
		)
		(fp_line
			(start 0.504 -0.25)
			(end 0.504 0.248)
			(stroke
				(width 0.15)
				(type solid)
			)
			(layer "F.Fab")
		)
		(fp_line
			(start 0.504 0.248)
			(end -0.494 0.248)
			(stroke
				(width 0.15)
				(type solid)
			)
			(layer "F.Fab")
		)
		(fp_text user "License: Apache-2.0"
			(at -0.939 5.799 0)
			(layer "F.Fab")
			(effects
				(font
					(size 0.7 0.7)
					(thickness 0.15)
				)
				(justify left bottom)
			)
		)
		(fp_text user "${REFERENCE}"
			(at -0.939 4.599 0)
			(layer "F.Fab")
			(effects
				(font
					(size 0.7 0.7)
					(thickness 0.15)
				)
				(justify left bottom)
			)
		)
		(fp_text user "Author: Antmicro"
			(at -0.939 3.399 0)
			(layer "F.Fab")
			(effects
				(font
					(size 0.7 0.7)
					(thickness 0.15)
				)
				(justify left bottom)
			)
		)
		(pad "1" smd roundrect
			(at -0.48 0)
			(size 0.59 0.64)
			(layers "F.Cu" "F.Mask" "F.Paste")
			(roundrect_rratio 0.25)
			(net 648 "/Expansion connector/DP3.TX3+")
			(pintype "passive")
		)
		(pad "2" smd roundrect
			(at 0.48 0)
			(size 0.59 0.64)
			(layers "F.Cu" "F.Mask" "F.Paste")
			(roundrect_rratio 0.25)
			(net 1267 "/SoM_IO2/DP3.TX3_C+")
			(pintype "passive")
		)
	)
	(footprint "antmicro-footprints:C_0402_1005Metric"
		(layer "F.Cu")
		(at 130.549999 60.98)
		(descr "Capacitor SMD 0402")
		(tags "capacitor SMD 0402")
		(property "Reference" "C374"
			(at 0.910001 -0.58 0)
			(layer "F.SilkS")
			(effects
				(font
					(size 0.7 0.7)
					(thickness 0.15)
				)
				(justify left bottom)
			)
		)
		(property "Value" "C_100n_0402"
			(at -1.022927 2.155213 0)
			(layer "F.Fab")
			(effects
				(font
					(size 0.7 0.7)
					(thickness 0.15)
				)
				(justify left bottom)
			)
		)
		(property "Datasheet" "https://www.murata.com/products/productdetail?partno=GRM155R61H104KE14%23"
			(at 0 0 0)
			(layer "F.Fab")
			(hide yes)
			(effects
				(font
					(size 1.27 1.27)
					(thickness 0.15)
				)
			)
		)
		(property "Description" "SMD Multilayer Ceramic Capacitor, 0.1 µF, 50 V, 0402 [1005 Metric], ± 10%, X5R, GRM Series"
			(at 0 0 0)
			(layer "F.Fab")
			(hide yes)
			(effects
				(font
					(size 1.27 1.27)
					(thickness 0.15)
				)
			)
		)
		(property "Manufacturer" "Murata"
			(at 0 0 0)
			(unlocked yes)
			(layer "F.Fab")
			(hide yes)
			(effects
				(font
					(size 1 1)
					(thickness 0.15)
				)
			)
		)
		(property "MPN" "GRM155R61H104KE14D"
			(at 0 0 0)
			(unlocked yes)
			(layer "F.Fab")
			(hide yes)
			(effects
				(font
					(size 1 1)
					(thickness 0.15)
				)
			)
		)
		(property "Val" "100n"
			(at 0 0 0)
			(unlocked yes)
			(layer "F.Fab")
			(hide yes)
			(effects
				(font
					(size 1 1)
					(thickness 0.15)
				)
			)
		)
		(property "License" "Apache-2.0"
			(at 0 0 0)
			(unlocked yes)
			(layer "F.Fab")
			(hide yes)
			(effects
				(font
					(size 1 1)
					(thickness 0.15)
				)
			)
		)
		(property "Author" "Antmicro"
			(at 0 0 0)
			(unlocked yes)
			(layer "F.Fab")
			(hide yes)
			(effects
				(font
					(size 1 1)
					(thickness 0.15)
				)
			)
		)
		(property "Voltage" "50V"
			(at 0 0 0)
			(unlocked yes)
			(layer "F.Fab")
			(hide yes)
			(effects
				(font
					(size 1 1)
					(thickness 0.15)
				)
			)
		)
		(property "Dielectric" "X5R"
			(at 0 0 0)
			(unlocked yes)
			(layer "F.Fab")
			(hide yes)
			(effects
				(font
					(size 1 1)
					(thickness 0.15)
				)
			)
		)
		(sheetname "/DCDC/")
		(sheetfile "dcdc.kicad_sch")
		(attr smd)
		(fp_poly
			(pts
				(xy -0.925 -0.47) (xy -0.925 0.47) (xy 0.925 0.47) (xy 0.925 -0.47)
			)
			(stroke
				(width 0.05)
				(type default)
			)
			(fill no)
			(layer "F.CrtYd")
		)
		(fp_line
			(start -0.494 -0.25)
			(end 0.504 -0.25)
			(stroke
				(width 0.15)
				(type solid)
			)
			(layer "F.Fab")
		)
		(fp_line
			(start -0.494 0.248)
			(end -0.494 -0.25)
			(stroke
				(width 0.15)
				(type solid)
			)
			(layer "F.Fab")
		)
		(fp_line
			(start 0.504 -0.25)
			(end 0.504 0.248)
			(stroke
				(width 0.15)
				(type solid)
			)
			(layer "F.Fab")
		)
		(fp_line
			(start 0.504 0.248)
			(end -0.494 0.248)
			(stroke
				(width 0.15)
				(type solid)
			)
			(layer "F.Fab")
		)
		(fp_text user "License: Apache-2.0"
			(at -0.939 5.799 0)
			(layer "F.Fab")
			(effects
				(font
					(size 0.7 0.7)
					(thickness 0.15)
				)
				(justify left bottom)
			)
		)
		(fp_text user "${REFERENCE}"
			(at -0.939 4.599 0)
			(layer "F.Fab")
			(effects
				(font
					(size 0.7 0.7)
					(thickness 0.15)
				)
				(justify left bottom)
			)
		)
		(fp_text user "Author: Antmicro"
			(at -0.939 3.399 0)
			(layer "F.Fab")
			(effects
				(font
					(size 0.7 0.7)
					(thickness 0.15)
				)
				(justify left bottom)
			)
		)
		(pad "1" smd roundrect
			(at -0.48 0)
			(size 0.59 0.64)
			(layers "F.Cu" "F.Mask" "F.Paste")
			(roundrect_rratio 0.25)
			(net 13 "VCC")
			(pintype "passive")
		)
		(pad "2" smd roundrect
			(at 0.48 0)
			(size 0.59 0.64)
			(layers "F.Cu" "F.Mask" "F.Paste")
			(roundrect_rratio 0.25)
			(net 1 "GND")
			(pintype "passive")
		)
	)
	(footprint "antmicro-footprints:R_0402_1005Metric"
		(layer "F.Cu")
		(at 190.6 82.4)
		(descr "Resistor SMD 0402")
		(tags "resistor SMD 0402")
		(property "Reference" "R107"
			(at -3.78 0.49 0)
			(layer "F.SilkS")
			(effects
				(font
					(size 0.7 0.7)
					(thickness 0.15)
				)
				(justify left bottom)
			)
		)
		(property "Value" "R_4k7_0402"
			(at -1.011843 1.772046 0)
			(layer "F.Fab")
			(effects
				(font
					(size 0.7 0.7)
					(thickness 0.15)
				)
				(justify left bottom)
			)
		)
		(property "Datasheet" "https://www.bourns.com/docs/product-datasheets/cr.pdf"
			(at 0 0 0)
			(layer "F.Fab")
			(hide yes)
			(effects
				(font
					(size 1.27 1.27)
					(thickness 0.15)
				)
			)
		)
		(property "Description" "SMD Chip Resistor, 4.7 kohm, ± 1%, 62.5 mW, 0402 [1005 Metric], Thick Film, General Purpose"
			(at 0 0 0)
			(layer "F.Fab")
			(hide yes)
			(effects
				(font
					(size 1.27 1.27)
					(thickness 0.15)
				)
			)
		)
		(property "Manufacturer" "Bourns"
			(at 0 0 0)
			(unlocked yes)
			(layer "F.Fab")
			(hide yes)
			(effects
				(font
					(size 1 1)
					(thickness 0.15)
				)
			)
		)
		(property "MPN" "CR0402-FX-4701GLF"
			(at 0 0 0)
			(unlocked yes)
			(layer "F.Fab")
			(hide yes)
			(effects
				(font
					(size 1 1)
					(thickness 0.15)
				)
			)
		)
		(property "Val" "4k7"
			(at 0 0 0)
			(unlocked yes)
			(layer "F.Fab")
			(hide yes)
			(effects
				(font
					(size 1 1)
					(thickness 0.15)
				)
			)
		)
		(property "License" "Apache-2.0"
			(at 0 0 0)
			(unlocked yes)
			(layer "F.Fab")
			(hide yes)
			(effects
				(font
					(size 1 1)
					(thickness 0.15)
				)
			)
		)
		(property "Author" "Antmicro"
			(at 0 0 0)
			(unlocked yes)
			(layer "F.Fab")
			(hide yes)
			(effects
				(font
					(size 1 1)
					(thickness 0.15)
				)
			)
		)
		(property "Tolerance" "1%"
			(at 0 0 0)
			(unlocked yes)
			(layer "F.Fab")
			(hide yes)
			(effects
				(font
					(size 1 1)
					(thickness 0.15)
				)
			)
		)
		(sheetname "/USB Debug, PD/")
		(sheetfile "usb_debug_pd.kicad_sch")
		(attr smd)
		(fp_poly
			(pts
				(xy -0.925 -0.47) (xy -0.925 0.47) (xy 0.925 0.47) (xy 0.925 -0.47)
			)
			(stroke
				(width 0.05)
				(type default)
			)
			(fill no)
			(layer "F.CrtYd")
		)
		(fp_poly
			(pts
				(xy -0.5 -0.25) (xy -0.5 0.25) (xy 0.5 0.25) (xy 0.5 -0.25)
			)
			(stroke
				(width 0.15)
				(type solid)
			)
			(fill no)
			(layer "F.Fab")
		)
		(fp_text user "License: Apache-2.0"
			(at -0.949999 5.169 0)
			(layer "F.Fab")
			(effects
				(font
					(size 0.7 0.7)
					(thickness 0.15)
				)
				(justify left bottom)
			)
		)
		(fp_text user "Author: Antmicro"
			(at -0.95 4.169 0)
			(layer "F.Fab")
			(effects
				(font
					(size 0.7 0.7)
					(thickness 0.15)
				)
				(justify left bottom)
			)
		)
		(fp_text user "${REFERENCE}"
			(at -0.95 3.168 0)
			(layer "F.Fab")
			(effects
				(font
					(size 0.7 0.7)
					(thickness 0.15)
				)
				(justify left bottom)
			)
		)
		(pad "1" smd roundrect
			(at -0.48 0)
			(size 0.59 0.64)
			(layers "F.Cu" "F.Mask" "F.Paste")
			(roundrect_rratio 0.25)
			(net 2 "+3V3")
			(pintype "passive")
		)
		(pad "2" smd roundrect
			(at 0.48 0)
			(size 0.59 0.64)
			(layers "F.Cu" "F.Mask" "F.Paste")
			(roundrect_rratio 0.25)
			(net 950 "/USB Debug, PD/PDC_I2C2_SDA")
			(pintype "passive")
		)
	)
	(footprint "antmicro-footprints:UQFN-24_2x4mm_P0.4mm_Texas_RJW0024A"
		(layer "F.Cu")
		(at 152.5 99)
		(property "Reference" "U5"
			(at -2.9 -1.5 0)
			(unlocked yes)
			(layer "F.SilkS")
			(effects
				(font
					(size 0.7 0.7)
					(thickness 0.15)
				)
				(justify left bottom)
			)
		)
		(property "Value" "SN74AXC8T245_UQFN"
			(at 0 3.4 0)
			(unlocked yes)
			(layer "F.Fab")
			(effects
				(font
					(size 0.7 0.7)
					(thickness 0.15)
				)
				(justify left bottom)
			)
		)
		(property "Datasheet" "https://www.ti.com/lit/ds/symlink/sn74axc8t245.pdf?ts=1702327536011"
			(at 0 0 0)
			(layer "F.Fab")
			(hide yes)
			(effects
				(font
					(size 1.27 1.27)
					(thickness 0.15)
				)
			)
		)
		(property "Description" "8-bit dual-supply bus transceiver"
			(at 0 0 0)
			(layer "F.Fab")
			(hide yes)
			(effects
				(font
					(size 1.27 1.27)
					(thickness 0.15)
				)
			)
		)
		(property "MPN" "SN74AXC8T245RJWR"
			(at 0 0 0)
			(unlocked yes)
			(layer "F.Fab")
			(hide yes)
			(effects
				(font
					(size 1 1)
					(thickness 0.15)
				)
			)
		)
		(property "Manufacturer" "Texas Instruments"
			(at 0 0 0)
			(unlocked yes)
			(layer "F.Fab")
			(hide yes)
			(effects
				(font
					(size 1 1)
					(thickness 0.15)
				)
			)
		)
		(property "Author" "Antmicro"
			(at 0 0 0)
			(unlocked yes)
			(layer "F.Fab")
			(hide yes)
			(effects
				(font
					(size 1 1)
					(thickness 0.15)
				)
			)
		)
		(property "License" "Apache-2.0"
			(at 0 0 0)
			(unlocked yes)
			(layer "F.Fab")
			(hide yes)
			(effects
				(font
					(size 1 1)
					(thickness 0.15)
				)
			)
		)
		(sheetname "/SoM_IO/")
		(sheetfile "som_io.kicad_sch")
		(attr smd)
		(fp_line
			(start -1.200001 2)
			(end -1.2 2.2)
			(stroke
				(width 0.15)
				(type solid)
			)
			(layer "F.SilkS")
		)
		(fp_line
			(start -1.2 2.2)
			(end -0.499999 2.2)
			(stroke
				(width 0.15)
				(type solid)
			)
			(layer "F.SilkS")
		)
		(fp_line
			(start -1 -2.2)
			(end -0.499999 -2.2)
			(stroke
				(width 0.15)
				(type solid)
			)
			(layer "F.SilkS")
		)
		(fp_line
			(start 0.499999 -2.2)
			(end 1.2 -2.2)
			(stroke
				(width 0.15)
				(type solid)
			)
			(layer "F.SilkS")
		)
		(fp_line
			(start 0.499999 2.2)
			(end 1.2 2.2)
			(stroke
				(width 0.15)
				(type solid)
			)
			(layer "F.SilkS")
		)
		(fp_line
			(start 1.2 -2.2)
			(end 1.200001 -2)
			(stroke
				(width 0.15)
				(type solid)
			)
			(layer "F.SilkS")
		)
		(fp_line
			(start 1.200001 2)
			(end 1.2 2.2)
			(stroke
				(width 0.15)
				(type solid)
			)
			(layer "F.SilkS")
		)
		(fp_circle
			(center -1.2 -2.05)
			(end -1.15 -2.05)
			(stroke
				(width 0.15)
				(type solid)
			)
			(fill yes)
			(layer "F.SilkS")
		)
		(fp_poly
			(pts
				(xy -1.200001 -0.95) (xy -1.2 -1.05) (xy -1.199 -1.06) (xy -1.196 -1.069) (xy -1.192 -1.078) (xy -1.185 -1.084999)
				(xy -1.178 -1.092) (xy -1.169 -1.096) (xy -1.16 -1.099) (xy -1.15 -1.1) (xy -0.3 -1.099999) (xy -0.29 -1.099)
				(xy -0.281 -1.096) (xy -0.272 -1.092001) (xy -0.265 -1.085) (xy -0.258 -1.078001) (xy -0.254 -1.069)
				(xy -0.251 -1.06) (xy -0.25 -1.05) (xy -0.25 -0.95) (xy -0.251 -0.94) (xy -0.254001 -0.931) (xy -0.258 -0.922)
				(xy -0.265 -0.915) (xy -0.272 -0.908) (xy -0.281 -0.904001) (xy -0.29 -0.901) (xy -0.3 -0.9) (xy -1.15 -0.9)
				(xy -1.16 -0.901) (xy -1.169 -0.904) (xy -1.178 -0.908) (xy -1.185 -0.915) (xy -1.192 -0.922) (xy -1.196 -0.931)
				(xy -1.199 -0.939999)
			)
			(stroke
				(width 0)
				(type solid)
			)
			(fill yes)
			(layer "F.Paste")
		)
		(fp_poly
			(pts
				(xy -1.200001 0.65) (xy -1.2 0.55) (xy -1.199 0.54) (xy -1.196 0.531) (xy -1.192 0.522) (xy -1.185001 0.515)
				(xy -1.178 0.508) (xy -1.169 0.504) (xy -1.159999 0.501) (xy -1.15 0.5) (xy -0.3 0.499999) (xy -0.289999 0.501)
				(xy -0.281 0.504) (xy -0.272 0.508) (xy -0.265 0.515) (xy -0.258 0.522) (xy -0.254 0.531) (xy -0.251 0.54)
				(xy -0.25 0.55) (xy -0.25 0.65) (xy -0.251 0.66) (xy -0.254001 0.669) (xy -0.258 0.678) (xy -0.265 0.685)
				(xy -0.272 0.692) (xy -0.281 0.696) (xy -0.29 0.699001) (xy -0.3 0.7) (xy -1.15 0.7) (xy -1.16 0.699001)
				(xy -1.169 0.696) (xy -1.178 0.692) (xy -1.185 0.685001) (xy -1.192 0.678) (xy -1.196 0.669) (xy -1.199001 0.66)
			)
			(stroke
				(width 0)
				(type solid)
			)
			(fill yes)
			(layer "F.Paste")
		)
		(fp_poly
			(pts
				(xy -1.200001 1.85) (xy -1.2 1.75) (xy -1.199 1.74) (xy -1.196 1.731) (xy -1.192 1.722) (xy -1.185 1.715001)
				(xy -1.178 1.708) (xy -1.169 1.704) (xy -1.16 1.701001) (xy -1.15 1.7) (xy -0.600001 1.7) (xy -0.59 1.701001)
				(xy -0.581 1.704) (xy -0.572 1.707999) (xy -0.565 1.715) (xy -0.558 1.721999) (xy -0.554 1.731)
				(xy -0.551 1.74) (xy -0.55 1.75) (xy -0.55 1.85) (xy -0.551 1.86) (xy -0.554 1.869) (xy -0.558 1.878)
				(xy -0.565 1.885) (xy -0.572 1.892) (xy -0.581 1.895999) (xy -0.59 1.899) (xy -0.6 1.9) (xy -1.15 1.9)
				(xy -1.16 1.899) (xy -1.169 1.896) (xy -1.178 1.892) (xy -1.185 1.885) (xy -1.192 1.878) (xy -1.196 1.869)
				(xy -1.199 1.860001)
			)
			(stroke
				(width 0)
				(type solid)
			)
			(fill yes)
			(layer "F.Paste")
		)
		(fp_poly
			(pts
				(xy -1.2 -1.75) (xy -1.200001 -1.85) (xy -1.199 -1.860001) (xy -1.196 -1.869) (xy -1.192 -1.878)
				(xy -1.185 -1.885) (xy -1.178 -1.892) (xy -1.169 -1.896) (xy -1.16 -1.899) (xy -1.15 -1.9) (xy -0.6 -1.9)
				(xy -0.59 -1.899) (xy -0.581 -1.895999) (xy -0.572 -1.892) (xy -0.565 -1.885) (xy -0.558 -1.878)
				(xy -0.554 -1.869) (xy -0.551 -1.86) (xy -0.55 -1.85) (xy -0.55 -1.75) (xy -0.551 -1.74) (xy -0.554 -1.731)
				(xy -0.558 -1.721999) (xy -0.565 -1.715) (xy -0.572 -1.707999) (xy -0.581 -1.704) (xy -0.59 -1.701001)
				(xy -0.600001 -1.7) (xy -1.15 -1.7) (xy -1.16 -1.701001) (xy -1.169 -1.704) (xy -1.178 -1.708) (xy -1.185 -1.715001)
				(xy -1.192 -1.722) (xy -1.196 -1.731) (xy -1.199 -1.74)
			)
			(stroke
				(width 0)
				(type solid)
			)
			(fill yes)
			(layer "F.Paste")
		)
		(fp_poly
			(pts
				(xy -1.2 -1.35) (xy -1.2 -1.45) (xy -1.199 -1.46) (xy -1.196 -1.469) (xy -1.192 -1.478) (xy -1.185 -1.485)
				(xy -1.178 -1.492) (xy -1.169 -1.496) (xy -1.16 -1.499) (xy -1.15 -1.5) (xy -0.6 -1.5) (xy -0.59 -1.499)
				(xy -0.581 -1.496) (xy -0.572 -1.492) (xy -0.565 -1.485) (xy -0.558 -1.478) (xy -0.554 -1.469) (xy -0.551 -1.46)
				(xy -0.55 -1.45) (xy -0.55 -1.35) (xy -0.551 -1.34) (xy -0.554 -1.331) (xy -0.558 -1.322) (xy -0.565 -1.315)
				(xy -0.572 -1.308) (xy -0.581 -1.304) (xy -0.59 -1.301) (xy -0.6 -1.3) (xy -1.15 -1.3) (xy -1.16 -1.301)
				(xy -1.169 -1.304) (xy -1.178 -1.308) (xy -1.185 -1.315) (xy -1.192 -1.322) (xy -1.196 -1.331) (xy -1.199 -1.34)
			)
			(stroke
				(width 0)
				(type solid)
			)
			(fill yes)
			(layer "F.Paste")
		)
		(fp_poly
			(pts
				(xy -1.2 -0.55) (xy -1.200001 -0.65) (xy -1.199001 -0.66) (xy -1.196 -0.669) (xy -1.192 -0.678)
				(xy -1.185 -0.685001) (xy -1.178 -0.692) (xy -1.169 -0.696) (xy -1.16 -0.699001) (xy -1.15 -0.7)
				(xy -0.3 -0.7) (xy -0.29 -0.699001) (xy -0.281 -0.696) (xy -0.272 -0.692) (xy -0.265 -0.685) (xy -0.258 -0.678)
				(xy -0.254001 -0.669) (xy -0.251 -0.66) (xy -0.25 -0.65) (xy -0.25 -0.55) (xy -0.251 -0.54) (xy -0.254 -0.531)
				(xy -0.258 -0.522) (xy -0.265 -0.515) (xy -0.272 -0.508) (xy -0.281 -0.504) (xy -0.289999 -0.501)
				(xy -0.3 -0.499999) (xy -1.15 -0.5) (xy -1.159999 -0.501) (xy -1.169 -0.504) (xy -1.178 -0.508)
				(xy -1.185001 -0.515) (xy -1.192 -0.522) (xy -1.196 -0.531) (xy -1.199 -0.54)
			)
			(stroke
				(width 0)
				(type solid)
			)
			(fill yes)
			(layer "F.Paste")
		)
		(fp_poly
			(pts
				(xy -1.2 -0.15) (xy -1.2 -0.25) (xy -1.199 -0.26) (xy -1.196 -0.269) (xy -1.192 -0.278) (xy -1.185 -0.285)
				(xy -1.178 -0.292) (xy -1.169 -0.296) (xy -1.16 -0.299) (xy -1.15 -0.3) (xy -0.3 -0.3) (xy -0.29 -0.299)
				(xy -0.281 -0.296001) (xy -0.272 -0.292) (xy -0.265 -0.285) (xy -0.258 -0.278) (xy -0.254 -0.269)
				(xy -0.251 -0.26) (xy -0.25 -0.25) (xy -0.25 -0.15) (xy -0.251 -0.14) (xy -0.254 -0.131) (xy -0.258001 -0.122)
				(xy -0.265 -0.115) (xy -0.272001 -0.108) (xy -0.281 -0.104) (xy -0.29 -0.101) (xy -0.3 -0.1) (xy -1.15 -0.1)
				(xy -1.16 -0.101) (xy -1.169 -0.104) (xy -1.178 -0.108) (xy -1.185 -0.115) (xy -1.192 -0.122) (xy -1.196 -0.131)
				(xy -1.199 -0.14)
			)
			(stroke
				(width 0)
				(type solid)
			)
			(fill yes)
			(layer "F.Paste")
		)
		(fp_poly
			(pts
				(xy -1.2 0.25) (xy -1.2 0.15) (xy -1.199 0.14) (xy -1.196 0.131) (xy -1.192 0.122) (xy -1.185 0.115)
				(xy -1.178 0.108) (xy -1.169 0.104) (xy -1.16 0.101) (xy -1.15 0.1) (xy -0.3 0.1) (xy -0.29 0.101)
				(xy -0.281 0.104) (xy -0.272001 0.108) (xy -0.265 0.115) (xy -0.258001 0.122) (xy -0.254 0.131)
				(xy -0.251 0.14) (xy -0.25 0.15) (xy -0.25 0.25) (xy -0.251 0.26) (xy -0.254 0.269) (xy -0.258 0.278)
				(xy -0.265 0.285) (xy -0.272 0.292) (xy -0.281 0.296001) (xy -0.29 0.299) (xy -0.3 0.3) (xy -1.15 0.3)
				(xy -1.16 0.299) (xy -1.169 0.296) (xy -1.178 0.292) (xy -1.185 0.285) (xy -1.192 0.278) (xy -1.196 0.269)
				(xy -1.199 0.26)
			)
			(stroke
				(width 0)
				(type solid)
			)
			(fill yes)
			(layer "F.Paste")
		)
		(fp_poly
			(pts
				(xy -1.2 1.05) (xy -1.200001 0.95) (xy -1.199 0.939999) (xy -1.196 0.931) (xy -1.192 0.922) (xy -1.185 0.915)
				(xy -1.178 0.908) (xy -1.169 0.904) (xy -1.16 0.901) (xy -1.15 0.9) (xy -0.3 0.9) (xy -0.29 0.901)
				(xy -0.281 0.904001) (xy -0.272 0.908) (xy -0.265 0.915) (xy -0.258 0.922) (xy -0.254001 0.931)
				(xy -0.251 0.94) (xy -0.25 0.95) (xy -0.25 1.05) (xy -0.251 1.06) (xy -0.254 1.069) (xy -0.258 1.078001)
				(xy -0.265 1.085) (xy -0.272 1.092001) (xy -0.281 1.096) (xy -0.29 1.099) (xy -0.3 1.099999) (xy -1.15 1.1)
				(xy -1.16 1.099) (xy -1.169 1.096) (xy -1.178 1.092) (xy -1.185 1.084999) (xy -1.192 1.078) (xy -1.196 1.069)
				(xy -1.199 1.06)
			)
			(stroke
				(width 0)
				(type solid)
			)
			(fill yes)
			(layer "F.Paste")
		)
		(fp_poly
			(pts
				(xy -1.2 1.45) (xy -1.2 1.35) (xy -1.199 1.34) (xy -1.196 1.331) (xy -1.192 1.322) (xy -1.185 1.315)
				(xy -1.178 1.308) (xy -1.169 1.304) (xy -1.16 1.301) (xy -1.15 1.3) (xy -0.6 1.3) (xy -0.59 1.301)
				(xy -0.581 1.304) (xy -0.572 1.308) (xy -0.565 1.315) (xy -0.558 1.322) (xy -0.554 1.331) (xy -0.551 1.34)
				(xy -0.55 1.35) (xy -0.55 1.45) (xy -0.551 1.46) (xy -0.554 1.469) (xy -0.558 1.478) (xy -0.565 1.485)
				(xy -0.572 1.492) (xy -0.581 1.496) (xy -0.59 1.499) (xy -0.6 1.5) (xy -1.15 1.5) (xy -1.16 1.499)
				(xy -1.169 1.496) (xy -1.178 1.492) (xy -1.185 1.485) (xy -1.192 1.478) (xy -1.196 1.469) (xy -1.199 1.46)
			)
			(stroke
				(width 0)
				(type solid)
			)
			(fill yes)
			(layer "F.Paste")
		)
		(fp_poly
			(pts
				(xy -0.25 1.5) (xy -0.15 1.5) (xy -0.14 1.501) (xy -0.131 1.504001) (xy -0.122 1.508) (xy -0.115 1.515)
				(xy -0.108 1.522) (xy -0.104001 1.531) (xy -0.101 1.54) (xy -0.1 1.55) (xy -0.1 2.15) (xy -0.101 2.16)
				(xy -0.104 2.169001) (xy -0.108 2.178) (xy -0.115 2.185) (xy -0.122 2.192) (xy -0.130999 2.196)
				(xy -0.14 2.199) (xy -0.15 2.2) (xy -0.25 2.2) (xy -0.26 2.199) (xy -0.269 2.196) (xy -0.278 2.192)
				(xy -0.285 2.185) (xy -0.292 2.178) (xy -0.296 2.169) (xy -0.299 2.16) (xy -0.3 2.150001) (xy -0.300001 1.55)
				(xy -0.298999 1.54) (xy -0.296 1.531) (xy -0.292 1.522) (xy -0.285 1.515) (xy -0.278 1.508) (xy -0.269 1.504)
				(xy -0.26 1.501)
			)
			(stroke
				(width 0)
				(type solid)
			)
			(fill yes)
			(layer "F.Paste")
		)
		(fp_poly
			(pts
				(xy -0.15 -1.5) (xy -0.25 -1.5) (xy -0.26 -1.501) (xy -0.269 -1.504) (xy -0.278 -1.508) (xy -0.285 -1.515)
				(xy -0.292 -1.522) (xy -0.296 -1.531) (xy -0.298999 -1.54) (xy -0.300001 -1.55) (xy -0.3 -2.150001)
				(xy -0.299 -2.16) (xy -0.296 -2.169) (xy -0.292 -2.178) (xy -0.285 -2.185) (xy -0.278 -2.192) (xy -0.269 -2.196)
				(xy -0.26 -2.199) (xy -0.25 -2.2) (xy -0.15 -2.2) (xy -0.14 -2.199) (xy -0.130999 -2.196) (xy -0.122 -2.192)
				(xy -0.115 -2.185) (xy -0.108 -2.178) (xy -0.104 -2.169001) (xy -0.101 -2.16) (xy -0.1 -2.15) (xy -0.1 -1.55)
				(xy -0.101 -1.54) (xy -0.104001 -1.531) (xy -0.108 -1.522) (xy -0.115 -1.515) (xy -0.122 -1.508)
				(xy -0.131 -1.504001) (xy -0.14 -1.501)
			)
			(stroke
				(width 0)
				(type solid)
			)
			(fill yes)
			(layer "F.Paste")
		)
		(fp_poly
			(pts
				(xy 0.15 1.5) (xy 0.25 1.5) (xy 0.26 1.501) (xy 0.269 1.504) (xy 0.278 1.508) (xy 0.285 1.515) (xy 0.292 1.522)
				(xy 0.296 1.531) (xy 0.298999 1.54) (xy 0.300001 1.55) (xy 0.3 2.150001) (xy 0.299 2.16) (xy 0.296 2.169)
				(xy 0.292 2.178) (xy 0.285 2.185) (xy 0.278 2.192) (xy 0.269 2.196) (xy 0.26 2.199) (xy 0.25 2.2)
				(xy 0.15 2.2) (xy 0.14 2.199) (xy 0.130999 2.196) (xy 0.122 2.192) (xy 0.115 2.185) (xy 0.108 2.178)
				(xy 0.104 2.169001) (xy 0.101 2.16) (xy 0.1 2.15) (xy 0.1 1.55) (xy 0.101 1.54) (xy 0.104001 1.531)
				(xy 0.108 1.522) (xy 0.115 1.515) (xy 0.122 1.508) (xy 0.131 1.504001) (xy 0.14 1.501)
			)
			(stroke
				(width 0)
				(type solid)
			)
			(fill yes)
			(layer "F.Paste")
		)
		(fp_poly
			(pts
				(xy 0.25 -1.5) (xy 0.15 -1.5) (xy 0.14 -1.501) (xy 0.131 -1.504001) (xy 0.122 -1.508) (xy 0.115 -1.515)
				(xy 0.108 -1.522) (xy 0.104001 -1.531) (xy 0.101 -1.54) (xy 0.1 -1.55) (xy 0.1 -2.15) (xy 0.101 -2.16)
				(xy 0.104 -2.169001) (xy 0.108 -2.178) (xy 0.115 -2.185) (xy 0.122 -2.192) (xy 0.130999 -2.196)
				(xy 0.14 -2.199) (xy 0.15 -2.2) (xy 0.25 -2.2) (xy 0.26 -2.199) (xy 0.269 -2.196) (xy 0.278 -2.192)
				(xy 0.285 -2.185) (xy 0.292 -2.178) (xy 0.296 -2.169) (xy 0.299 -2.16) (xy 0.3 -2.150001) (xy 0.300001 -1.55)
				(xy 0.298999 -1.54) (xy 0.296 -1.531) (xy 0.292 -1.522) (xy 0.285 -1.515) (xy 0.278 -1.508) (xy 0.269 -1.504)
				(xy 0.26 -1.501)
			)
			(stroke
				(width 0)
				(type solid)
			)
			(fill yes)
			(layer "F.Paste")
		)
		(fp_poly
			(pts
				(xy 1.2 -1.45) (xy 1.2 -1.35) (xy 1.199 -1.34) (xy 1.196 -1.331) (xy 1.192 -1.322) (xy 1.185 -1.315)
				(xy 1.178 -1.308) (xy 1.169 -1.304) (xy 1.16 -1.301) (xy 1.15 -1.3) (xy 0.6 -1.3) (xy 0.59 -1.301)
				(xy 0.581 -1.304) (xy 0.572 -1.308) (xy 0.565 -1.315) (xy 0.558 -1.322) (xy 0.554 -1.331) (xy 0.551 -1.34)
				(xy 0.55 -1.35) (xy 0.55 -1.45) (xy 0.551 -1.46) (xy 0.554 -1.469) (xy 0.558 -1.478) (xy 0.565 -1.485)
				(xy 0.572 -1.492) (xy 0.581 -1.496) (xy 0.59 -1.499) (xy 0.6 -1.5) (xy 1.15 -1.5) (xy 1.16 -1.499)
				(xy 1.169 -1.496) (xy 1.178 -1.492) (xy 1.185 -1.485) (xy 1.192 -1.478) (xy 1.196 -1.469) (xy 1.199 -1.46)
			)
			(stroke
				(width 0)
				(type solid)
			)
			(fill yes)
			(layer "F.Paste")
		)
		(fp_poly
			(pts
				(xy 1.2 -1.05) (xy 1.200001 -0.95) (xy 1.199 -0.939999) (xy 1.196 -0.931) (xy 1.192 -0.922) (xy 1.185 -0.915)
				(xy 1.178 -0.908) (xy 1.169 -0.904) (xy 1.16 -0.901) (xy 1.15 -0.9) (xy 0.3 -0.9) (xy 0.29 -0.901)
				(xy 0.281 -0.904001) (xy 0.272 -0.908) (xy 0.265 -0.915) (xy 0.258 -0.922) (xy 0.254001 -0.931)
				(xy 0.251 -0.94) (xy 0.25 -0.95) (xy 0.25 -1.05) (xy 0.251 -1.06) (xy 0.254 -1.069) (xy 0.258 -1.078001)
				(xy 0.265 -1.085) (xy 0.272 -1.092001) (xy 0.281 -1.096) (xy 0.29 -1.099) (xy 0.3 -1.099999) (xy 1.15 -1.1)
				(xy 1.16 -1.099) (xy 1.169 -1.096) (xy 1.178 -1.092) (xy 1.185 -1.084999) (xy 1.192 -1.078) (xy 1.196 -1.069)
				(xy 1.199 -1.06)
			)
			(stroke
				(width 0)
				(type solid)
			)
			(fill yes)
			(layer "F.Paste")
		)
		(fp_poly
			(pts
				(xy 1.2 -0.25) (xy 1.2 -0.15) (xy 1.199 -0.14) (xy 1.196 -0.131) (xy 1.192 -0.122) (xy 1.185 -0.115)
				(xy 1.178 -0.108) (xy 1.169 -0.104) (xy 1.16 -0.101) (xy 1.15 -0.1) (xy 0.3 -0.1) (xy 0.29 -0.101)
				(xy 0.281 -0.104) (xy 0.272001 -0.108) (xy 0.265 -0.115) (xy 0.258001 -0.122) (xy 0.254 -0.131)
				(xy 0.251 -0.14) (xy 0.25 -0.15) (xy 0.25 -0.25) (xy 0.251 -0.26) (xy 0.254 -0.269) (xy 0.258 -0.278)
				(xy 0.265 -0.285) (xy 0.272 -0.292) (xy 0.281 -0.296001) (xy 0.29 -0.299) (xy 0.3 -0.3) (xy 1.15 -0.3)
				(xy 1.16 -0.299) (xy 1.169 -0.296) (xy 1.178 -0.292) (xy 1.185 -0.285) (xy 1.192 -0.278) (xy 1.196 -0.269)
				(xy 1.199 -0.26)
			)
			(stroke
				(width 0)
				(type solid)
			)
			(fill yes)
			(layer "F.Paste")
		)
		(fp_poly
			(pts
				(xy 1.2 0.15) (xy 1.2 0.25) (xy 1.199 0.26) (xy 1.196 0.269) (xy 1.192 0.278) (xy 1.185 0.285) (xy 1.178 0.292)
				(xy 1.169 0.296) (xy 1.16 0.299) (xy 1.15 0.3) (xy 0.3 0.3) (xy 0.29 0.299) (xy 0.281 0.296001)
				(xy 0.272 0.292) (xy 0.265 0.285) (xy 0.258 0.278) (xy 0.254 0.269) (xy 0.251 0.26) (xy 0.25 0.25)
				(xy 0.25 0.15) (xy 0.251 0.14) (xy 0.254 0.131) (xy 0.258001 0.122) (xy 0.265 0.115) (xy 0.272001 0.108)
				(xy 0.281 0.104) (xy 0.29 0.101) (xy 0.3 0.1) (xy 1.15 0.1) (xy 1.16 0.101) (xy 1.169 0.104) (xy 1.178 0.108)
				(xy 1.185 0.115) (xy 1.192 0.122) (xy 1.196 0.131) (xy 1.199 0.14)
			)
			(stroke
				(width 0)
				(type solid)
			)
			(fill yes)
			(layer "F.Paste")
		)
		(fp_poly
			(pts
				(xy 1.2 0.55) (xy 1.200001 0.65) (xy 1.199001 0.66) (xy 1.196 0.669) (xy 1.192 0.678) (xy 1.185 0.685001)
				(xy 1.178 0.692) (xy 1.169 0.696) (xy 1.16 0.699001) (xy 1.15 0.7) (xy 0.3 0.7) (xy 0.29 0.699001)
				(xy 0.281 0.696) (xy 0.272 0.692) (xy 0.265 0.685) (xy 0.258 0.678) (xy 0.254001 0.669) (xy 0.251 0.66)
				(xy 0.25 0.65) (xy 0.25 0.55) (xy 0.251 0.54) (xy 0.254 0.531) (xy 0.258 0.522) (xy 0.265 0.515)
				(xy 0.272 0.508) (xy 0.281 0.504) (xy 0.289999 0.501) (xy 0.3 0.499999) (xy 1.15 0.5) (xy 1.159999 0.501)
				(xy 1.169 0.504) (xy 1.178 0.508) (xy 1.185001 0.515) (xy 1.192 0.522) (xy 1.196 0.531) (xy 1.199 0.54)
			)
			(stroke
				(width 0)
				(type solid)
			)
			(fill yes)
			(layer "F.Paste")
		)
		(fp_poly
			(pts
				(xy 1.2 1.35) (xy 1.2 1.45) (xy 1.199 1.46) (xy 1.196 1.469) (xy 1.192 1.478) (xy 1.185 1.485) (xy 1.178 1.492)
				(xy 1.169 1.496) (xy 1.16 1.499) (xy 1.15 1.5) (xy 0.6 1.5) (xy 0.59 1.499) (xy 0.581 1.496) (xy 0.572 1.492)
				(xy 0.565 1.485) (xy 0.558 1.478) (xy 0.554 1.469) (xy 0.551 1.46) (xy 0.55 1.45) (xy 0.55 1.35)
				(xy 0.551 1.34) (xy 0.554 1.331) (xy 0.558 1.322) (xy 0.565 1.315) (xy 0.572 1.308) (xy 0.581 1.304)
				(xy 0.59 1.301) (xy 0.6 1.3) (xy 1.15 1.3) (xy 1.16 1.301) (xy 1.169 1.304) (xy 1.178 1.308) (xy 1.185 1.315)
				(xy 1.192 1.322) (xy 1.196 1.331) (xy 1.199 1.34)
			)
			(stroke
				(width 0)
				(type solid)
			)
			(fill yes)
			(layer "F.Paste")
		)
		(fp_poly
			(pts
				(xy 1.2 1.75) (xy 1.200001 1.85) (xy 1.199 1.860001) (xy 1.196 1.869) (xy 1.192 1.878) (xy 1.185 1.885)
				(xy 1.178 1.892) (xy 1.169 1.896) (xy 1.16 1.899) (xy 1.15 1.9) (xy 0.6 1.9) (xy 0.59 1.899) (xy 0.581 1.895999)
				(xy 0.572 1.892) (xy 0.565 1.885) (xy 0.558 1.878) (xy 0.554 1.869) (xy 0.551 1.86) (xy 0.55 1.85)
				(xy 0.55 1.75) (xy 0.551 1.74) (xy 0.554 1.731) (xy 0.558 1.721999) (xy 0.565 1.715) (xy 0.572 1.707999)
				(xy 0.581 1.704) (xy 0.59 1.701001) (xy 0.600001 1.7) (xy 1.15 1.7) (xy 1.16 1.701001) (xy 1.169 1.704)
				(xy 1.178 1.708) (xy 1.185 1.715001) (xy 1.192 1.722) (xy 1.196 1.731) (xy 1.199 1.74)
			)
			(stroke
				(width 0)
				(type solid)
			)
			(fill yes)
			(layer "F.Paste")
		)
		(fp_poly
			(pts
				(xy 1.200001 -1.85) (xy 1.2 -1.75) (xy 1.199 -1.74) (xy 1.196 -1.731) (xy 1.192 -1.722) (xy 1.185 -1.715001)
				(xy 1.178 -1.708) (xy 1.169 -1.704) (xy 1.16 -1.701001) (xy 1.15 -1.7) (xy 0.600001 -1.7) (xy 0.59 -1.701001)
				(xy 0.581 -1.704) (xy 0.572 -1.707999) (xy 0.565 -1.715) (xy 0.558 -1.721999) (xy 0.554 -1.731)
				(xy 0.551 -1.74) (xy 0.55 -1.75) (xy 0.55 -1.85) (xy 0.551 -1.86) (xy 0.554 -1.869) (xy 0.558 -1.878)
				(xy 0.565 -1.885) (xy 0.572 -1.892) (xy 0.581 -1.895999) (xy 0.59 -1.899) (xy 0.6 -1.9) (xy 1.15 -1.9)
				(xy 1.16 -1.899) (xy 1.169 -1.896) (xy 1.178 -1.892) (xy 1.185 -1.885) (xy 1.192 -1.878) (xy 1.196 -1.869)
				(xy 1.199 -1.860001)
			)
			(stroke
				(width 0)
				(type solid)
			)
			(fill yes)
			(layer "F.Paste")
		)
		(fp_poly
			(pts
				(xy 1.200001 -0.65) (xy 1.2 -0.55) (xy 1.199 -0.54) (xy 1.196 -0.531) (xy 1.192 -0.522) (xy 1.185001 -0.515)
				(xy 1.178 -0.508) (xy 1.169 -0.504) (xy 1.159999 -0.501) (xy 1.15 -0.5) (xy 0.3 -0.499999) (xy 0.289999 -0.501)
				(xy 0.281 -0.504) (xy 0.272 -0.508) (xy 0.265 -0.515) (xy 0.258 -0.522) (xy 0.254 -0.531) (xy 0.251 -0.54)
				(xy 0.25 -0.55) (xy 0.25 -0.65) (xy 0.251 -0.66) (xy 0.254001 -0.669) (xy 0.258 -0.678) (xy 0.265 -0.685)
				(xy 0.272 -0.692) (xy 0.281 -0.696) (xy 0.29 -0.699001) (xy 0.3 -0.7) (xy 1.15 -0.7) (xy 1.16 -0.699001)
				(xy 1.169 -0.696) (xy 1.178 -0.692) (xy 1.185 -0.685001) (xy 1.192 -0.678) (xy 1.196 -0.669) (xy 1.199001 -0.66)
			)
			(stroke
				(width 0)
				(type solid)
			)
			(fill yes)
			(layer "F.Paste")
		)
		(fp_poly
			(pts
				(xy 1.200001 0.95) (xy 1.2 1.05) (xy 1.199 1.06) (xy 1.196 1.069) (xy 1.192 1.078) (xy 1.185 1.084999)
				(xy 1.178 1.092) (xy 1.169 1.096) (xy 1.16 1.099) (xy 1.15 1.1) (xy 0.3 1.099999) (xy 0.29 1.099)
				(xy 0.281 1.096) (xy 0.272 1.092001) (xy 0.265 1.085) (xy 0.258 1.078001) (xy 0.254 1.069) (xy 0.251 1.06)
				(xy 0.25 1.05) (xy 0.25 0.95) (xy 0.251 0.94) (xy 0.254001 0.931) (xy 0.258 0.922) (xy 0.265 0.915)
				(xy 0.272 0.908) (xy 0.281 0.904001) (xy 0.29 0.901) (xy 0.3 0.9) (xy 1.15 0.9) (xy 1.16 0.901)
				(xy 1.169 0.904) (xy 1.178 0.908) (xy 1.185 0.915) (xy 1.192 0.922) (xy 1.196 0.931) (xy 1.199 0.939999)
			)
			(stroke
				(width 0)
				(type solid)
			)
			(fill yes)
			(layer "F.Paste")
		)
		(fp_poly
			(pts
				(xy -1.3 -2.3) (xy 1.3 -2.3) (xy 1.3 2.3) (xy -1.3 2.3)
			)
			(stroke
				(width 0.05)
				(type solid)
			)
			(fill no)
			(layer "F.CrtYd")
		)
		(fp_line
			(start -1.05 -2.05)
			(end 1.05 -2.05)
			(stroke
				(width 0.15)
				(type solid)
			)
			(layer "F.Fab")
		)
		(fp_line
			(start -1.05 2.05)
			(end -1.05 -2.05)
			(stroke
				(width 0.15)
				(type solid)
			)
			(layer "F.Fab")
		)
		(fp_line
			(start -1.05 2.05)
			(end 1.05 2.05)
			(stroke
				(width 0.15)
				(type solid)
			)
			(layer "F.Fab")
		)
		(fp_line
			(start 1.05 2.05)
			(end 1.05 -2.05)
			(stroke
				(width 0.15)
				(type solid)
			)
			(layer "F.Fab")
		)
		(fp_circle
			(center -0.5 -1.5)
			(end -0.2 -1.5)
			(stroke
				(width 0.15)
				(type solid)
			)
			(fill no)
			(layer "F.Fab")
		)
		(fp_text user "${REFERENCE}"
			(at -1.65 4.7 0)
			(unlocked yes)
			(layer "F.Fab")
			(effects
				(font
					(size 0.7 0.7)
					(thickness 0.15)
				)
				(justify left bottom)
			)
		)
		(fp_text user "Author: Antmicro"
			(at -1.65 5.9 0)
			(layer "F.Fab")
			(effects
				(font
					(size 0.7 0.7)
					(thickness 0.15)
				)
				(justify left bottom)
			)
		)
		(fp_text user "License: Apache-2.0"
			(at -1.65 7.1 0)
			(layer "F.Fab")
			(effects
				(font
					(size 0.7 0.7)
					(thickness 0.15)
				)
				(justify left bottom)
			)
		)
		(pad "1" smd rect
			(at -0.85 -1.8)
			(size 0.700001 0.2)
			(layers "F.Cu" "F.Mask")
			(net 11 "+1V8")
			(pinfunction "DIR1")
			(pintype "input")
		)
		(pad "2" smd rect
			(at -0.85 -1.4)
			(size 0.700001 0.2)
			(layers "F.Cu" "F.Mask")
			(net 1 "GND")
			(pinfunction "A1")
			(pintype "bidirectional")
		)
		(pad "3" smd rect
			(at -0.7 -1)
			(size 1 0.2)
			(layers "F.Cu" "F.Mask")
			(net 906 "/SoM_IO/M2_E_W_DIS_1_1V8")
			(pinfunction "A2")
			(pintype "bidirectional")
		)
		(pad "4" smd rect
			(at -0.7 -0.6)
			(size 1 0.2)
			(layers "F.Cu" "F.Mask")
			(net 878 "/SoM_IO/M2_E_W_DIS_2_1V8")
			(pinfunction "A3")
			(pintype "bidirectional")
		)
		(pad "5" smd rect
			(at -0.7 -0.2)
			(size 1 0.2)
			(layers "F.Cu" "F.Mask")
			(net 496 "/SoM_IO/UART3_DEBUG_TX_1V8")
			(pinfunction "A4")
			(pintype "bidirectional")
		)
		(pad "6" smd rect
			(at -0.7 0.2)
			(size 1 0.2)
			(layers "F.Cu" "F.Mask")
			(net 494 "/SoM_IO/UART3_DEBUG_RX_1V8")
			(pinfunction "A5")
			(pintype "bidirectional")
		)
		(pad "7" smd rect
			(at -0.7 0.6)
			(size 1 0.2)
			(layers "F.Cu" "F.Mask")
			(net 580 "/SoM_IO/USBC1_FLG_1V8")
			(pinfunction "A6")
			(pintype "bidirectional")
		)
		(pad "8" smd rect
			(at -0.7 1)
			(size 1 0.2)
			(layers "F.Cu" "F.Mask")
			(net 1292 "/SoM_IO/GPIO_EXP_IRQ_1V8")
			(pinfunction "A7")
			(pintype "bidirectional")
		)
		(pad "9" smd rect
			(at -0.85 1.4)
			(size 0.700001 0.2)
			(layers "F.Cu" "F.Mask")
			(net 1339 "unconnected-(U5-A8-Pad9)")
			(pinfunction "A8")
			(pintype "bidirectional+no_connect")
		)
		(pad "10" smd rect
			(at -0.85 1.8)
			(size 0.700001 0.2)
			(layers "F.Cu" "F.Mask")
			(net 11 "+1V8")
			(pinfunction "DIR2")
			(pintype "input")
		)
		(pad "11" smd rect
			(at -0.199999 1.825 90)
			(size 0.750001 0.2)
			(layers "F.Cu" "F.Mask")
			(net 1 "GND")
			(pinfunction "GND")
			(pintype "power_in")
		)
		(pad "12" smd rect
			(at 0.199999 1.825 90)
			(size 0.750001 0.2)
			(layers "F.Cu" "F.Mask")
			(net 1 "GND")
			(pinfunction "GND")
			(pintype "passive")
		)
		(pad "13" smd rect
			(at 0.85 1.8)
			(size 0.700001 0.2)
			(layers "F.Cu" "F.Mask")
			(net 1 "GND")
			(pinfunction "B8")
			(pintype "bidirectional")
		)
		(pad "14" smd rect
			(at 0.85 1.4)
			(size 0.700001 0.2)
			(layers "F.Cu" "F.Mask")
			(net 1309 "/Peripherals/GPIO_EXP_IRQ")
			(pinfunction "B7")
			(pintype "bidirectional")
		)
		(pad "15" smd rect
			(at 0.7 1)
			(size 1 0.2)
			(layers "F.Cu" "F.Mask")
			(net 962 "/SoM_IO/USBC1_FLG")
			(pinfunction "B6")
			(pintype "bidirectional")
		)
		(pad "16" smd rect
			(at 0.7 0.6)
			(size 1 0.2)
			(layers "F.Cu" "F.Mask")
			(net 960 "/SoM_IO/UART3_DEBUG.RX")
			(pinfunction "B5")
			(pintype "bidirectional")
		)
		(pad "17" smd rect
			(at 0.7 0.2)
			(size 1 0.2)
			(layers "F.Cu" "F.Mask")
			(net 959 "/SoM_IO/UART3_DEBUG.TX")
			(pinfunction "B4")
			(pintype "bidirectional")
		)
		(pad "18" smd rect
			(at 0.7 -0.2)
			(size 1 0.2)
			(layers "F.Cu" "F.Mask")
			(net 1167 "/M.2/M2_E.W_DIS_2")
			(pinfunction "B3")
			(pintype "bidirectional")
		)
		(pad "19" smd rect
			(at 0.7 -0.6)
			(size 1 0.2)
			(layers "F.Cu" "F.Mask")
			(net 1113 "/M.2/M2_E.W_DIS_1")
			(pinfunction "B2")
			(pintype "bidirectional")
		)
		(pad "20" smd rect
			(at 0.7 -1)
			(size 1 0.2)
			(layers "F.Cu" "F.Mask")
			(net 1338 "unconnected-(U5-B1-Pad20)")
			(pinfunction "B1")
			(pintype "bidirectional+no_connect")
		)
		(pad "21" smd rect
			(at 0.85 -1.4)
			(size 0.700001 0.2)
			(layers "F.Cu" "F.Mask")
			(net 1 "GND")
			(pinfunction "OE_N")
			(pintype "input")
		)
		(pad "22" smd rect
			(at 0.85 -1.8)
			(size 0.700001 0.2)
			(layers "F.Cu" "F.Mask")
			(net 2 "+3V3")
			(pinfunction "VCCB")
			(pintype "power_in")
		)
		(pad "23" smd rect
			(at 0.199999 -1.825 90)
			(size 0.750001 0.2)
			(layers "F.Cu" "F.Mask")
			(net 2 "+3V3")
			(pinfunction "VCCB")
			(pintype "passive")
		)
		(pad "24" smd rect
			(at -0.199999 -1.825 90)
			(size 0.750001 0.2)
			(layers "F.Cu" "F.Mask")
			(net 11 "+1V8")
			(pinfunction "VCCA")
			(pintype "power_in")
		)
	)
	(footprint "antmicro-footprints:R_0402_1005Metric"
		(layer "F.Cu")
		(at 180.859468 139.33 -90)
		(descr "Resistor SMD 0402")
		(tags "resistor SMD 0402")
		(property "Reference" "R13"
			(at -5.83 -2.340532 90)
			(layer "F.SilkS")
			(effects
				(font
					(size 0.7 0.7)
					(thickness 0.15)
				)
				(justify right top)
			)
		)
		(property "Value" "R_499k_0402"
			(at -1.011843 1.772047 90)
			(layer "F.Fab")
			(effects
				(font
					(size 0.7 0.7)
					(thickness 0.15)
				)
				(justify right top)
			)
		)
		(property "Datasheet" "https://www.mouser.com/datasheet/2/54/cr-1858361.pdf"
			(at 0 0 90)
			(layer "F.Fab")
			(hide yes)
			(effects
				(font
					(size 1.27 1.27)
					(thickness 0.15)
				)
			)
		)
		(property "Description" "SMD Chip Resistor, 499 kohm, ± 1%, 63 mW, 0402 [1005 Metric], Thick Film, General Purpose"
			(at 0 0 90)
			(layer "F.Fab")
			(hide yes)
			(effects
				(font
					(size 1.27 1.27)
					(thickness 0.15)
				)
			)
		)
		(property "MPN" "CR0402-FX-4993GLF"
			(at 0 0 270)
			(unlocked yes)
			(layer "F.Fab")
			(hide yes)
			(effects
				(font
					(size 1 1)
					(thickness 0.15)
				)
			)
		)
		(property "Manufacturer" "Bourns"
			(at 0 0 270)
			(unlocked yes)
			(layer "F.Fab")
			(hide yes)
			(effects
				(font
					(size 1 1)
					(thickness 0.15)
				)
			)
		)
		(property "License" "Apache-2.0"
			(at 0 0 270)
			(unlocked yes)
			(layer "F.Fab")
			(hide yes)
			(effects
				(font
					(size 1 1)
					(thickness 0.15)
				)
			)
		)
		(property "Author" "Antmicro"
			(at 0 0 270)
			(unlocked yes)
			(layer "F.Fab")
			(hide yes)
			(effects
				(font
					(size 1 1)
					(thickness 0.15)
				)
			)
		)
		(property "Val" "499k"
			(at 0 0 270)
			(unlocked yes)
			(layer "F.Fab")
			(hide yes)
			(effects
				(font
					(size 1 1)
					(thickness 0.15)
				)
			)
		)
		(property "Tolerance" "1%"
			(at 0 0 270)
			(unlocked yes)
			(layer "F.Fab")
			(hide yes)
			(effects
				(font
					(size 1 1)
					(thickness 0.15)
				)
			)
		)
		(sheetname "/DCDC/")
		(sheetfile "dcdc.kicad_sch")
		(attr smd)
		(fp_rect
			(start -0.925 -0.47)
			(end 0.925 0.47)
			(stroke
				(width 0.05)
				(type default)
			)
			(fill no)
			(layer "F.CrtYd")
		)
		(fp_rect
			(start -0.5 -0.25)
			(end 0.5 0.25)
			(stroke
				(width 0.15)
				(type solid)
			)
			(fill no)
			(layer "F.Fab")
		)
		(fp_text user "License: Apache-2.0"
			(at -0.95 5.169 90)
			(layer "F.Fab")
			(effects
				(font
					(size 0.7 0.7)
					(thickness 0.15)
				)
				(justify right top)
			)
		)
		(fp_text user "Author: Antmicro"
			(at -0.95 4.169 90)
			(layer "F.Fab")
			(effects
				(font
					(size 0.7 0.7)
					(thickness 0.15)
				)
				(justify right top)
			)
		)
		(fp_text user "${REFERENCE}"
			(at -0.95 3.168 90)
			(layer "F.Fab")
			(effects
				(font
					(size 0.7 0.7)
					(thickness 0.15)
				)
				(justify right top)
			)
		)
		(pad "1" smd roundrect
			(at -0.48 0 270)
			(size 0.59 0.64)
			(layers "F.Cu" "F.Mask" "F.Paste")
			(roundrect_rratio 0.25)
			(net 1 "GND")
			(pintype "passive")
		)
		(pad "2" smd roundrect
			(at 0.48 0 270)
			(size 0.59 0.64)
			(layers "F.Cu" "F.Mask" "F.Paste")
			(roundrect_rratio 0.25)
			(net 1204 "/DCDC/12V_MODE1")
			(pintype "passive")
		)
	)
	(footprint "antmicro-footprints:R_0402_1005Metric"
		(layer "F.Cu")
		(at 196.35 85.92 -90)
		(descr "Resistor SMD 0402")
		(tags "resistor SMD 0402")
		(property "Reference" "R108"
			(at -1.71 1.46 90)
			(layer "F.SilkS")
			(effects
				(font
					(size 0.7 0.7)
					(thickness 0.15)
				)
				(justify right top)
			)
		)
		(property "Value" "R_200R_0402"
			(at -1.011843 1.772047 90)
			(layer "F.Fab")
			(effects
				(font
					(size 0.7 0.7)
					(thickness 0.15)
				)
				(justify right top)
			)
		)
		(property "Datasheet" "https://www.bourns.com/docs/product-datasheets/cr.pdf"
			(at 0 0 90)
			(layer "F.Fab")
			(hide yes)
			(effects
				(font
					(size 1.27 1.27)
					(thickness 0.15)
				)
			)
		)
		(property "Description" "SMD Chip Resistor, 200 ohm, ± 1%, 62.5 mW, 0402 [1005 Metric], Thick Film, General Purpose"
			(at 0 0 90)
			(layer "F.Fab")
			(hide yes)
			(effects
				(font
					(size 1.27 1.27)
					(thickness 0.15)
				)
			)
		)
		(property "Manufacturer" "Bourns"
			(at 0 0 270)
			(unlocked yes)
			(layer "F.Fab")
			(hide yes)
			(effects
				(font
					(size 1 1)
					(thickness 0.15)
				)
			)
		)
		(property "MPN" "CR0402-FX-2000GLF"
			(at 0 0 270)
			(unlocked yes)
			(layer "F.Fab")
			(hide yes)
			(effects
				(font
					(size 1 1)
					(thickness 0.15)
				)
			)
		)
		(property "Val" "200R"
			(at 0 0 270)
			(unlocked yes)
			(layer "F.Fab")
			(hide yes)
			(effects
				(font
					(size 1 1)
					(thickness 0.15)
				)
			)
		)
		(property "License" "Apache-2.0"
			(at 0 0 270)
			(unlocked yes)
			(layer "F.Fab")
			(hide yes)
			(effects
				(font
					(size 1 1)
					(thickness 0.15)
				)
			)
		)
		(property "Author" "Antmicro"
			(at 0 0 270)
			(unlocked yes)
			(layer "F.Fab")
			(hide yes)
			(effects
				(font
					(size 1 1)
					(thickness 0.15)
				)
			)
		)
		(property "Tolerance" "1%"
			(at 0 0 270)
			(unlocked yes)
			(layer "F.Fab")
			(hide yes)
			(effects
				(font
					(size 1 1)
					(thickness 0.15)
				)
			)
		)
		(sheetname "/USB Debug, PD/")
		(sheetfile "usb_debug_pd.kicad_sch")
		(attr smd)
		(fp_rect
			(start -0.925 -0.47)
			(end 0.925 0.47)
			(stroke
				(width 0.05)
				(type default)
			)
			(fill no)
			(layer "F.CrtYd")
		)
		(fp_rect
			(start -0.5 -0.25)
			(end 0.5 0.25)
			(stroke
				(width 0.15)
				(type solid)
			)
			(fill no)
			(layer "F.Fab")
		)
		(fp_text user "License: Apache-2.0"
			(at -0.95 5.169 90)
			(layer "F.Fab")
			(effects
				(font
					(size 0.7 0.7)
					(thickness 0.15)
				)
				(justify right top)
			)
		)
		(fp_text user "${REFERENCE}"
			(at -0.95 3.168 90)
			(layer "F.Fab")
			(effects
				(font
					(size 0.7 0.7)
					(thickness 0.15)
				)
				(justify right top)
			)
		)
		(fp_text user "Author: Antmicro"
			(at -0.95 4.169 90)
			(layer "F.Fab")
			(effects
				(font
					(size 0.7 0.7)
					(thickness 0.15)
				)
				(justify right top)
			)
		)
		(pad "1" smd roundrect
			(at -0.48 0 270)
			(size 0.59 0.64)
			(layers "F.Cu" "F.Mask" "F.Paste")
			(roundrect_rratio 0.25)
			(net 951 "/USB Debug, PD/PDC_GPIO14")
			(pintype "passive")
		)
		(pad "2" smd roundrect
			(at 0.48 0 270)
			(size 0.59 0.64)
			(layers "F.Cu" "F.Mask" "F.Paste")
			(roundrect_rratio 0.25)
			(net 533 "Net-(D18-A)")
			(pintype "passive")
		)
	)
	(footprint "antmicro-footprints:C_0402_1005Metric"
		(layer "F.Cu")
		(at 215.524132 84.282 -90)
		(descr "Capacitor SMD 0402")
		(tags "capacitor SMD 0402")
		(property "Reference" "C129"
			(at -3.682 0.324132 90)
			(layer "F.SilkS")
			(effects
				(font
					(size 0.7 0.7)
					(thickness 0.15)
				)
				(justify right top)
			)
		)
		(property "Value" "C_100n_0402"
			(at -1.022927 2.155213 90)
			(layer "F.Fab")
			(effects
				(font
					(size 0.7 0.7)
					(thickness 0.15)
				)
				(justify right top)
			)
		)
		(property "Datasheet" "https://www.murata.com/products/productdetail?partno=GRM155R61H104KE14%23"
			(at 0 0 90)
			(layer "F.Fab")
			(hide yes)
			(effects
				(font
					(size 1.27 1.27)
					(thickness 0.15)
				)
			)
		)
		(property "Description" "SMD Multilayer Ceramic Capacitor, 0.1 µF, 50 V, 0402 [1005 Metric], ± 10%, X5R, GRM Series"
			(at 0 0 90)
			(layer "F.Fab")
			(hide yes)
			(effects
				(font
					(size 1.27 1.27)
					(thickness 0.15)
				)
			)
		)
		(property "Manufacturer" "Murata"
			(at 0 0 270)
			(unlocked yes)
			(layer "F.Fab")
			(hide yes)
			(effects
				(font
					(size 1 1)
					(thickness 0.15)
				)
			)
		)
		(property "MPN" "GRM155R61H104KE14D"
			(at 0 0 270)
			(unlocked yes)
			(layer "F.Fab")
			(hide yes)
			(effects
				(font
					(size 1 1)
					(thickness 0.15)
				)
			)
		)
		(property "Val" "100n"
			(at 0 0 270)
			(unlocked yes)
			(layer "F.Fab")
			(hide yes)
			(effects
				(font
					(size 1 1)
					(thickness 0.15)
				)
			)
		)
		(property "License" "Apache-2.0"
			(at 0 0 270)
			(unlocked yes)
			(layer "F.Fab")
			(hide yes)
			(effects
				(font
					(size 1 1)
					(thickness 0.15)
				)
			)
		)
		(property "Author" "Antmicro"
			(at 0 0 270)
			(unlocked yes)
			(layer "F.Fab")
			(hide yes)
			(effects
				(font
					(size 1 1)
					(thickness 0.15)
				)
			)
		)
		(property "Voltage" "50V"
			(at 0 0 270)
			(unlocked yes)
			(layer "F.Fab")
			(hide yes)
			(effects
				(font
					(size 1 1)
					(thickness 0.15)
				)
			)
		)
		(property "Dielectric" "X5R"
			(at 0 0 270)
			(unlocked yes)
			(layer "F.Fab")
			(hide yes)
			(effects
				(font
					(size 1 1)
					(thickness 0.15)
				)
			)
		)
		(sheetname "/USB DP Alt mode/")
		(sheetfile "usb_dp.kicad_sch")
		(attr smd)
		(fp_rect
			(start -0.925 -0.47)
			(end 0.925 0.47)
			(stroke
				(width 0.05)
				(type default)
			)
			(fill no)
			(layer "F.CrtYd")
		)
		(fp_line
			(start -0.494 0.248)
			(end -0.494 -0.25)
			(stroke
				(width 0.15)
				(type solid)
			)
			(layer "F.Fab")
		)
		(fp_line
			(start 0.504 0.248)
			(end -0.494 0.248)
			(stroke
				(width 0.15)
				(type solid)
			)
			(layer "F.Fab")
		)
		(fp_line
			(start -0.494 -0.25)
			(end 0.504 -0.25)
			(stroke
				(width 0.15)
				(type solid)
			)
			(layer "F.Fab")
		)
		(fp_line
			(start 0.504 -0.25)
			(end 0.504 0.248)
			(stroke
				(width 0.15)
				(type solid)
			)
			(layer "F.Fab")
		)
		(fp_text user "License: Apache-2.0"
			(at -0.939 5.799 90)
			(layer "F.Fab")
			(effects
				(font
					(size 0.7 0.7)
					(thickness 0.15)
				)
				(justify right top)
			)
		)
		(fp_text user "${REFERENCE}"
			(at -0.939 4.599 90)
			(layer "F.Fab")
			(effects
				(font
					(size 0.7 0.7)
					(thickness 0.15)
				)
				(justify right top)
			)
		)
		(fp_text user "Author: Antmicro"
			(at -0.939 3.399 90)
			(layer "F.Fab")
			(effects
				(font
					(size 0.7 0.7)
					(thickness 0.15)
				)
				(justify right top)
			)
		)
		(pad "1" smd roundrect
			(at -0.48 0 270)
			(size 0.59 0.64)
			(layers "F.Cu" "F.Mask" "F.Paste")
			(roundrect_rratio 0.25)
			(net 324 "/SoM_IO2/USBSS1.RX-")
			(pintype "passive")
		)
		(pad "2" smd roundrect
			(at 0.48 0 270)
			(size 0.59 0.64)
			(layers "F.Cu" "F.Mask" "F.Paste")
			(roundrect_rratio 0.25)
			(net 322 "/USB DP Alt mode/USBSS1_RX_C_N")
			(pintype "passive")
		)
	)
	(footprint "antmicro-footprints:C_0402_1005Metric"
		(layer "F.Cu")
		(at 89.1 96.9)
		(descr "Capacitor SMD 0402")
		(tags "capacitor SMD 0402")
		(property "Reference" "C336"
			(at -3.82 0.45 0)
			(layer "F.SilkS")
			(effects
				(font
					(size 0.7 0.7)
					(thickness 0.15)
				)
				(justify left bottom)
			)
		)
		(property "Value" "C_100n_0402"
			(at -1.022927 2.155213 0)
			(layer "F.Fab")
			(effects
				(font
					(size 0.7 0.7)
					(thickness 0.15)
				)
				(justify left bottom)
			)
		)
		(property "Datasheet" "https://www.murata.com/products/productdetail?partno=GRM155R61H104KE14%23"
			(at 0 0 0)
			(layer "F.Fab")
			(hide yes)
			(effects
				(font
					(size 1.27 1.27)
					(thickness 0.15)
				)
			)
		)
		(property "Description" "SMD Multilayer Ceramic Capacitor, 0.1 µF, 50 V, 0402 [1005 Metric], ± 10%, X5R, GRM Series"
			(at 0 0 0)
			(layer "F.Fab")
			(hide yes)
			(effects
				(font
					(size 1.27 1.27)
					(thickness 0.15)
				)
			)
		)
		(property "Manufacturer" "Murata"
			(at 0 0 0)
			(unlocked yes)
			(layer "F.Fab")
			(hide yes)
			(effects
				(font
					(size 1 1)
					(thickness 0.15)
				)
			)
		)
		(property "MPN" "GRM155R61H104KE14D"
			(at 0 0 0)
			(unlocked yes)
			(layer "F.Fab")
			(hide yes)
			(effects
				(font
					(size 1 1)
					(thickness 0.15)
				)
			)
		)
		(property "Val" "100n"
			(at 0 0 0)
			(unlocked yes)
			(layer "F.Fab")
			(hide yes)
			(effects
				(font
					(size 1 1)
					(thickness 0.15)
				)
			)
		)
		(property "License" "Apache-2.0"
			(at 0 0 0)
			(unlocked yes)
			(layer "F.Fab")
			(hide yes)
			(effects
				(font
					(size 1 1)
					(thickness 0.15)
				)
			)
		)
		(property "Author" "Antmicro"
			(at 0 0 0)
			(unlocked yes)
			(layer "F.Fab")
			(hide yes)
			(effects
				(font
					(size 1 1)
					(thickness 0.15)
				)
			)
		)
		(property "Voltage" "50V"
			(at 0 0 0)
			(unlocked yes)
			(layer "F.Fab")
			(hide yes)
			(effects
				(font
					(size 1 1)
					(thickness 0.15)
				)
			)
		)
		(property "Dielectric" "X5R"
			(at 0 0 0)
			(unlocked yes)
			(layer "F.Fab")
			(hide yes)
			(effects
				(font
					(size 1 1)
					(thickness 0.15)
				)
			)
		)
		(sheetname "/SoM_IO2/")
		(sheetfile "som_io2.kicad_sch")
		(attr smd)
		(fp_rect
			(start -0.925 -0.47)
			(end 0.925 0.47)
			(stroke
				(width 0.05)
				(type default)
			)
			(fill no)
			(layer "F.CrtYd")
		)
		(fp_line
			(start -0.494 -0.25)
			(end 0.504 -0.25)
			(stroke
				(width 0.15)
				(type solid)
			)
			(layer "F.Fab")
		)
		(fp_line
			(start -0.494 0.248)
			(end -0.494 -0.25)
			(stroke
				(width 0.15)
				(type solid)
			)
			(layer "F.Fab")
		)
		(fp_line
			(start 0.504 -0.25)
			(end 0.504 0.248)
			(stroke
				(width 0.15)
				(type solid)
			)
			(layer "F.Fab")
		)
		(fp_line
			(start 0.504 0.248)
			(end -0.494 0.248)
			(stroke
				(width 0.15)
				(type solid)
			)
			(layer "F.Fab")
		)
		(fp_text user "${REFERENCE}"
			(at -0.939 4.599 0)
			(layer "F.Fab")
			(effects
				(font
					(size 0.7 0.7)
					(thickness 0.15)
				)
				(justify left bottom)
			)
		)
		(fp_text user "License: Apache-2.0"
			(at -0.939 5.799 0)
			(layer "F.Fab")
			(effects
				(font
					(size 0.7 0.7)
					(thickness 0.15)
				)
				(justify left bottom)
			)
		)
		(fp_text user "Author: Antmicro"
			(at -0.939 3.399 0)
			(layer "F.Fab")
			(effects
				(font
					(size 0.7 0.7)
					(thickness 0.15)
				)
				(justify left bottom)
			)
		)
		(pad "1" smd roundrect
			(at -0.48 0)
			(size 0.59 0.64)
			(layers "F.Cu" "F.Mask" "F.Paste")
			(roundrect_rratio 0.25)
			(net 756 "/Expansion connector/DP2.TX2+")
			(pintype "passive")
		)
		(pad "2" smd roundrect
			(at 0.48 0)
			(size 0.59 0.64)
			(layers "F.Cu" "F.Mask" "F.Paste")
			(roundrect_rratio 0.25)
			(net 1256 "/SoM_IO2/DP2.TX2_C+")
			(pintype "passive")
		)
	)
	(footprint "antmicro-footprints:TP_SMD_0.75mm"
		(layer "F.Cu")
		(at 69.279 61.981 90)
		(property "Reference" "TP22"
			(at 0.41 3.21 0)
			(layer "F.SilkS")
			(effects
				(font
					(size 0.7 0.7)
					(thickness 0.15)
				)
				(justify right top)
			)
		)
		(property "Value" "TP_0.75mm_SMD"
			(at 0 1.2 90)
			(layer "F.Fab")
			(effects
				(font
					(size 0.7 0.7)
					(thickness 0.15)
				)
				(justify left bottom)
			)
		)
		(property "Description" "SMT test point"
			(at 0 0 90)
			(layer "F.Fab")
			(hide yes)
			(effects
				(font
					(size 1.27 1.27)
					(thickness 0.15)
				)
			)
		)
		(property "MPN" ""
			(at 0 0 90)
			(unlocked yes)
			(layer "F.Fab")
			(hide yes)
			(effects
				(font
					(size 1 1)
					(thickness 0.15)
				)
			)
		)
		(property "Manufacturer" ""
			(at 0 0 90)
			(unlocked yes)
			(layer "F.Fab")
			(hide yes)
			(effects
				(font
					(size 1 1)
					(thickness 0.15)
				)
			)
		)
		(property "Author" "Antmicro"
			(at 0 0 90)
			(unlocked yes)
			(layer "F.Fab")
			(hide yes)
			(effects
				(font
					(size 1 1)
					(thickness 0.15)
				)
			)
		)
		(property "License" "Apache-2.0"
			(at 0 0 90)
			(unlocked yes)
			(layer "F.Fab")
			(hide yes)
			(effects
				(font
					(size 1 1)
					(thickness 0.15)
				)
			)
		)
		(sheetname "/CSI/")
		(sheetfile "csi.kicad_sch")
		(attr exclude_from_pos_files exclude_from_bom)
		(fp_circle
			(center 0 0)
			(end 0.475 0)
			(stroke
				(width 0.05)
				(type default)
			)
			(fill no)
			(layer "F.CrtYd")
		)
		(fp_text user "${REFERENCE}"
			(at -0.4 2.7 90)
			(layer "F.Fab")
			(effects
				(font
					(size 0.7 0.7)
					(thickness 0.15)
				)
				(justify left bottom)
			)
		)
		(fp_text user "Author: Antmicro"
			(at -0.4 3.901 90)
			(layer "F.Fab")
			(effects
				(font
					(size 0.7 0.7)
					(thickness 0.15)
				)
				(justify left bottom)
			)
		)
		(fp_text user "License: Apache-2.0"
			(at -0.4 5.101 90)
			(layer "F.Fab")
			(effects
				(font
					(size 0.7 0.7)
					(thickness 0.15)
				)
				(justify left bottom)
			)
		)
		(pad "1" smd circle
			(at 0 0 90)
			(size 0.75 0.75)
			(layers "F.Cu" "F.Mask")
			(net 1046 "/CSI/MUX_I2C_4_SCL")
			(pinfunction "1")
			(pintype "passive")
		)
	)
	(footprint "antmicro-footprints:C_0805_2012Metric"
		(layer "F.Cu")
		(at 162.25 73.3 -90)
		(descr "Capacitor SMD 0805")
		(tags "capacitor SMD 0805")
		(property "Reference" "C283"
			(at -4.9 0.35 90)
			(layer "F.SilkS")
			(effects
				(font
					(size 0.7 0.7)
					(thickness 0.15)
				)
				(justify right top)
			)
		)
		(property "Value" "C_22u_25V_0805"
			(at -2.055717 1.963152 90)
			(layer "F.Fab")
			(effects
				(font
					(size 0.7 0.7)
					(thickness 0.15)
				)
				(justify right top)
			)
		)
		(property "Datasheet" "https://product.samsungsem.com/mlcc/CL21A226MAYNNN.do"
			(at 0 0 90)
			(layer "F.Fab")
			(hide yes)
			(effects
				(font
					(size 1.27 1.27)
					(thickness 0.15)
				)
			)
		)
		(property "Description" "SMT Multilayer Ceramic Capacitor, 22uF, +/-20%, 25V, X5R, 0805 [2012 Metric]"
			(at 0 0 90)
			(layer "F.Fab")
			(hide yes)
			(effects
				(font
					(size 1.27 1.27)
					(thickness 0.15)
				)
			)
		)
		(property "MPN" "CL21A226MAYNNNE"
			(at 0 0 270)
			(unlocked yes)
			(layer "F.Fab")
			(hide yes)
			(effects
				(font
					(size 1 1)
					(thickness 0.15)
				)
			)
		)
		(property "Manufacturer" "Samsung Electro-Mechanics"
			(at 0 0 270)
			(unlocked yes)
			(layer "F.Fab")
			(hide yes)
			(effects
				(font
					(size 1 1)
					(thickness 0.15)
				)
			)
		)
		(property "License" "Apache-2.0"
			(at 0 0 270)
			(unlocked yes)
			(layer "F.Fab")
			(hide yes)
			(effects
				(font
					(size 1 1)
					(thickness 0.15)
				)
			)
		)
		(property "Author" "Antmicro"
			(at 0 0 270)
			(unlocked yes)
			(layer "F.Fab")
			(hide yes)
			(effects
				(font
					(size 1 1)
					(thickness 0.15)
				)
			)
		)
		(property "Val" "22u"
			(at 0 0 270)
			(unlocked yes)
			(layer "F.Fab")
			(hide yes)
			(effects
				(font
					(size 1 1)
					(thickness 0.15)
				)
			)
		)
		(property "Voltage" "25V"
			(at 0 0 270)
			(unlocked yes)
			(layer "F.Fab")
			(hide yes)
			(effects
				(font
					(size 1 1)
					(thickness 0.15)
				)
			)
		)
		(property "Dielectric" "X5R"
			(at 0 0 270)
			(unlocked yes)
			(layer "F.Fab")
			(hide yes)
			(effects
				(font
					(size 1 1)
					(thickness 0.15)
				)
			)
		)
		(property "Public" "False"
			(at 0 0 270)
			(unlocked yes)
			(layer "F.Fab")
			(hide yes)
			(effects
				(font
					(size 1 1)
					(thickness 0.15)
				)
			)
		)
		(component_classes
			(class "DCDC_20V")
		)
		(sheetname "/DCDC/")
		(sheetfile "dcdc.kicad_sch")
		(attr smd)
		(fp_line
			(start -0.3 0.7)
			(end 0.3 0.7)
			(stroke
				(width 0.15)
				(type solid)
			)
			(layer "F.SilkS")
		)
		(fp_line
			(start -0.3 -0.7)
			(end 0.3 -0.7)
			(stroke
				(width 0.15)
				(type solid)
			)
			(layer "F.SilkS")
		)
		(fp_rect
			(start 1.95 -0.9)
			(end -1.95 0.9)
			(stroke
				(width 0.05)
				(type default)
			)
			(fill no)
			(layer "F.CrtYd")
		)
		(fp_rect
			(start -0.95 -0.675)
			(end 0.95 0.675)
			(stroke
				(width 0.15)
				(type solid)
			)
			(fill no)
			(layer "F.Fab")
		)
		(fp_text user "Author: Antmicro"
			(at -1.9 5.947 90)
			(layer "F.Fab")
			(effects
				(font
					(size 0.7 0.7)
					(thickness 0.15)
				)
				(justify right top)
			)
		)
		(fp_text user "License: Apache-2.0"
			(at -1.9 4.947 90)
			(layer "F.Fab")
			(effects
				(font
					(size 0.7 0.7)
					(thickness 0.15)
				)
				(justify right top)
			)
		)
		(fp_text user "${REFERENCE}"
			(at -1.9 3.947 90)
			(layer "F.Fab")
			(effects
				(font
					(size 0.7 0.7)
					(thickness 0.15)
				)
				(justify right top)
			)
		)
		(pad "1" smd roundrect
			(at -1.1 0 270)
			(size 1.2 1.3)
			(layers "F.Cu" "F.Mask" "F.Paste")
			(roundrect_rratio 0.25)
			(net 1 "GND")
			(pintype "passive")
		)
		(pad "2" smd roundrect
			(at 1.1 0 270)
			(size 1.2 1.3)
			(layers "F.Cu" "F.Mask" "F.Paste")
			(roundrect_rratio 0.25)
			(net 1105 "/DCDC/20V_OUT")
			(pintype "passive")
		)
	)
	(footprint "antmicro-footprints:TP_SMD_0.75mm"
		(layer "F.Cu")
		(at 164.03 57.14 180)
		(property "Reference" "TP42"
			(at 1.49 0.39 90)
			(layer "F.SilkS")
			(hide yes)
			(effects
				(font
					(size 0.7 0.7)
					(thickness 0.15)
				)
				(justify right top)
			)
		)
		(property "Value" "TP_0.75mm_SMD"
			(at 0 1.2 0)
			(layer "F.Fab")
			(effects
				(font
					(size 0.7 0.7)
					(thickness 0.15)
				)
				(justify right top)
			)
		)
		(property "Description" "SMT test point"
			(at 0 0 0)
			(layer "F.Fab")
			(hide yes)
			(effects
				(font
					(size 1.27 1.27)
					(thickness 0.15)
				)
			)
		)
		(property "MPN" ""
			(at 0 0 180)
			(unlocked yes)
			(layer "F.Fab")
			(hide yes)
			(effects
				(font
					(size 1 1)
					(thickness 0.15)
				)
			)
		)
		(property "Manufacturer" ""
			(at 0 0 180)
			(unlocked yes)
			(layer "F.Fab")
			(hide yes)
			(effects
				(font
					(size 1 1)
					(thickness 0.15)
				)
			)
		)
		(property "Author" "Antmicro"
			(at 0 0 180)
			(unlocked yes)
			(layer "F.Fab")
			(hide yes)
			(effects
				(font
					(size 1 1)
					(thickness 0.15)
				)
			)
		)
		(property "License" "Apache-2.0"
			(at 0 0 180)
			(unlocked yes)
			(layer "F.Fab")
			(hide yes)
			(effects
				(font
					(size 1 1)
					(thickness 0.15)
				)
			)
		)
		(sheetname "/Power/")
		(sheetfile "power.kicad_sch")
		(attr exclude_from_pos_files exclude_from_bom)
		(fp_circle
			(center 0 0)
			(end 0.475 0)
			(stroke
				(width 0.05)
				(type default)
			)
			(fill no)
			(layer "F.CrtYd")
		)
		(fp_text user "Author: Antmicro"
			(at -0.4 3.901 0)
			(layer "F.Fab")
			(effects
				(font
					(size 0.7 0.7)
					(thickness 0.15)
				)
				(justify right top)
			)
		)
		(fp_text user "${REFERENCE}"
			(at -0.4 2.7 0)
			(layer "F.Fab")
			(effects
				(font
					(size 0.7 0.7)
					(thickness 0.15)
				)
				(justify right top)
			)
		)
		(fp_text user "License: Apache-2.0"
			(at -0.4 5.101 0)
			(layer "F.Fab")
			(effects
				(font
					(size 0.7 0.7)
					(thickness 0.15)
				)
				(justify right top)
			)
		)
		(pad "1" smd circle
			(at 0 0 180)
			(size 0.75 0.75)
			(layers "F.Cu" "F.Mask")
			(net 11 "+1V8")
			(pinfunction "1")
			(pintype "passive")
		)
	)
	(footprint "antmicro-footprints:R_0402_1005Metric"
		(layer "F.Cu")
		(at 167.95 144.8 90)
		(descr "Resistor SMD 0402")
		(tags "resistor SMD 0402")
		(property "Reference" "R25"
			(at -1 1.35 90)
			(layer "F.SilkS")
			(effects
				(font
					(size 0.7 0.7)
					(thickness 0.15)
				)
				(justify left bottom)
			)
		)
		(property "Value" "R_0R_0402"
			(at -1.011843 1.772047 90)
			(layer "F.Fab")
			(effects
				(font
					(size 0.7 0.7)
					(thickness 0.15)
				)
				(justify left bottom)
			)
		)
		(property "Datasheet" "https://industrial.panasonic.com/cdbs/www-data/pdf/RDA0000/AOA0000C301.pdf"
			(at 0 0 90)
			(layer "F.Fab")
			(hide yes)
			(effects
				(font
					(size 1.27 1.27)
					(thickness 0.15)
				)
			)
		)
		(property "Description" "SMD Chip Resistor, Jumper, 0 ohm, 100 mW, 0402 [1005 Metric], Thick Film, General Purpose"
			(at 0 0 90)
			(layer "F.Fab")
			(hide yes)
			(effects
				(font
					(size 1.27 1.27)
					(thickness 0.15)
				)
			)
		)
		(property "MPN" "ERJ2GE0R00X"
			(at 0 0 90)
			(unlocked yes)
			(layer "F.Fab")
			(hide yes)
			(effects
				(font
					(size 1 1)
					(thickness 0.15)
				)
			)
		)
		(property "Manufacturer" "Panasonic"
			(at 0 0 90)
			(unlocked yes)
			(layer "F.Fab")
			(hide yes)
			(effects
				(font
					(size 1 1)
					(thickness 0.15)
				)
			)
		)
		(property "License" "Apache-2.0"
			(at 0 0 90)
			(unlocked yes)
			(layer "F.Fab")
			(hide yes)
			(effects
				(font
					(size 1 1)
					(thickness 0.15)
				)
			)
		)
		(property "Author" "Antmicro"
			(at 0 0 90)
			(unlocked yes)
			(layer "F.Fab")
			(hide yes)
			(effects
				(font
					(size 1 1)
					(thickness 0.15)
				)
			)
		)
		(property "Val" "0R"
			(at 0 0 90)
			(unlocked yes)
			(layer "F.Fab")
			(hide yes)
			(effects
				(font
					(size 1 1)
					(thickness 0.15)
				)
			)
		)
		(property "Tolerance" "~"
			(at 0 0 90)
			(unlocked yes)
			(layer "F.Fab")
			(hide yes)
			(effects
				(font
					(size 1 1)
					(thickness 0.15)
				)
			)
		)
		(property "Current" "1A"
			(at 0 0 90)
			(unlocked yes)
			(layer "F.Fab")
			(hide yes)
			(effects
				(font
					(size 1 1)
					(thickness 0.15)
				)
			)
		)
		(sheetname "/Peripherals/")
		(sheetfile "peripherals.kicad_sch")
		(attr smd exclude_from_pos_files exclude_from_bom dnp)
		(fp_rect
			(start -0.925 -0.47)
			(end 0.925 0.47)
			(stroke
				(width 0.05)
				(type default)
			)
			(fill no)
			(layer "F.CrtYd")
		)
		(fp_rect
			(start -0.5 -0.25)
			(end 0.5 0.25)
			(stroke
				(width 0.15)
				(type solid)
			)
			(fill no)
			(layer "F.Fab")
		)
		(fp_text user "${REFERENCE}"
			(at -0.95 3.168 90)
			(layer "F.Fab")
			(effects
				(font
					(size 0.7 0.7)
					(thickness 0.15)
				)
				(justify left bottom)
			)
		)
		(fp_text user "License: Apache-2.0"
			(at -0.95 5.169 90)
			(layer "F.Fab")
			(effects
				(font
					(size 0.7 0.7)
					(thickness 0.15)
				)
				(justify left bottom)
			)
		)
		(fp_text user "Author: Antmicro"
			(at -0.95 4.169 90)
			(layer "F.Fab")
			(effects
				(font
					(size 0.7 0.7)
					(thickness 0.15)
				)
				(justify left bottom)
			)
		)
		(pad "1" smd roundrect
			(at -0.48 0 90)
			(size 0.59 0.64)
			(layers "F.Cu" "F.Mask" "F.Paste")
			(roundrect_rratio 0.25)
			(net 634 "+12V")
			(pintype "passive")
		)
		(pad "2" smd roundrect
			(at 0.48 0 90)
			(size 0.59 0.64)
			(layers "F.Cu" "F.Mask" "F.Paste")
			(roundrect_rratio 0.25)
			(net 1043 "/Peripherals/FAN_VDD")
			(pintype "passive")
		)
	)
	(footprint "antmicro-footprints:C_0603_1608Metric_EIA"
		(layer "F.Cu")
		(at 147.954391 126.46)
		(descr "Capacitor SMD 0603, IPC-7351 Density Level A")
		(tags "Capacitor 0603")
		(property "Reference" "C37"
			(at 1.145609 0.44 0)
			(layer "F.SilkS")
			(effects
				(font
					(size 0.7 0.7)
					(thickness 0.15)
				)
				(justify left bottom)
			)
		)
		(property "Value" "C_22u_16V_0603"
			(at -1.42757 1.770288 0)
			(layer "F.Fab")
			(effects
				(font
					(size 0.7 0.7)
					(thickness 0.15)
				)
				(justify left bottom)
			)
		)
		(property "Datasheet" "https://product.samsungsem.com/mlcc/CL10A226MO7JZN.do"
			(at 0 0 0)
			(layer "F.Fab")
			(hide yes)
			(effects
				(font
					(size 1.27 1.27)
					(thickness 0.15)
				)
			)
		)
		(property "Description" "SMD Multilayer Ceramic Capacitor"
			(at 0 0 0)
			(layer "F.Fab")
			(hide yes)
			(effects
				(font
					(size 1.27 1.27)
					(thickness 0.15)
				)
			)
		)
		(property "MPN" "CL10A226MO7JZNC"
			(at 0 0 0)
			(unlocked yes)
			(layer "F.Fab")
			(hide yes)
			(effects
				(font
					(size 1 1)
					(thickness 0.15)
				)
			)
		)
		(property "Manufacturer" "Samsung Electro-Mechanics"
			(at 0 0 0)
			(unlocked yes)
			(layer "F.Fab")
			(hide yes)
			(effects
				(font
					(size 1 1)
					(thickness 0.15)
				)
			)
		)
		(property "License" "Apache-2.0"
			(at 0 0 0)
			(unlocked yes)
			(layer "F.Fab")
			(hide yes)
			(effects
				(font
					(size 1 1)
					(thickness 0.15)
				)
			)
		)
		(property "Author" "Antmicro"
			(at 0 0 0)
			(unlocked yes)
			(layer "F.Fab")
			(hide yes)
			(effects
				(font
					(size 1 1)
					(thickness 0.15)
				)
			)
		)
		(property "Val" "22u"
			(at 0 0 0)
			(unlocked yes)
			(layer "F.Fab")
			(hide yes)
			(effects
				(font
					(size 1 1)
					(thickness 0.15)
				)
			)
		)
		(property "Voltage" "16V"
			(at 0 0 0)
			(unlocked yes)
			(layer "F.Fab")
			(hide yes)
			(effects
				(font
					(size 1 1)
					(thickness 0.15)
				)
			)
		)
		(property "Dielectric" ""
			(at 0 0 0)
			(unlocked yes)
			(layer "F.Fab")
			(hide yes)
			(effects
				(font
					(size 1 1)
					(thickness 0.15)
				)
			)
		)
		(component_classes
			(class "DCDC_1V8")
		)
		(sheetname "/DCDC/")
		(sheetfile "dcdc.kicad_sch")
		(attr smd)
		(fp_line
			(start -0.15 -0.55)
			(end 0.15 -0.55)
			(stroke
				(width 0.15)
				(type solid)
			)
			(layer "F.SilkS")
		)
		(fp_line
			(start -0.15 0.55)
			(end 0.15 0.55)
			(stroke
				(width 0.15)
				(type solid)
			)
			(layer "F.SilkS")
		)
		(fp_rect
			(start -1.25 -0.65)
			(end 1.25 0.65)
			(stroke
				(width 0.05)
				(type solid)
			)
			(fill no)
			(layer "F.CrtYd")
		)
		(fp_rect
			(start -0.8 -0.45)
			(end 0.8 0.45)
			(stroke
				(width 0.15)
				(type solid)
			)
			(fill no)
			(layer "F.Fab")
		)
		(fp_text user "License: Apache-2.0"
			(at -1.682 5.895 0)
			(layer "F.Fab")
			(effects
				(font
					(size 0.7 0.7)
					(thickness 0.15)
				)
				(justify left bottom)
			)
		)
		(fp_text user "Author: Antmicro"
			(at -1.682 4.894 0)
			(layer "F.Fab")
			(effects
				(font
					(size 0.7 0.7)
					(thickness 0.15)
				)
				(justify left bottom)
			)
		)
		(fp_text user "${REFERENCE}"
			(at -1.682 3.895 0)
			(layer "F.Fab")
			(effects
				(font
					(size 0.7 0.7)
					(thickness 0.15)
				)
				(justify left bottom)
			)
		)
		(pad "1" smd roundrect
			(at -0.7 0)
			(size 0.8 1.1)
			(layers "F.Cu" "F.Mask" "F.Paste")
			(roundrect_rratio 0.2)
			(net 1 "GND")
			(pintype "passive")
		)
		(pad "2" smd roundrect
			(at 0.7 0)
			(size 0.8 1.1)
			(layers "F.Cu" "F.Mask" "F.Paste")
			(roundrect_rratio 0.2)
			(net 17 "/DCDC/1V8_OUT")
			(pintype "passive")
		)
	)
	(footprint "antmicro-footprints:C_0402_1005Metric"
		(layer "F.Cu")
		(at 197.2 127.3)
		(descr "Capacitor SMD 0402")
		(tags "capacitor SMD 0402")
		(property "Reference" "C89"
			(at -1 1.4 0)
			(layer "F.SilkS")
			(effects
				(font
					(size 0.7 0.7)
					(thickness 0.15)
				)
				(justify left bottom)
			)
		)
		(property "Value" "C_100n_0402"
			(at -1.022927 2.155213 0)
			(layer "F.Fab")
			(effects
				(font
					(size 0.7 0.7)
					(thickness 0.15)
				)
				(justify left bottom)
			)
		)
		(property "Datasheet" "https://www.murata.com/products/productdetail?partno=GRM155R61H104KE14%23"
			(at 0 0 0)
			(layer "F.Fab")
			(hide yes)
			(effects
				(font
					(size 1.27 1.27)
					(thickness 0.15)
				)
			)
		)
		(property "Description" "SMD Multilayer Ceramic Capacitor, 0.1 µF, 50 V, 0402 [1005 Metric], ± 10%, X5R, GRM Series"
			(at 0 0 0)
			(layer "F.Fab")
			(hide yes)
			(effects
				(font
					(size 1.27 1.27)
					(thickness 0.15)
				)
			)
		)
		(property "MPN" "GRM155R61H104KE14D"
			(at 0 0 0)
			(unlocked yes)
			(layer "F.Fab")
			(hide yes)
			(effects
				(font
					(size 1 1)
					(thickness 0.15)
				)
			)
		)
		(property "Val" "100n"
			(at 0 0 0)
			(unlocked yes)
			(layer "F.Fab")
			(hide yes)
			(effects
				(font
					(size 1 1)
					(thickness 0.15)
				)
			)
		)
		(property "Voltage" "50V"
			(at 0 0 0)
			(unlocked yes)
			(layer "F.Fab")
			(hide yes)
			(effects
				(font
					(size 1 1)
					(thickness 0.15)
				)
			)
		)
		(property "Dielectric" "X5R"
			(at 0 0 0)
			(unlocked yes)
			(layer "F.Fab")
			(hide yes)
			(effects
				(font
					(size 1 1)
					(thickness 0.15)
				)
			)
		)
		(property "Manufacturer" "Murata"
			(at 0 0 0)
			(unlocked yes)
			(layer "F.Fab")
			(hide yes)
			(effects
				(font
					(size 1 1)
					(thickness 0.15)
				)
			)
		)
		(property "License" "Apache-2.0"
			(at 0 0 0)
			(unlocked yes)
			(layer "F.Fab")
			(hide yes)
			(effects
				(font
					(size 1 1)
					(thickness 0.15)
				)
			)
		)
		(property "Author" "Antmicro"
			(at 0 0 0)
			(unlocked yes)
			(layer "F.Fab")
			(hide yes)
			(effects
				(font
					(size 1 1)
					(thickness 0.15)
				)
			)
		)
		(sheetname "/USB Hub/")
		(sheetfile "usb_hub.kicad_sch")
		(attr smd)
		(fp_rect
			(start -0.925 -0.47)
			(end 0.925 0.47)
			(stroke
				(width 0.05)
				(type default)
			)
			(fill no)
			(layer "F.CrtYd")
		)
		(fp_line
			(start -0.494 -0.25)
			(end 0.504 -0.25)
			(stroke
				(width 0.15)
				(type solid)
			)
			(layer "F.Fab")
		)
		(fp_line
			(start -0.494 0.248)
			(end -0.494 -0.25)
			(stroke
				(width 0.15)
				(type solid)
			)
			(layer "F.Fab")
		)
		(fp_line
			(start 0.504 -0.25)
			(end 0.504 0.248)
			(stroke
				(width 0.15)
				(type solid)
			)
			(layer "F.Fab")
		)
		(fp_line
			(start 0.504 0.248)
			(end -0.494 0.248)
			(stroke
				(width 0.15)
				(type solid)
			)
			(layer "F.Fab")
		)
		(fp_text user "Author: Antmicro"
			(at -0.939 3.399 0)
			(layer "F.Fab")
			(effects
				(font
					(size 0.7 0.7)
					(thickness 0.15)
				)
				(justify left bottom)
			)
		)
		(fp_text user "${REFERENCE}"
			(at -0.939 4.599 0)
			(layer "F.Fab")
			(effects
				(font
					(size 0.7 0.7)
					(thickness 0.15)
				)
				(justify left bottom)
			)
		)
		(fp_text user "License: Apache-2.0"
			(at -0.939 5.799 0)
			(layer "F.Fab")
			(effects
				(font
					(size 0.7 0.7)
					(thickness 0.15)
				)
				(justify left bottom)
			)
		)
		(pad "1" smd roundrect
			(at -0.48 0)
			(size 0.59 0.64)
			(layers "F.Cu" "F.Mask" "F.Paste")
			(roundrect_rratio 0.25)
			(net 1 "GND")
			(pintype "passive")
		)
		(pad "2" smd roundrect
			(at 0.48 0)
			(size 0.59 0.64)
			(layers "F.Cu" "F.Mask" "F.Paste")
			(roundrect_rratio 0.25)
			(net 2 "+3V3")
			(pintype "passive")
		)
	)
	(footprint "antmicro-footprints:C_0402_1005Metric"
		(layer "F.Cu")
		(at 197.22 122.9)
		(descr "Capacitor SMD 0402")
		(tags "capacitor SMD 0402")
		(property "Reference" "C358"
			(at -1.315 -1.8 0)
			(layer "F.SilkS")
			(effects
				(font
					(size 0.7 0.7)
					(thickness 0.15)
				)
				(justify left bottom)
			)
		)
		(property "Value" "C_100n_0402"
			(at -1.022927 2.155213 0)
			(layer "F.Fab")
			(effects
				(font
					(size 0.7 0.7)
					(thickness 0.15)
				)
				(justify left bottom)
			)
		)
		(property "Datasheet" "https://www.murata.com/products/productdetail?partno=GRM155R61H104KE14%23"
			(at 0 0 0)
			(layer "F.Fab")
			(hide yes)
			(effects
				(font
					(size 1.27 1.27)
					(thickness 0.15)
				)
			)
		)
		(property "Description" "SMD Multilayer Ceramic Capacitor, 0.1 µF, 50 V, 0402 [1005 Metric], ± 10%, X5R, GRM Series"
			(at 0 0 0)
			(layer "F.Fab")
			(hide yes)
			(effects
				(font
					(size 1.27 1.27)
					(thickness 0.15)
				)
			)
		)
		(property "MPN" "GRM155R61H104KE14D"
			(at 0 0 0)
			(unlocked yes)
			(layer "F.Fab")
			(hide yes)
			(effects
				(font
					(size 1 1)
					(thickness 0.15)
				)
			)
		)
		(property "Val" "100n"
			(at 0 0 0)
			(unlocked yes)
			(layer "F.Fab")
			(hide yes)
			(effects
				(font
					(size 1 1)
					(thickness 0.15)
				)
			)
		)
		(property "Voltage" "50V"
			(at 0 0 0)
			(unlocked yes)
			(layer "F.Fab")
			(hide yes)
			(effects
				(font
					(size 1 1)
					(thickness 0.15)
				)
			)
		)
		(property "Dielectric" "X5R"
			(at 0 0 0)
			(unlocked yes)
			(layer "F.Fab")
			(hide yes)
			(effects
				(font
					(size 1 1)
					(thickness 0.15)
				)
			)
		)
		(property "Manufacturer" "Murata"
			(at 0 0 0)
			(unlocked yes)
			(layer "F.Fab")
			(hide yes)
			(effects
				(font
					(size 1 1)
					(thickness 0.15)
				)
			)
		)
		(property "License" "Apache-2.0"
			(at 0 0 0)
			(unlocked yes)
			(layer "F.Fab")
			(hide yes)
			(effects
				(font
					(size 1 1)
					(thickness 0.15)
				)
			)
		)
		(property "Author" "Antmicro"
			(at 0 0 0)
			(unlocked yes)
			(layer "F.Fab")
			(hide yes)
			(effects
				(font
					(size 1 1)
					(thickness 0.15)
				)
			)
		)
		(sheetname "/USB Hub/")
		(sheetfile "usb_hub.kicad_sch")
		(attr smd)
		(fp_rect
			(start -0.925 -0.47)
			(end 0.925 0.47)
			(stroke
				(width 0.05)
				(type default)
			)
			(fill no)
			(layer "F.CrtYd")
		)
		(fp_line
			(start -0.494 -0.25)
			(end 0.504 -0.25)
			(stroke
				(width 0.15)
				(type solid)
			)
			(layer "F.Fab")
		)
		(fp_line
			(start -0.494 0.248)
			(end -0.494 -0.25)
			(stroke
				(width 0.15)
				(type solid)
			)
			(layer "F.Fab")
		)
		(fp_line
			(start 0.504 -0.25)
			(end 0.504 0.248)
			(stroke
				(width 0.15)
				(type solid)
			)
			(layer "F.Fab")
		)
		(fp_line
			(start 0.504 0.248)
			(end -0.494 0.248)
			(stroke
				(width 0.15)
				(type solid)
			)
			(layer "F.Fab")
		)
		(fp_text user "${REFERENCE}"
			(at -0.939 4.599 0)
			(layer "F.Fab")
			(effects
				(font
					(size 0.7 0.7)
					(thickness 0.15)
				)
				(justify left bottom)
			)
		)
		(fp_text user "Author: Antmicro"
			(at -0.939 3.399 0)
			(layer "F.Fab")
			(effects
				(font
					(size 0.7 0.7)
					(thickness 0.15)
				)
				(justify left bottom)
			)
		)
		(fp_text user "License: Apache-2.0"
			(at -0.939 5.799 0)
			(layer "F.Fab")
			(effects
				(font
					(size 0.7 0.7)
					(thickness 0.15)
				)
				(justify left bottom)
			)
		)
		(pad "1" smd roundrect
			(at -0.48 0)
			(size 0.59 0.64)
			(layers "F.Cu" "F.Mask" "F.Paste")
			(roundrect_rratio 0.25)
			(net 1 "GND")
			(pintype "passive")
		)
		(pad "2" smd roundrect
			(at 0.48 0)
			(size 0.59 0.64)
			(layers "F.Cu" "F.Mask" "F.Paste")
			(roundrect_rratio 0.25)
			(net 282 "+1V15")
			(pintype "passive")
		)
	)
	(footprint "antmicro-footprints:C_0805_2012Metric"
		(layer "F.Cu")
		(at 113.249999 56.74 -90)
		(descr "Capacitor SMD 0805")
		(tags "capacitor SMD 0805")
		(property "Reference" "C379"
			(at -1.87 0.949999 180)
			(layer "F.SilkS")
			(effects
				(font
					(size 0.7 0.7)
					(thickness 0.15)
				)
				(justify left bottom)
			)
		)
		(property "Value" "C_22u_25V_0805"
			(at -2.055717 1.963152 90)
			(layer "F.Fab")
			(effects
				(font
					(size 0.7 0.7)
					(thickness 0.15)
				)
				(justify right top)
			)
		)
		(property "Datasheet" "https://product.samsungsem.com/mlcc/CL21A226MAYNNN.do"
			(at 0 0 90)
			(layer "F.Fab")
			(hide yes)
			(effects
				(font
					(size 1.27 1.27)
					(thickness 0.15)
				)
			)
		)
		(property "Description" "SMT Multilayer Ceramic Capacitor, 22uF, +/-20%, 25V, X5R, 0805 [2012 Metric]"
			(at 0 0 90)
			(layer "F.Fab")
			(hide yes)
			(effects
				(font
					(size 1.27 1.27)
					(thickness 0.15)
				)
			)
		)
		(property "MPN" "CL21A226MAYNNNE"
			(at 0 0 270)
			(unlocked yes)
			(layer "F.Fab")
			(hide yes)
			(effects
				(font
					(size 1 1)
					(thickness 0.15)
				)
			)
		)
		(property "Manufacturer" "Samsung Electro-Mechanics"
			(at 0 0 270)
			(unlocked yes)
			(layer "F.Fab")
			(hide yes)
			(effects
				(font
					(size 1 1)
					(thickness 0.15)
				)
			)
		)
		(property "License" "Apache-2.0"
			(at 0 0 270)
			(unlocked yes)
			(layer "F.Fab")
			(hide yes)
			(effects
				(font
					(size 1 1)
					(thickness 0.15)
				)
			)
		)
		(property "Author" "Antmicro"
			(at 0 0 270)
			(unlocked yes)
			(layer "F.Fab")
			(hide yes)
			(effects
				(font
					(size 1 1)
					(thickness 0.15)
				)
			)
		)
		(property "Val" "22u"
			(at 0 0 270)
			(unlocked yes)
			(layer "F.Fab")
			(hide yes)
			(effects
				(font
					(size 1 1)
					(thickness 0.15)
				)
			)
		)
		(property "Voltage" "25V"
			(at 0 0 270)
			(unlocked yes)
			(layer "F.Fab")
			(hide yes)
			(effects
				(font
					(size 1 1)
					(thickness 0.15)
				)
			)
		)
		(property "Dielectric" "X5R"
			(at 0 0 270)
			(unlocked yes)
			(layer "F.Fab")
			(hide yes)
			(effects
				(font
					(size 1 1)
					(thickness 0.15)
				)
			)
		)
		(property "Public" "False"
			(at 0 0 270)
			(unlocked yes)
			(layer "F.Fab")
			(hide yes)
			(effects
				(font
					(size 1 1)
					(thickness 0.15)
				)
			)
		)
		(sheetname "/DCDC/")
		(sheetfile "dcdc.kicad_sch")
		(attr smd)
		(fp_line
			(start -0.3 0.7)
			(end 0.3 0.7)
			(stroke
				(width 0.15)
				(type solid)
			)
			(layer "F.SilkS")
		)
		(fp_line
			(start -0.3 -0.7)
			(end 0.3 -0.7)
			(stroke
				(width 0.15)
				(type solid)
			)
			(layer "F.SilkS")
		)
		(fp_rect
			(start 1.95 -0.9)
			(end -1.95 0.9)
			(stroke
				(width 0.05)
				(type default)
			)
			(fill no)
			(layer "F.CrtYd")
		)
		(fp_rect
			(start -0.95 -0.675)
			(end 0.95 0.675)
			(stroke
				(width 0.15)
				(type solid)
			)
			(fill no)
			(layer "F.Fab")
		)
		(fp_text user "Author: Antmicro"
			(at -1.9 5.947 90)
			(layer "F.Fab")
			(effects
				(font
					(size 0.7 0.7)
					(thickness 0.15)
				)
				(justify right top)
			)
		)
		(fp_text user "License: Apache-2.0"
			(at -1.9 4.947 90)
			(layer "F.Fab")
			(effects
				(font
					(size 0.7 0.7)
					(thickness 0.15)
				)
				(justify right top)
			)
		)
		(fp_text user "${REFERENCE}"
			(at -1.9 3.947 90)
			(layer "F.Fab")
			(effects
				(font
					(size 0.7 0.7)
					(thickness 0.15)
				)
				(justify right top)
			)
		)
		(pad "1" smd roundrect
			(at -1.1 0 270)
			(size 1.2 1.3)
			(layers "F.Cu" "F.Mask" "F.Paste")
			(roundrect_rratio 0.25)
			(net 1 "GND")
			(pintype "passive")
		)
		(pad "2" smd roundrect
			(at 1.1 0 270)
			(size 1.2 1.3)
			(layers "F.Cu" "F.Mask" "F.Paste")
			(roundrect_rratio 0.25)
			(net 1278 "/DCDC/5V_{AON}_OUT")
			(pintype "passive")
		)
	)
	(footprint "antmicro-footprints:C_0805_2012Metric"
		(layer "F.Cu")
		(at 176.13 110.356 90)
		(descr "Capacitor SMD 0805")
		(tags "capacitor SMD 0805")
		(property "Reference" "C45"
			(at 1.92 -0.16 90)
			(layer "F.SilkS")
			(effects
				(font
					(size 0.7 0.7)
					(thickness 0.15)
				)
				(justify left bottom)
			)
		)
		(property "Value" "C_22u_25V_0805"
			(at -2.055717 1.963152 90)
			(layer "F.Fab")
			(effects
				(font
					(size 0.7 0.7)
					(thickness 0.15)
				)
				(justify left bottom)
			)
		)
		(property "Datasheet" "https://product.samsungsem.com/mlcc/CL21A226MAYNNN.do"
			(at 0 0 90)
			(layer "F.Fab")
			(hide yes)
			(effects
				(font
					(size 1.27 1.27)
					(thickness 0.15)
				)
			)
		)
		(property "Description" "SMT Multilayer Ceramic Capacitor, 22uF, +/-20%, 25V, X5R, 0805 [2012 Metric]"
			(at 0 0 90)
			(layer "F.Fab")
			(hide yes)
			(effects
				(font
					(size 1.27 1.27)
					(thickness 0.15)
				)
			)
		)
		(property "MPN" "CL21A226MAYNNNE"
			(at 0 0 90)
			(unlocked yes)
			(layer "F.Fab")
			(hide yes)
			(effects
				(font
					(size 1 1)
					(thickness 0.15)
				)
			)
		)
		(property "Manufacturer" "Samsung Electro-Mechanics"
			(at 0 0 90)
			(unlocked yes)
			(layer "F.Fab")
			(hide yes)
			(effects
				(font
					(size 1 1)
					(thickness 0.15)
				)
			)
		)
		(property "License" "Apache-2.0"
			(at 0 0 90)
			(unlocked yes)
			(layer "F.Fab")
			(hide yes)
			(effects
				(font
					(size 1 1)
					(thickness 0.15)
				)
			)
		)
		(property "Author" "Antmicro"
			(at 0 0 90)
			(unlocked yes)
			(layer "F.Fab")
			(hide yes)
			(effects
				(font
					(size 1 1)
					(thickness 0.15)
				)
			)
		)
		(property "Val" "22u"
			(at 0 0 90)
			(unlocked yes)
			(layer "F.Fab")
			(hide yes)
			(effects
				(font
					(size 1 1)
					(thickness 0.15)
				)
			)
		)
		(property "Voltage" "25V"
			(at 0 0 90)
			(unlocked yes)
			(layer "F.Fab")
			(hide yes)
			(effects
				(font
					(size 1 1)
					(thickness 0.15)
				)
			)
		)
		(property "Dielectric" "X5R"
			(at 0 0 90)
			(unlocked yes)
			(layer "F.Fab")
			(hide yes)
			(effects
				(font
					(size 1 1)
					(thickness 0.15)
				)
			)
		)
		(property "Public" "False"
			(at 0 0 90)
			(unlocked yes)
			(layer "F.Fab")
			(hide yes)
			(effects
				(font
					(size 1 1)
					(thickness 0.15)
				)
			)
		)
		(sheetname "/DCDC/")
		(sheetfile "dcdc.kicad_sch")
		(attr smd)
		(fp_line
			(start -0.3 -0.7)
			(end 0.3 -0.7)
			(stroke
				(width 0.15)
				(type solid)
			)
			(layer "F.SilkS")
		)
		(fp_line
			(start -0.3 0.7)
			(end 0.3 0.7)
			(stroke
				(width 0.15)
				(type solid)
			)
			(layer "F.SilkS")
		)
		(fp_rect
			(start 1.95 -0.9)
			(end -1.95 0.9)
			(stroke
				(width 0.05)
				(type default)
			)
			(fill no)
			(layer "F.CrtYd")
		)
		(fp_rect
			(start -0.95 -0.675)
			(end 0.95 0.675)
			(stroke
				(width 0.15)
				(type solid)
			)
			(fill no)
			(layer "F.Fab")
		)
		(fp_text user "${REFERENCE}"
			(at -1.9 3.947 90)
			(layer "F.Fab")
			(effects
				(font
					(size 0.7 0.7)
					(thickness 0.15)
				)
				(justify left bottom)
			)
		)
		(fp_text user "License: Apache-2.0"
			(at -1.9 4.947 90)
			(layer "F.Fab")
			(effects
				(font
					(size 0.7 0.7)
					(thickness 0.15)
				)
				(justify left bottom)
			)
		)
		(fp_text user "Author: Antmicro"
			(at -1.9 5.947 90)
			(layer "F.Fab")
			(effects
				(font
					(size 0.7 0.7)
					(thickness 0.15)
				)
				(justify left bottom)
			)
		)
		(pad "1" smd roundrect
			(at -1.1 0 90)
			(size 1.2 1.3)
			(layers "F.Cu" "F.Mask" "F.Paste")
			(roundrect_rratio 0.25)
			(net 1 "GND")
			(pintype "passive")
		)
		(pad "2" smd roundrect
			(at 1.1 0 90)
			(size 1.2 1.3)
			(layers "F.Cu" "F.Mask" "F.Paste")
			(roundrect_rratio 0.25)
			(net 13 "VCC")
			(pintype "passive")
		)
	)
	(footprint "antmicro-footprints:L_Coilcraft-XAL7070"
		(layer "F.Cu")
		(at 180 97.5 180)
		(property "Reference" "L3"
			(at -4.234468 -2.855 90)
			(layer "F.SilkS")
			(effects
				(font
					(size 0.7 0.7)
					(thickness 0.15)
				)
				(justify right top)
			)
		)
		(property "Value" "L_3u3_15.1A_Coilcraft-XAL7070"
			(at 0 5.2 0)
			(layer "F.Fab")
			(effects
				(font
					(size 0.7 0.7)
					(thickness 0.15)
				)
				(justify right top)
			)
		)
		(property "Datasheet" "https://www.coilcraft.com/en-us/products/power/shielded-inductors/molded-inductor/xal/xal7070/xal7070-332/"
			(at 0 0 0)
			(layer "F.Fab")
			(hide yes)
			(effects
				(font
					(size 1.27 1.27)
					(thickness 0.15)
				)
			)
		)
		(property "Description" "Power Inductor (SMD), 3.3 µH, 15.1 A, Shielded, 19.4 A, XAL7070"
			(at 0 0 0)
			(layer "F.Fab")
			(hide yes)
			(effects
				(font
					(size 1.27 1.27)
					(thickness 0.15)
				)
			)
		)
		(property "Val" "3u3/15.1A"
			(at 0 0 180)
			(unlocked yes)
			(layer "F.Fab")
			(hide yes)
			(effects
				(font
					(size 1 1)
					(thickness 0.15)
				)
			)
		)
		(property "Manufacturer" "Coilcraft"
			(at 0 0 180)
			(unlocked yes)
			(layer "F.Fab")
			(hide yes)
			(effects
				(font
					(size 1 1)
					(thickness 0.15)
				)
			)
		)
		(property "MPN" "XAL7070-332MEB"
			(at 0 0 180)
			(unlocked yes)
			(layer "F.Fab")
			(hide yes)
			(effects
				(font
					(size 1 1)
					(thickness 0.15)
				)
			)
		)
		(property "ISat" "19.4 A"
			(at 0 0 180)
			(unlocked yes)
			(layer "F.Fab")
			(hide yes)
			(effects
				(font
					(size 1 1)
					(thickness 0.15)
				)
			)
		)
		(property "IMax" "15.1 A"
			(at 0 0 180)
			(unlocked yes)
			(layer "F.Fab")
			(hide yes)
			(effects
				(font
					(size 1 1)
					(thickness 0.15)
				)
			)
		)
		(property "Size" "7.7x8"
			(at 0 0 180)
			(unlocked yes)
			(layer "F.Fab")
			(hide yes)
			(effects
				(font
					(size 1 1)
					(thickness 0.15)
				)
			)
		)
		(property "Author" "Antmicro"
			(at 0 0 180)
			(unlocked yes)
			(layer "F.Fab")
			(hide yes)
			(effects
				(font
					(size 1 1)
					(thickness 0.15)
				)
			)
		)
		(property "License" "Apache-2.0"
			(at 0 0 180)
			(unlocked yes)
			(layer "F.Fab")
			(hide yes)
			(effects
				(font
					(size 1 1)
					(thickness 0.15)
				)
			)
		)
		(component_classes
			(class "DCDC_SOM")
		)
		(sheetname "/DCDC/")
		(sheetfile "dcdc.kicad_sch")
		(attr smd)
		(fp_line
			(start 3.85 -4)
			(end 3.85 4)
			(stroke
				(width 0.15)
				(type solid)
			)
			(layer "F.SilkS")
		)
		(fp_line
			(start 3.85 -4)
			(end -3.85 -4)
			(stroke
				(width 0.15)
				(type solid)
			)
			(layer "F.SilkS")
		)
		(fp_line
			(start -3.85 4)
			(end 3.85 4)
			(stroke
				(width 0.15)
				(type solid)
			)
			(layer "F.SilkS")
		)
		(fp_line
			(start -3.85 4)
			(end -3.85 -4)
			(stroke
				(width 0.15)
				(type solid)
			)
			(layer "F.SilkS")
		)
		(fp_rect
			(start -4.09 -4.25)
			(end 4.09 4.25)
			(stroke
				(width 0.05)
				(type solid)
			)
			(fill no)
			(layer "F.CrtYd")
		)
		(fp_line
			(start 3.85 4)
			(end -3.85 4)
			(stroke
				(width 0.15)
				(type solid)
			)
			(layer "F.Fab")
		)
		(fp_line
			(start 3.85 -4)
			(end 3.85 4)
			(stroke
				(width 0.15)
				(type solid)
			)
			(layer "F.Fab")
		)
		(fp_line
			(start -3.85 4)
			(end -3.85 -4)
			(stroke
				(width 0.15)
				(type solid)
			)
			(layer "F.Fab")
		)
		(fp_line
			(start -3.85 -4)
			(end 3.85 -4)
			(stroke
				(width 0.15)
				(type solid)
			)
			(layer "F.Fab")
		)
		(fp_text user "Author: Antmicro"
			(at -4.09 7.2 0)
			(layer "F.Fab")
			(effects
				(font
					(size 0.7 0.7)
					(thickness 0.15)
				)
				(justify right top)
			)
		)
		(fp_text user "License: Apache-2.0"
			(at -4.09 9.6 0)
			(layer "F.Fab")
			(effects
				(font
					(size 0.7 0.7)
					(thickness 0.15)
				)
				(justify right top)
			)
		)
		(fp_text user "${REFERENCE}"
			(at -4.09 8.4 0)
			(layer "F.Fab")
			(effects
				(font
					(size 0.7 0.7)
					(thickness 0.15)
				)
				(justify right top)
			)
		)
		(pad "1" smd roundrect
			(at -2.41 0 180)
			(size 1.92 6.5)
			(layers "F.Cu" "F.Mask" "F.Paste")
			(roundrect_rratio 0.1)
			(net 1183 "/DCDC/16V_SW")
			(pintype "passive")
		)
		(pad "2" smd roundrect
			(at 2.41 0 180)
			(size 1.92 6.5)
			(layers "F.Cu" "F.Mask" "F.Paste")
			(roundrect_rratio 0.1)
			(net 903 "/DCDC/16V_OUT")
			(pintype "passive")
		)
	)
	(footprint "antmicro-footprints:R_0603_1608Metric"
		(layer "F.Cu")
		(at 136.4 60.4 -90)
		(descr "Resistor SMD 0603")
		(tags "resistor SMD 0603")
		(property "Reference" "R63"
			(at -1.1 -0.73 90)
			(layer "F.SilkS")
			(effects
				(font
					(size 0.7 0.7)
					(thickness 0.15)
				)
				(justify right top)
			)
		)
		(property "Value" "R_0R_22.4A_0603"
			(at 0 1.6 90)
			(layer "F.Fab")
			(effects
				(font
					(size 0.7 0.7)
					(thickness 0.15)
				)
				(justify right top)
			)
		)
		(property "Datasheet" "https://fscdn.rohm.com/en/products/databook/datasheet/passive/resistor/chip_resistor/pmr-jpw-e.pdf"
			(at 0 0 90)
			(layer "F.Fab")
			(hide yes)
			(effects
				(font
					(size 1.27 1.27)
					(thickness 0.15)
				)
			)
		)
		(property "Description" "SMD Chip Resistor"
			(at 0 0 90)
			(layer "F.Fab")
			(hide yes)
			(effects
				(font
					(size 1.27 1.27)
					(thickness 0.15)
				)
			)
		)
		(property "Manufacturer" "ROHM Semiconductor"
			(at 0 0 270)
			(unlocked yes)
			(layer "F.Fab")
			(hide yes)
			(effects
				(font
					(size 1 1)
					(thickness 0.15)
				)
			)
		)
		(property "MPN" "PMR03EZPJ000"
			(at 0 0 270)
			(unlocked yes)
			(layer "F.Fab")
			(hide yes)
			(effects
				(font
					(size 1 1)
					(thickness 0.15)
				)
			)
		)
		(property "Val" "0R"
			(at 0 0 270)
			(unlocked yes)
			(layer "F.Fab")
			(hide yes)
			(effects
				(font
					(size 1 1)
					(thickness 0.15)
				)
			)
		)
		(property "License" "Apache-2.0"
			(at 0 0 270)
			(unlocked yes)
			(layer "F.Fab")
			(hide yes)
			(effects
				(font
					(size 1 1)
					(thickness 0.15)
				)
			)
		)
		(property "Author" "Antmicro"
			(at 0 0 270)
			(unlocked yes)
			(layer "F.Fab")
			(hide yes)
			(effects
				(font
					(size 1 1)
					(thickness 0.15)
				)
			)
		)
		(property "Tolerance" "template_tolerance"
			(at 0 0 270)
			(unlocked yes)
			(layer "F.Fab")
			(hide yes)
			(effects
				(font
					(size 1 1)
					(thickness 0.15)
				)
			)
		)
		(property "Max. Curr." "22.4A"
			(at 0 0 90)
			(unlocked yes)
			(layer "F.Fab")
			(hide yes)
			(effects
				(font
					(size 1 1)
					(thickness 0.15)
				)
			)
		)
		(sheetname "/Power/")
		(sheetfile "power.kicad_sch")
		(attr smd)
		(fp_line
			(start -0.15 0.4)
			(end 0.15 0.4)
			(stroke
				(width 0.15)
				(type solid)
			)
			(layer "F.SilkS")
		)
		(fp_line
			(start -0.15 -0.4)
			(end 0.15 -0.4)
			(stroke
				(width 0.15)
				(type solid)
			)
			(layer "F.SilkS")
		)
		(fp_poly
			(pts
				(xy -1.25 -0.65) (xy 1.25 -0.65) (xy 1.25 0.65) (xy -1.25 0.65)
			)
			(stroke
				(width 0.05)
				(type solid)
			)
			(fill no)
			(layer "F.CrtYd")
		)
		(fp_poly
			(pts
				(xy -0.8 -0.4) (xy 0.8 -0.4) (xy 0.8 0.4) (xy -0.8 0.4)
			)
			(stroke
				(width 0.15)
				(type solid)
			)
			(fill no)
			(layer "F.Fab")
		)
		(fp_text user "${REFERENCE}"
			(at -1.25 3.898 90)
			(layer "F.Fab")
			(effects
				(font
					(size 0.7 0.7)
					(thickness 0.15)
				)
				(justify right top)
			)
		)
		(fp_text user "Author: Antmicro"
			(at -1.25 4.9 90)
			(layer "F.Fab")
			(effects
				(font
					(size 0.7 0.7)
					(thickness 0.15)
				)
				(justify right top)
			)
		)
		(fp_text user "License: Apache-2.0"
			(at -1.249999 5.9 90)
			(layer "F.Fab")
			(effects
				(font
					(size 0.7 0.7)
					(thickness 0.15)
				)
				(justify right top)
			)
		)
		(pad "1" smd roundrect
			(at -0.7 0 270)
			(size 0.8 1)
			(layers "F.Cu" "F.Mask" "F.Paste")
			(roundrect_rratio 0.2)
			(net 31 "/Power/3V3_LDO")
			(pintype "passive")
		)
		(pad "2" smd roundrect
			(at 0.7 0 270)
			(size 0.8 1)
			(layers "F.Cu" "F.Mask" "F.Paste")
			(roundrect_rratio 0.2)
			(net 4 "+3V3_AON")
			(pintype "passive")
		)
	)
	(footprint "antmicro-footprints:XDFN-2_1x0.60mm"
		(layer "F.Cu")
		(at 211.25 55.5 -90)
		(property "Reference" "D54"
			(at 1 0.5 90)
			(layer "F.SilkS")
			(effects
				(font
					(size 0.7 0.7)
					(thickness 0.15)
				)
				(justify left bottom)
			)
		)
		(property "Value" "TPD1E0B04_XDFN-2"
			(at 0 1.5 90)
			(layer "F.Fab")
			(effects
				(font
					(size 0.7 0.7)
					(thickness 0.15)
				)
				(justify right top)
			)
		)
		(property "Datasheet" "https://www.ti.com/general/docs/suppproductinfo.tsp?distId=26&gotoUrl=https://www.ti.com/lit/gpn/tpd1e0b04"
			(at 0 0 90)
			(layer "F.Fab")
			(hide yes)
			(effects
				(font
					(size 1.27 1.27)
					(thickness 0.15)
				)
			)
		)
		(property "Description" "Bidirectional TVS, 8 kV,  XDFN-2, 3.6 V, 0.18 pF"
			(at 0 0 90)
			(layer "F.Fab")
			(hide yes)
			(effects
				(font
					(size 1.27 1.27)
					(thickness 0.15)
				)
			)
		)
		(property "MPN" "TPD1E0B04DPYR"
			(at 0 0 90)
			(layer "F.Fab")
			(hide yes)
			(effects
				(font
					(size 1.27 1.27)
					(thickness 0.15)
				)
			)
		)
		(property "Manufacturer" "Texas Instruments"
			(at 0 0 90)
			(layer "F.Fab")
			(hide yes)
			(effects
				(font
					(size 1.27 1.27)
					(thickness 0.15)
				)
			)
		)
		(property "Author" "Antmicro"
			(at 0 0 270)
			(unlocked yes)
			(layer "F.Fab")
			(hide yes)
			(effects
				(font
					(size 1 1)
					(thickness 0.15)
				)
			)
		)
		(property "License" "Apache-2.0"
			(at 0 0 270)
			(unlocked yes)
			(layer "F.Fab")
			(hide yes)
			(effects
				(font
					(size 1 1)
					(thickness 0.15)
				)
			)
		)
		(sheetname "/SoM_Power/")
		(sheetfile "som_power.kicad_sch")
		(attr smd)
		(fp_poly
			(pts
				(xy -0.725 -0.475) (xy 0.725 -0.475) (xy 0.725 0.475) (xy -0.725 0.475)
			)
			(stroke
				(width 0.05)
				(type solid)
			)
			(fill no)
			(layer "F.CrtYd")
		)
		(fp_poly
			(pts
				(xy -0.55 -0.35) (xy 0.55 -0.35) (xy 0.55 0.35) (xy -0.55 0.35)
			)
			(stroke
				(width 0.15)
				(type solid)
			)
			(fill no)
			(layer "F.Fab")
		)
		(fp_text user "License: Apache-2.0"
			(at -0.799999 5.6 90)
			(layer "F.Fab")
			(effects
				(font
					(size 0.7 0.7)
					(thickness 0.15)
				)
				(justify right top)
			)
		)
		(fp_text user "${REFERENCE}"
			(at -0.8 3.2 90)
			(layer "F.Fab")
			(effects
				(font
					(size 0.7 0.7)
					(thickness 0.15)
				)
				(justify right top)
			)
		)
		(fp_text user "Author: Antmicro"
			(at -0.8 4.4 90)
			(layer "F.Fab")
			(effects
				(font
					(size 0.7 0.7)
					(thickness 0.15)
				)
				(justify right top)
			)
		)
		(pad "1" smd roundrect
			(at -0.350999 0 270)
			(size 0.3 0.5)
			(layers "F.Cu" "F.Mask" "F.Paste")
			(roundrect_rratio 0.25)
			(net 1 "GND")
			(pinfunction "C")
			(pintype "passive")
		)
		(pad "2" smd roundrect
			(at 0.349 0 270)
			(size 0.3 0.5)
			(layers "F.Cu" "F.Mask" "F.Paste")
			(roundrect_rratio 0.25)
			(net 610 "/SoM_Power/~{PWR_BTN}")
			(pinfunction "A")
			(pintype "passive")
		)
	)
	(footprint "antmicro-footprints:R_0402_1005Metric"
		(layer "F.Cu")
		(at 232.540532 108.71 180)
		(descr "Resistor SMD 0402")
		(tags "resistor SMD 0402")
		(property "Reference" "R271"
			(at -1.359468 -0.79 0)
			(layer "F.SilkS")
			(effects
				(font
					(size 0.7 0.7)
					(thickness 0.15)
				)
				(justify right top)
			)
		)
		(property "Value" "R_470R_0402"
			(at -1.011843 1.772046 0)
			(layer "F.Fab")
			(effects
				(font
					(size 0.7 0.7)
					(thickness 0.15)
				)
				(justify right top)
			)
		)
		(property "Datasheet" "https://www.bourns.com/docs/product-datasheets/cr.pdf"
			(at 0 0 0)
			(layer "F.Fab")
			(hide yes)
			(effects
				(font
					(size 1.27 1.27)
					(thickness 0.15)
				)
			)
		)
		(property "Description" "SMD Chip Resistor, 470 ohm, ± 1%, 62.5 mW, 0402 [1005 Metric], Thick Film, General Purpose"
			(at 0 0 0)
			(layer "F.Fab")
			(hide yes)
			(effects
				(font
					(size 1.27 1.27)
					(thickness 0.15)
				)
			)
		)
		(property "Manufacturer" "Bourns"
			(at 0 0 180)
			(unlocked yes)
			(layer "F.Fab")
			(hide yes)
			(effects
				(font
					(size 1 1)
					(thickness 0.15)
				)
			)
		)
		(property "MPN" "CR0402-FX-4700GLF"
			(at 0 0 180)
			(unlocked yes)
			(layer "F.Fab")
			(hide yes)
			(effects
				(font
					(size 1 1)
					(thickness 0.15)
				)
			)
		)
		(property "Val" "470R"
			(at 0 0 180)
			(unlocked yes)
			(layer "F.Fab")
			(hide yes)
			(effects
				(font
					(size 1 1)
					(thickness 0.15)
				)
			)
		)
		(property "License" "Apache-2.0"
			(at 0 0 180)
			(unlocked yes)
			(layer "F.Fab")
			(hide yes)
			(effects
				(font
					(size 1 1)
					(thickness 0.15)
				)
			)
		)
		(property "Author" "Antmicro"
			(at 0 0 180)
			(unlocked yes)
			(layer "F.Fab")
			(hide yes)
			(effects
				(font
					(size 1 1)
					(thickness 0.15)
				)
			)
		)
		(property "Tolerance" "1%"
			(at 0 0 180)
			(unlocked yes)
			(layer "F.Fab")
			(hide yes)
			(effects
				(font
					(size 1 1)
					(thickness 0.15)
				)
			)
		)
		(sheetname "/Recovery USB/")
		(sheetfile "recovery_usb.kicad_sch")
		(attr smd)
		(fp_poly
			(pts
				(xy -0.925 -0.47) (xy 0.925 -0.47) (xy 0.925 0.47) (xy -0.925 0.47)
			)
			(stroke
				(width 0.05)
				(type default)
			)
			(fill no)
			(layer "F.CrtYd")
		)
		(fp_poly
			(pts
				(xy -0.5 -0.25) (xy 0.5 -0.25) (xy 0.5 0.25) (xy -0.5 0.25)
			)
			(stroke
				(width 0.15)
				(type solid)
			)
			(fill no)
			(layer "F.Fab")
		)
		(fp_text user "${REFERENCE}"
			(at -0.95 3.168 0)
			(layer "F.Fab")
			(effects
				(font
					(size 0.7 0.7)
					(thickness 0.15)
				)
				(justify right top)
			)
		)
		(fp_text user "Author: Antmicro"
			(at -0.95 4.169 0)
			(layer "F.Fab")
			(effects
				(font
					(size 0.7 0.7)
					(thickness 0.15)
				)
				(justify right top)
			)
		)
		(fp_text user "License: Apache-2.0"
			(at -0.949999 5.169 0)
			(layer "F.Fab")
			(effects
				(font
					(size 0.7 0.7)
					(thickness 0.15)
				)
				(justify right top)
			)
		)
		(pad "1" smd roundrect
			(at -0.48 0 180)
			(size 0.59 0.64)
			(layers "F.Cu" "F.Mask" "F.Paste")
			(roundrect_rratio 0.25)
			(net 1391 "Net-(D51-A)")
			(pintype "passive")
		)
		(pad "2" smd roundrect
			(at 0.48 0 180)
			(size 0.59 0.64)
			(layers "F.Cu" "F.Mask" "F.Paste")
			(roundrect_rratio 0.25)
			(net 287 "/Recovery USB/USBC2_VBUS")
			(pintype "passive")
		)
	)
	(footprint "antmicro-footprints:R_0402_1005Metric"
		(layer "F.Cu")
		(at 181.85 139.33 -90)
		(descr "Resistor SMD 0402")
		(tags "resistor SMD 0402")
		(property "Reference" "R15"
			(at -5.83 -2.25 90)
			(layer "F.SilkS")
			(effects
				(font
					(size 0.7 0.7)
					(thickness 0.15)
				)
				(justify right top)
			)
		)
		(property "Value" "R_51k_0402"
			(at -1.011843 1.772047 90)
			(layer "F.Fab")
			(effects
				(font
					(size 0.7 0.7)
					(thickness 0.15)
				)
				(justify right top)
			)
		)
		(property "Datasheet" "https://www.bourns.com/docs/product-datasheets/cr.pdf"
			(at 0 0 90)
			(layer "F.Fab")
			(hide yes)
			(effects
				(font
					(size 1.27 1.27)
					(thickness 0.15)
				)
			)
		)
		(property "Description" "SMD Chip Resistor, 51 kohm, ± 1%, 63 mW, 0402 [1005 Metric], Thick Film, General Purpose"
			(at 0 0 90)
			(layer "F.Fab")
			(hide yes)
			(effects
				(font
					(size 1.27 1.27)
					(thickness 0.15)
				)
			)
		)
		(property "MPN" "CR0402-FX-5102GLF"
			(at 0 0 270)
			(unlocked yes)
			(layer "F.Fab")
			(hide yes)
			(effects
				(font
					(size 1 1)
					(thickness 0.15)
				)
			)
		)
		(property "Manufacturer" "Bourns"
			(at 0 0 270)
			(unlocked yes)
			(layer "F.Fab")
			(hide yes)
			(effects
				(font
					(size 1 1)
					(thickness 0.15)
				)
			)
		)
		(property "License" "Apache-2.0"
			(at 0 0 270)
			(unlocked yes)
			(layer "F.Fab")
			(hide yes)
			(effects
				(font
					(size 1 1)
					(thickness 0.15)
				)
			)
		)
		(property "Author" "Antmicro"
			(at 0 0 270)
			(unlocked yes)
			(layer "F.Fab")
			(hide yes)
			(effects
				(font
					(size 1 1)
					(thickness 0.15)
				)
			)
		)
		(property "Val" "51k"
			(at 0 0 270)
			(unlocked yes)
			(layer "F.Fab")
			(hide yes)
			(effects
				(font
					(size 1 1)
					(thickness 0.15)
				)
			)
		)
		(property "Tolerance" "1%"
			(at 0 0 270)
			(unlocked yes)
			(layer "F.Fab")
			(hide yes)
			(effects
				(font
					(size 1 1)
					(thickness 0.15)
				)
			)
		)
		(sheetname "/DCDC/")
		(sheetfile "dcdc.kicad_sch")
		(attr smd)
		(fp_rect
			(start -0.925 -0.47)
			(end 0.925 0.47)
			(stroke
				(width 0.05)
				(type default)
			)
			(fill no)
			(layer "F.CrtYd")
		)
		(fp_rect
			(start -0.5 -0.25)
			(end 0.5 0.25)
			(stroke
				(width 0.15)
				(type solid)
			)
			(fill no)
			(layer "F.Fab")
		)
		(fp_text user "Author: Antmicro"
			(at -0.95 4.169 90)
			(layer "F.Fab")
			(effects
				(font
					(size 0.7 0.7)
					(thickness 0.15)
				)
				(justify right top)
			)
		)
		(fp_text user "License: Apache-2.0"
			(at -0.95 5.169 90)
			(layer "F.Fab")
			(effects
				(font
					(size 0.7 0.7)
					(thickness 0.15)
				)
				(justify right top)
			)
		)
		(fp_text user "${REFERENCE}"
			(at -0.95 3.168 90)
			(layer "F.Fab")
			(effects
				(font
					(size 0.7 0.7)
					(thickness 0.15)
				)
				(justify right top)
			)
		)
		(pad "1" smd roundrect
			(at -0.48 0 270)
			(size 0.59 0.64)
			(layers "F.Cu" "F.Mask" "F.Paste")
			(roundrect_rratio 0.25)
			(net 1 "GND")
			(pintype "passive")
		)
		(pad "2" smd roundrect
			(at 0.48 0 270)
			(size 0.59 0.64)
			(layers "F.Cu" "F.Mask" "F.Paste")
			(roundrect_rratio 0.25)
			(net 1205 "/DCDC/12V_MODE2")
			(pintype "passive")
		)
	)
	(footprint "antmicro-footprints:C_0805_2012Metric"
		(layer "F.Cu")
		(at 173.17 73.32 -90)
		(descr "Capacitor SMD 0805")
		(tags "capacitor SMD 0805")
		(property "Reference" "C303"
			(at 1.78449 -1.468678 90)
			(layer "F.SilkS")
			(effects
				(font
					(size 0.7 0.7)
					(thickness 0.15)
				)
				(justify right top)
			)
		)
		(property "Value" "C_22u_25V_0805"
			(at -2.055717 1.963152 90)
			(layer "F.Fab")
			(effects
				(font
					(size 0.7 0.7)
					(thickness 0.15)
				)
				(justify right top)
			)
		)
		(property "Datasheet" "https://product.samsungsem.com/mlcc/CL21A226MAYNNN.do"
			(at 0 0 90)
			(layer "F.Fab")
			(hide yes)
			(effects
				(font
					(size 1.27 1.27)
					(thickness 0.15)
				)
			)
		)
		(property "Description" "SMT Multilayer Ceramic Capacitor, 22uF, +/-20%, 25V, X5R, 0805 [2012 Metric]"
			(at 0 0 90)
			(layer "F.Fab")
			(hide yes)
			(effects
				(font
					(size 1.27 1.27)
					(thickness 0.15)
				)
			)
		)
		(property "MPN" "CL21A226MAYNNNE"
			(at 0 0 270)
			(unlocked yes)
			(layer "F.Fab")
			(hide yes)
			(effects
				(font
					(size 1 1)
					(thickness 0.15)
				)
			)
		)
		(property "Manufacturer" "Samsung Electro-Mechanics"
			(at 0 0 270)
			(unlocked yes)
			(layer "F.Fab")
			(hide yes)
			(effects
				(font
					(size 1 1)
					(thickness 0.15)
				)
			)
		)
		(property "License" "Apache-2.0"
			(at 0 0 270)
			(unlocked yes)
			(layer "F.Fab")
			(hide yes)
			(effects
				(font
					(size 1 1)
					(thickness 0.15)
				)
			)
		)
		(property "Author" "Antmicro"
			(at 0 0 270)
			(unlocked yes)
			(layer "F.Fab")
			(hide yes)
			(effects
				(font
					(size 1 1)
					(thickness 0.15)
				)
			)
		)
		(property "Val" "22u"
			(at 0 0 270)
			(unlocked yes)
			(layer "F.Fab")
			(hide yes)
			(effects
				(font
					(size 1 1)
					(thickness 0.15)
				)
			)
		)
		(property "Voltage" "25V"
			(at 0 0 270)
			(unlocked yes)
			(layer "F.Fab")
			(hide yes)
			(effects
				(font
					(size 1 1)
					(thickness 0.15)
				)
			)
		)
		(property "Dielectric" "X5R"
			(at 0 0 270)
			(unlocked yes)
			(layer "F.Fab")
			(hide yes)
			(effects
				(font
					(size 1 1)
					(thickness 0.15)
				)
			)
		)
		(property "Public" "False"
			(at 0 0 270)
			(unlocked yes)
			(layer "F.Fab")
			(hide yes)
			(effects
				(font
					(size 1 1)
					(thickness 0.15)
				)
			)
		)
		(component_classes
			(class "DCDC_20V")
		)
		(sheetname "/DCDC/")
		(sheetfile "dcdc.kicad_sch")
		(attr smd)
		(fp_line
			(start -0.3 0.7)
			(end 0.3 0.7)
			(stroke
				(width 0.15)
				(type solid)
			)
			(layer "F.SilkS")
		)
		(fp_line
			(start -0.3 -0.7)
			(end 0.3 -0.7)
			(stroke
				(width 0.15)
				(type solid)
			)
			(layer "F.SilkS")
		)
		(fp_rect
			(start 1.95 -0.9)
			(end -1.95 0.9)
			(stroke
				(width 0.05)
				(type default)
			)
			(fill no)
			(layer "F.CrtYd")
		)
		(fp_rect
			(start -0.95 -0.675)
			(end 0.95 0.675)
			(stroke
				(width 0.15)
				(type solid)
			)
			(fill no)
			(layer "F.Fab")
		)
		(fp_text user "${REFERENCE}"
			(at -1.9 3.947 90)
			(layer "F.Fab")
			(effects
				(font
					(size 0.7 0.7)
					(thickness 0.15)
				)
				(justify right top)
			)
		)
		(fp_text user "Author: Antmicro"
			(at -1.9 5.947 90)
			(layer "F.Fab")
			(effects
				(font
					(size 0.7 0.7)
					(thickness 0.15)
				)
				(justify right top)
			)
		)
		(fp_text user "License: Apache-2.0"
			(at -1.9 4.947 90)
			(layer "F.Fab")
			(effects
				(font
					(size 0.7 0.7)
					(thickness 0.15)
				)
				(justify right top)
			)
		)
		(pad "1" smd roundrect
			(at -1.1 0 270)
			(size 1.2 1.3)
			(layers "F.Cu" "F.Mask" "F.Paste")
			(roundrect_rratio 0.25)
			(net 1 "GND")
			(pintype "passive")
		)
		(pad "2" smd roundrect
			(at 1.1 0 270)
			(size 1.2 1.3)
			(layers "F.Cu" "F.Mask" "F.Paste")
			(roundrect_rratio 0.25)
			(net 1105 "/DCDC/20V_OUT")
			(pintype "passive")
		)
	)
	(footprint "antmicro-footprints:R_0402_1005Metric"
		(layer "F.Cu")
		(at 179.604468 86.725 -90)
		(descr "Resistor SMD 0402")
		(tags "resistor SMD 0402")
		(property "Reference" "R20"
			(at -2.96 0.32 90)
			(layer "F.SilkS")
			(effects
				(font
					(size 0.7 0.7)
					(thickness 0.15)
				)
				(justify right top)
			)
		)
		(property "Value" "R_100k_0402"
			(at -1.011843 1.772047 90)
			(layer "F.Fab")
			(effects
				(font
					(size 0.7 0.7)
					(thickness 0.15)
				)
				(justify right top)
			)
		)
		(property "Datasheet" "https://www.bourns.com/docs/product-datasheets/cr.pdf"
			(at 0 0 90)
			(layer "F.Fab")
			(hide yes)
			(effects
				(font
					(size 1.27 1.27)
					(thickness 0.15)
				)
			)
		)
		(property "Description" "SMD Chip Resistor, 100 kohm, ± 1%, 62.5 mW, 0402 [1005 Metric], Thick Film, General Purpose"
			(at 0 0 90)
			(layer "F.Fab")
			(hide yes)
			(effects
				(font
					(size 1.27 1.27)
					(thickness 0.15)
				)
			)
		)
		(property "MPN" "CR0402-FX-1003GLF"
			(at 0 0 270)
			(unlocked yes)
			(layer "F.Fab")
			(hide yes)
			(effects
				(font
					(size 1 1)
					(thickness 0.15)
				)
			)
		)
		(property "Manufacturer" "Bourns"
			(at 0 0 270)
			(unlocked yes)
			(layer "F.Fab")
			(hide yes)
			(effects
				(font
					(size 1 1)
					(thickness 0.15)
				)
			)
		)
		(property "License" "Apache-2.0"
			(at 0 0 270)
			(unlocked yes)
			(layer "F.Fab")
			(hide yes)
			(effects
				(font
					(size 1 1)
					(thickness 0.15)
				)
			)
		)
		(property "Author" "Antmicro"
			(at 0 0 270)
			(unlocked yes)
			(layer "F.Fab")
			(hide yes)
			(effects
				(font
					(size 1 1)
					(thickness 0.15)
				)
			)
		)
		(property "Val" "100k"
			(at 0 0 270)
			(unlocked yes)
			(layer "F.Fab")
			(hide yes)
			(effects
				(font
					(size 1 1)
					(thickness 0.15)
				)
			)
		)
		(property "Tolerance" "1%"
			(at 0 0 270)
			(unlocked yes)
			(layer "F.Fab")
			(hide yes)
			(effects
				(font
					(size 1 1)
					(thickness 0.15)
				)
			)
		)
		(component_classes
			(class "DCDC_SOM")
		)
		(sheetname "/DCDC/")
		(sheetfile "dcdc.kicad_sch")
		(attr smd)
		(fp_rect
			(start -0.925 -0.47)
			(end 0.925 0.47)
			(stroke
				(width 0.05)
				(type default)
			)
			(fill no)
			(layer "F.CrtYd")
		)
		(fp_rect
			(start -0.5 -0.25)
			(end 0.5 0.25)
			(stroke
				(width 0.15)
				(type solid)
			)
			(fill no)
			(layer "F.Fab")
		)
		(fp_text user "Author: Antmicro"
			(at -0.95 4.169 90)
			(layer "F.Fab")
			(effects
				(font
					(size 0.7 0.7)
					(thickness 0.15)
				)
				(justify right top)
			)
		)
		(fp_text user "License: Apache-2.0"
			(at -0.95 5.169 90)
			(layer "F.Fab")
			(effects
				(font
					(size 0.7 0.7)
					(thickness 0.15)
				)
				(justify right top)
			)
		)
		(fp_text user "${REFERENCE}"
			(at -0.95 3.168 90)
			(layer "F.Fab")
			(effects
				(font
					(size 0.7 0.7)
					(thickness 0.15)
				)
				(justify right top)
			)
		)
		(pad "1" smd roundrect
			(at -0.48 0 270)
			(size 0.59 0.64)
			(layers "F.Cu" "F.Mask" "F.Paste")
			(roundrect_rratio 0.25)
			(net 1 "GND")
			(pintype "passive")
		)
		(pad "2" smd roundrect
			(at 0.48 0 270)
			(size 0.59 0.64)
			(layers "F.Cu" "F.Mask" "F.Paste")
			(roundrect_rratio 0.25)
			(net 1207 "/DCDC/16V_MODE1")
			(pintype "passive")
		)
	)
	(footprint "antmicro-footprints:TP_SMD_0.75mm"
		(layer "F.Cu")
		(at 161.72 57.14)
		(property "Reference" "TP64"
			(at -0.65 2.16 90)
			(layer "F.SilkS")
			(hide yes)
			(effects
				(font
					(size 0.7 0.7)
					(thickness 0.15)
				)
				(justify left bottom)
			)
		)
		(property "Value" "TP_0.75mm_SMD"
			(at 0 1.2 0)
			(layer "F.Fab")
			(effects
				(font
					(size 0.7 0.7)
					(thickness 0.15)
				)
				(justify left bottom)
			)
		)
		(property "Description" "SMT test point"
			(at 0 0 0)
			(layer "F.Fab")
			(hide yes)
			(effects
				(font
					(size 1.27 1.27)
					(thickness 0.15)
				)
			)
		)
		(property "MPN" ""
			(at 0 0 0)
			(unlocked yes)
			(layer "F.Fab")
			(hide yes)
			(effects
				(font
					(size 1 1)
					(thickness 0.15)
				)
			)
		)
		(property "Manufacturer" ""
			(at 0 0 0)
			(unlocked yes)
			(layer "F.Fab")
			(hide yes)
			(effects
				(font
					(size 1 1)
					(thickness 0.15)
				)
			)
		)
		(property "Author" "Antmicro"
			(at 0 0 0)
			(unlocked yes)
			(layer "F.Fab")
			(hide yes)
			(effects
				(font
					(size 1 1)
					(thickness 0.15)
				)
			)
		)
		(property "License" "Apache-2.0"
			(at 0 0 0)
			(unlocked yes)
			(layer "F.Fab")
			(hide yes)
			(effects
				(font
					(size 1 1)
					(thickness 0.15)
				)
			)
		)
		(sheetname "/Power/")
		(sheetfile "power.kicad_sch")
		(attr exclude_from_pos_files exclude_from_bom)
		(fp_circle
			(center 0 0)
			(end 0.475 0)
			(stroke
				(width 0.05)
				(type default)
			)
			(fill no)
			(layer "F.CrtYd")
		)
		(fp_text user "${REFERENCE}"
			(at -0.4 2.7 0)
			(layer "F.Fab")
			(effects
				(font
					(size 0.7 0.7)
					(thickness 0.15)
				)
				(justify left bottom)
			)
		)
		(fp_text user "License: Apache-2.0"
			(at -0.4 5.101 0)
			(layer "F.Fab")
			(effects
				(font
					(size 0.7 0.7)
					(thickness 0.15)
				)
				(justify left bottom)
			)
		)
		(fp_text user "Author: Antmicro"
			(at -0.4 3.901 0)
			(layer "F.Fab")
			(effects
				(font
					(size 0.7 0.7)
					(thickness 0.15)
				)
				(justify left bottom)
			)
		)
		(pad "1" smd circle
			(at 0 0)
			(size 0.75 0.75)
			(layers "F.Cu" "F.Mask")
			(net 282 "+1V15")
			(pinfunction "1")
			(pintype "passive")
		)
	)
	(footprint "antmicro-footprints:R_0402_1005Metric"
		(layer "F.Cu")
		(at 213.8 107 -90)
		(descr "Resistor SMD 0402")
		(tags "resistor SMD 0402")
		(property "Reference" "R255"
			(at -1.2 1.4 90)
			(layer "F.SilkS")
			(effects
				(font
					(size 0.7 0.7)
					(thickness 0.15)
				)
				(justify right top)
			)
		)
		(property "Value" "R_200k_0402"
			(at -1.011843 1.772046 90)
			(layer "F.Fab")
			(effects
				(font
					(size 0.7 0.7)
					(thickness 0.15)
				)
				(justify right top)
			)
		)
		(property "Datasheet" "https://www.bourns.com/docs/product-datasheets/cr.pdf"
			(at 0 0 90)
			(layer "F.Fab")
			(hide yes)
			(effects
				(font
					(size 1.27 1.27)
					(thickness 0.15)
				)
			)
		)
		(property "Description" "SMD Chip Resistor, 200 kohm, ± 1%, 62.5 mW, 0402 [1005 Metric], Thick Film, General Purpose"
			(at 0 0 90)
			(layer "F.Fab")
			(hide yes)
			(effects
				(font
					(size 1.27 1.27)
					(thickness 0.15)
				)
			)
		)
		(property "Manufacturer" "Bourns"
			(at 0 0 270)
			(unlocked yes)
			(layer "F.Fab")
			(hide yes)
			(effects
				(font
					(size 1 1)
					(thickness 0.15)
				)
			)
		)
		(property "MPN" "CR0402-FX-2003GLF"
			(at 0 0 270)
			(unlocked yes)
			(layer "F.Fab")
			(hide yes)
			(effects
				(font
					(size 1 1)
					(thickness 0.15)
				)
			)
		)
		(property "Val" "200k"
			(at 0 0 270)
			(unlocked yes)
			(layer "F.Fab")
			(hide yes)
			(effects
				(font
					(size 1 1)
					(thickness 0.15)
				)
			)
		)
		(property "License" "Apache-2.0"
			(at 0 0 270)
			(unlocked yes)
			(layer "F.Fab")
			(hide yes)
			(effects
				(font
					(size 1 1)
					(thickness 0.15)
				)
			)
		)
		(property "Author" "Antmicro"
			(at 0 0 270)
			(unlocked yes)
			(layer "F.Fab")
			(hide yes)
			(effects
				(font
					(size 1 1)
					(thickness 0.15)
				)
			)
		)
		(property "Tolerance" "1%"
			(at 0 0 270)
			(unlocked yes)
			(layer "F.Fab")
			(hide yes)
			(effects
				(font
					(size 1 1)
					(thickness 0.15)
				)
			)
		)
		(sheetname "/Recovery USB/")
		(sheetfile "recovery_usb.kicad_sch")
		(attr smd)
		(fp_poly
			(pts
				(xy -0.925 -0.47) (xy -0.925 0.47) (xy 0.925 0.47) (xy 0.925 -0.47)
			)
			(stroke
				(width 0.05)
				(type default)
			)
			(fill no)
			(layer "F.CrtYd")
		)
		(fp_poly
			(pts
				(xy -0.5 -0.25) (xy -0.5 0.25) (xy 0.5 0.25) (xy 0.5 -0.25)
			)
			(stroke
				(width 0.15)
				(type solid)
			)
			(fill no)
			(layer "F.Fab")
		)
		(fp_text user "${REFERENCE}"
			(at -0.95 3.168 90)
			(layer "F.Fab")
			(effects
				(font
					(size 0.7 0.7)
					(thickness 0.15)
				)
				(justify right top)
			)
		)
		(fp_text user "License: Apache-2.0"
			(at -0.949999 5.169 90)
			(layer "F.Fab")
			(effects
				(font
					(size 0.7 0.7)
					(thickness 0.15)
				)
				(justify right top)
			)
		)
		(fp_text user "Author: Antmicro"
			(at -0.95 4.169 90)
			(layer "F.Fab")
			(effects
				(font
					(size 0.7 0.7)
					(thickness 0.15)
				)
				(justify right top)
			)
		)
		(pad "1" smd roundrect
			(at -0.48 0 270)
			(size 0.59 0.64)
			(layers "F.Cu" "F.Mask" "F.Paste")
			(roundrect_rratio 0.25)
			(net 1013 "/Recovery USB/USBC2_DIR")
			(pintype "passive")
		)
		(pad "2" smd roundrect
			(at 0.48 0 270)
			(size 0.59 0.64)
			(layers "F.Cu" "F.Mask" "F.Paste")
			(roundrect_rratio 0.25)
			(net 2 "+3V3")
			(pintype "passive")
		)
	)
	(footprint "antmicro-footprints:USON-10_2.5x1mm_P0.5mm"
		(layer "F.Cu")
		(at 160.22 144.23 180)
		(descr "USON-10 2.5x1mm_ Pitch 0.5mm")
		(tags "USON-10 2.5x1mm Pitch 0.5mm")
		(property "Reference" "U16"
			(at -0.88 2.43 0)
			(layer "F.SilkS")
			(effects
				(font
					(size 0.7 0.7)
					(thickness 0.15)
				)
				(justify right top)
			)
		)
		(property "Value" "TPD4E05U06QDQARQ1"
			(at 0.018 2.499 0)
			(layer "F.Fab")
			(effects
				(font
					(size 0.7 0.7)
					(thickness 0.15)
				)
				(justify right top)
			)
		)
		(property "Datasheet" "https://www.ti.com/lit/ds/symlink/tpd4e05u06-q1.pdf?HQS=dis-mous-null-mousermode-dsf-pf-null-wwe&ts=1663591265741&ref_url=https%253A%252F%252Fwww.mouser.com%252F"
			(at 0 0 0)
			(layer "F.Fab")
			(hide yes)
			(effects
				(font
					(size 1.27 1.27)
					(thickness 0.15)
				)
			)
		)
		(property "Description" "TVS diode array, 12 kV, USON-10, 5.5 V, 0.5 pF"
			(at 0 0 0)
			(layer "F.Fab")
			(hide yes)
			(effects
				(font
					(size 1.27 1.27)
					(thickness 0.15)
				)
			)
		)
		(property "Manufacturer" "Texas Instruments"
			(at 0 0 0)
			(unlocked yes)
			(layer "F.Fab")
			(hide yes)
			(effects
				(font
					(size 1 1)
					(thickness 0.15)
				)
			)
		)
		(property "MPN" "TPD4E05U06QDQARQ1"
			(at 0 0 0)
			(unlocked yes)
			(layer "F.Fab")
			(hide yes)
			(effects
				(font
					(size 1 1)
					(thickness 0.15)
				)
			)
		)
		(property "Author" "Antmicro"
			(at 0 0 0)
			(unlocked yes)
			(layer "F.Fab")
			(hide yes)
			(effects
				(font
					(size 1 1)
					(thickness 0.15)
				)
			)
		)
		(property "License" "Apache-2.0"
			(at 0 0 0)
			(unlocked yes)
			(layer "F.Fab")
			(hide yes)
			(effects
				(font
					(size 1 1)
					(thickness 0.15)
				)
			)
		)
		(sheetname "/Peripherals/")
		(sheetfile "peripherals.kicad_sch")
		(attr smd)
		(fp_line
			(start 0.498 1.398)
			(end -0.5 1.398)
			(stroke
				(width 0.15)
				(type solid)
			)
			(layer "F.SilkS")
		)
		(fp_line
			(start 0.498 -1.401)
			(end -0.5 -1.401)
			(stroke
				(width 0.15)
				(type solid)
			)
			(layer "F.SilkS")
		)
		(fp_circle
			(center -0.68 -1.27)
			(end -0.63 -1.27)
			(stroke
				(width 0.15)
				(type solid)
			)
			(fill yes)
			(layer "F.SilkS")
		)
		(fp_rect
			(start -0.8 -1.5)
			(end 0.8 1.499)
			(stroke
				(width 0.05)
				(type solid)
			)
			(fill no)
			(layer "F.CrtYd")
		)
		(fp_line
			(start 0.498 -1.25)
			(end 0.498 1.249)
			(stroke
				(width 0.15)
				(type solid)
			)
			(layer "F.Fab")
		)
		(fp_line
			(start 0.498 -1.25)
			(end -0.25 -1.25)
			(stroke
				(width 0.15)
				(type solid)
			)
			(layer "F.Fab")
		)
		(fp_line
			(start -0.25 -1.25)
			(end -0.5 -1)
			(stroke
				(width 0.15)
				(type solid)
			)
			(layer "F.Fab")
		)
		(fp_line
			(start -0.5 1.249)
			(end 0.498 1.249)
			(stroke
				(width 0.15)
				(type solid)
			)
			(layer "F.Fab")
		)
		(fp_line
			(start -0.5 -1)
			(end -0.5 1.249)
			(stroke
				(width 0.15)
				(type solid)
			)
			(layer "F.Fab")
		)
		(fp_text user "Author: Antmicro"
			(at -0.802 5.7 0)
			(layer "F.Fab")
			(effects
				(font
					(size 0.7 0.7)
					(thickness 0.15)
				)
				(justify right top)
			)
		)
		(fp_text user "License: Apache-2.0"
			(at -0.802 6.9 0)
			(layer "F.Fab")
			(effects
				(font
					(size 0.7 0.7)
					(thickness 0.15)
				)
				(justify right top)
			)
		)
		(fp_text user "${REFERENCE}"
			(at -0.802 4.498 0)
			(layer "F.Fab")
			(effects
				(font
					(size 0.7 0.7)
					(thickness 0.15)
				)
				(justify right top)
			)
		)
		(pad "1" smd roundrect
			(at -0.387 -1 90)
			(size 0.25 0.55)
			(layers "F.Cu" "F.Mask" "F.Paste")
			(roundrect_rratio 0.25)
			(net 1 "GND")
			(pintype "passive")
		)
		(pad "2" smd roundrect
			(at -0.387 -0.5 90)
			(size 0.25 0.55)
			(layers "F.Cu" "F.Mask" "F.Paste")
			(roundrect_rratio 0.25)
			(net 279 "/Peripherals/FAN_TACH_5V")
			(pintype "passive")
		)
		(pad "3" smd roundrect
			(at -0.387 0 90)
			(size 0.4 0.55)
			(layers "F.Cu" "F.Mask" "F.Paste")
			(roundrect_rratio 0.25)
			(net 1 "GND")
			(pintype "power_in")
		)
		(pad "4" smd roundrect
			(at -0.387 0.498 90)
			(size 0.25 0.55)
			(layers "F.Cu" "F.Mask" "F.Paste")
			(roundrect_rratio 0.25)
			(net 281 "/Peripherals/FAN_PWM_5V")
			(pintype "passive")
		)
		(pad "5" smd roundrect
			(at -0.387 0.998 90)
			(size 0.25 0.55)
			(layers "F.Cu" "F.Mask" "F.Paste")
			(roundrect_rratio 0.25)
			(net 1 "GND")
			(pintype "passive")
		)
		(pad "6" smd roundrect
			(at 0.385 0.998 90)
			(size 0.25 0.55)
			(layers "F.Cu" "F.Mask" "F.Paste")
			(roundrect_rratio 0.25)
			(net 1 "GND")
			(pintype "passive")
		)
		(pad "7" smd roundrect
			(at 0.385 0.498 90)
			(size 0.25 0.55)
			(layers "F.Cu" "F.Mask" "F.Paste")
			(roundrect_rratio 0.25)
			(net 281 "/Peripherals/FAN_PWM_5V")
			(pintype "passive")
		)
		(pad "8" smd roundrect
			(at 0.385 0 90)
			(size 0.4 0.55)
			(layers "F.Cu" "F.Mask" "F.Paste")
			(roundrect_rratio 0.25)
			(net 1 "GND")
			(pintype "passive")
		)
		(pad "9" smd roundrect
			(at 0.385 -0.5 90)
			(size 0.25 0.55)
			(layers "F.Cu" "F.Mask" "F.Paste")
			(roundrect_rratio 0.25)
			(net 279 "/Peripherals/FAN_TACH_5V")
			(pintype "passive")
		)
		(pad "10" smd roundrect
			(at 0.385 -1 90)
			(size 0.25 0.55)
			(layers "F.Cu" "F.Mask" "F.Paste")
			(roundrect_rratio 0.25)
			(net 1 "GND")
			(pintype "passive")
		)
	)
	(footprint "antmicro-footprints:R_0402_1005Metric"
		(layer "F.Cu")
		(at 90.03 149.18)
		(descr "Resistor SMD 0402")
		(tags "resistor SMD 0402")
		(property "Reference" "R8"
			(at -1.81 2.925001 0)
			(layer "F.SilkS")
			(effects
				(font
					(size 0.7 0.7)
					(thickness 0.15)
				)
				(justify left bottom)
			)
		)
		(property "Value" "R_33R_0402"
			(at -1.011843 1.772046 0)
			(layer "F.Fab")
			(effects
				(font
					(size 0.7 0.7)
					(thickness 0.15)
				)
				(justify left bottom)
			)
		)
		(property "Datasheet" "https://www.bourns.com/docs/product-datasheets/cr.pdf"
			(at 0 0 0)
			(layer "F.Fab")
			(hide yes)
			(effects
				(font
					(size 1.27 1.27)
					(thickness 0.15)
				)
			)
		)
		(property "Description" "SMD Chip Resistor, 33 ohm, ± 1%, 62.5 mW, 0402 [1005 Metric], Thick Film, General Purpose"
			(at 0 0 0)
			(layer "F.Fab")
			(hide yes)
			(effects
				(font
					(size 1.27 1.27)
					(thickness 0.15)
				)
			)
		)
		(property "MPN" "CR0402-FX-33R0GLF"
			(at 0 0 0)
			(unlocked yes)
			(layer "F.Fab")
			(hide yes)
			(effects
				(font
					(size 1 1)
					(thickness 0.15)
				)
			)
		)
		(property "Manufacturer" "Bourns"
			(at 0 0 0)
			(unlocked yes)
			(layer "F.Fab")
			(hide yes)
			(effects
				(font
					(size 1 1)
					(thickness 0.15)
				)
			)
		)
		(property "License" "Apache-2.0"
			(at 0 0 0)
			(unlocked yes)
			(layer "F.Fab")
			(hide yes)
			(effects
				(font
					(size 1 1)
					(thickness 0.15)
				)
			)
		)
		(property "Author" "Antmicro"
			(at 0 0 0)
			(unlocked yes)
			(layer "F.Fab")
			(hide yes)
			(effects
				(font
					(size 1 1)
					(thickness 0.15)
				)
			)
		)
		(property "Val" "33R"
			(at 0 0 0)
			(unlocked yes)
			(layer "F.Fab")
			(hide yes)
			(effects
				(font
					(size 1 1)
					(thickness 0.15)
				)
			)
		)
		(property "Tolerance" "1%"
			(at 0 0 0)
			(unlocked yes)
			(layer "F.Fab")
			(hide yes)
			(effects
				(font
					(size 1 1)
					(thickness 0.15)
				)
			)
		)
		(sheetname "/SoM_IO2/")
		(sheetfile "som_io2.kicad_sch")
		(attr smd)
		(fp_poly
			(pts
				(xy -0.925 -0.47) (xy -0.925 0.47) (xy 0.925 0.47) (xy 0.925 -0.47)
			)
			(stroke
				(width 0.05)
				(type default)
			)
			(fill no)
			(layer "F.CrtYd")
		)
		(fp_poly
			(pts
				(xy -0.5 -0.25) (xy -0.5 0.25) (xy 0.5 0.25) (xy 0.5 -0.25)
			)
			(stroke
				(width 0.15)
				(type solid)
			)
			(fill no)
			(layer "F.Fab")
		)
		(fp_text user "Author: Antmicro"
			(at -0.95 4.169 0)
			(layer "F.Fab")
			(effects
				(font
					(size 0.7 0.7)
					(thickness 0.15)
				)
				(justify left bottom)
			)
		)
		(fp_text user "License: Apache-2.0"
			(at -0.949999 5.169 0)
			(layer "F.Fab")
			(effects
				(font
					(size 0.7 0.7)
					(thickness 0.15)
				)
				(justify left bottom)
			)
		)
		(fp_text user "${REFERENCE}"
			(at -0.95 3.168 0)
			(layer "F.Fab")
			(effects
				(font
					(size 0.7 0.7)
					(thickness 0.15)
				)
				(justify left bottom)
			)
		)
		(pad "1" smd roundrect
			(at -0.48 0)
			(size 0.59 0.64)
			(layers "F.Cu" "F.Mask" "F.Paste")
			(roundrect_rratio 0.25)
			(net 897 "/SoM_IO2/C2_CLK+")
			(pintype "passive")
		)
		(pad "2" smd roundrect
			(at 0.48 0)
			(size 0.59 0.64)
			(layers "F.Cu" "F.Mask" "F.Paste")
			(roundrect_rratio 0.25)
			(net 898 "/SoM_IO2/C2_REFCLK+")
			(pintype "passive")
		)
	)
	(footprint "antmicro-footprints:C_0402_1005Metric"
		(layer "F.Cu")
		(at 207 76.2 90)
		(descr "Capacitor SMD 0402")
		(tags "capacitor SMD 0402")
		(property "Reference" "C143"
			(at 0.9 0.4 90)
			(layer "F.SilkS")
			(effects
				(font
					(size 0.7 0.7)
					(thickness 0.15)
				)
				(justify left bottom)
			)
		)
		(property "Value" "C_100n_0402"
			(at -1.022927 2.155213 90)
			(layer "F.Fab")
			(effects
				(font
					(size 0.7 0.7)
					(thickness 0.15)
				)
				(justify left bottom)
			)
		)
		(property "Datasheet" "https://www.murata.com/products/productdetail?partno=GRM155R61H104KE14%23"
			(at 0 0 90)
			(layer "F.Fab")
			(hide yes)
			(effects
				(font
					(size 1.27 1.27)
					(thickness 0.15)
				)
			)
		)
		(property "Description" "SMD Multilayer Ceramic Capacitor, 0.1 µF, 50 V, 0402 [1005 Metric], ± 10%, X5R, GRM Series"
			(at 0 0 90)
			(layer "F.Fab")
			(hide yes)
			(effects
				(font
					(size 1.27 1.27)
					(thickness 0.15)
				)
			)
		)
		(property "MPN" "GRM155R61H104KE14D"
			(at 0 0 90)
			(unlocked yes)
			(layer "F.Fab")
			(hide yes)
			(effects
				(font
					(size 1 1)
					(thickness 0.15)
				)
			)
		)
		(property "Manufacturer" "Murata"
			(at 0 0 90)
			(unlocked yes)
			(layer "F.Fab")
			(hide yes)
			(effects
				(font
					(size 1 1)
					(thickness 0.15)
				)
			)
		)
		(property "Val" "100n"
			(at 0 0 90)
			(unlocked yes)
			(layer "F.Fab")
			(hide yes)
			(effects
				(font
					(size 1 1)
					(thickness 0.15)
				)
			)
		)
		(property "License" "Apache-2.0"
			(at 0 0 90)
			(unlocked yes)
			(layer "F.Fab")
			(hide yes)
			(effects
				(font
					(size 1 1)
					(thickness 0.15)
				)
			)
		)
		(property "Author" "Antmicro"
			(at 0 0 90)
			(unlocked yes)
			(layer "F.Fab")
			(hide yes)
			(effects
				(font
					(size 1 1)
					(thickness 0.15)
				)
			)
		)
		(property "Voltage" "50V"
			(at 0 0 90)
			(unlocked yes)
			(layer "F.Fab")
			(hide yes)
			(effects
				(font
					(size 1 1)
					(thickness 0.15)
				)
			)
		)
		(property "Dielectric" "X5R"
			(at 0 0 90)
			(unlocked yes)
			(layer "F.Fab")
			(hide yes)
			(effects
				(font
					(size 1 1)
					(thickness 0.15)
				)
			)
		)
		(sheetname "/USB Debug, PD/")
		(sheetfile "usb_debug_pd.kicad_sch")
		(attr smd)
		(fp_rect
			(start -0.925 -0.47)
			(end 0.925 0.47)
			(stroke
				(width 0.05)
				(type default)
			)
			(fill no)
			(layer "F.CrtYd")
		)
		(fp_line
			(start 0.504 -0.25)
			(end 0.504 0.248)
			(stroke
				(width 0.15)
				(type solid)
			)
			(layer "F.Fab")
		)
		(fp_line
			(start -0.494 -0.25)
			(end 0.504 -0.25)
			(stroke
				(width 0.15)
				(type solid)
			)
			(layer "F.Fab")
		)
		(fp_line
			(start 0.504 0.248)
			(end -0.494 0.248)
			(stroke
				(width 0.15)
				(type solid)
			)
			(layer "F.Fab")
		)
		(fp_line
			(start -0.494 0.248)
			(end -0.494 -0.25)
			(stroke
				(width 0.15)
				(type solid)
			)
			(layer "F.Fab")
		)
		(fp_text user "${REFERENCE}"
			(at -0.939 4.599 90)
			(layer "F.Fab")
			(effects
				(font
					(size 0.7 0.7)
					(thickness 0.15)
				)
				(justify left bottom)
			)
		)
		(fp_text user "License: Apache-2.0"
			(at -0.939 5.799 90)
			(layer "F.Fab")
			(effects
				(font
					(size 0.7 0.7)
					(thickness 0.15)
				)
				(justify left bottom)
			)
		)
		(fp_text user "Author: Antmicro"
			(at -0.939 3.399 90)
			(layer "F.Fab")
			(effects
				(font
					(size 0.7 0.7)
					(thickness 0.15)
				)
				(justify left bottom)
			)
		)
		(pad "1" smd roundrect
			(at -0.48 0 90)
			(size 0.59 0.64)
			(layers "F.Cu" "F.Mask" "F.Paste")
			(roundrect_rratio 0.25)
			(net 525 "/Power/USBPD2_HV")
			(pintype "passive")
		)
		(pad "2" smd roundrect
			(at 0.48 0 90)
			(size 0.59 0.64)
			(layers "F.Cu" "F.Mask" "F.Paste")
			(roundrect_rratio 0.25)
			(net 1 "GND")
			(pintype "passive")
		)
	)
	(footprint "antmicro-footprints:C_0603_1608Metric_EIA"
		(layer "F.Cu")
		(at 186.94 127.3 -90)
		(descr "Capacitor SMD 0603, IPC-7351 Density Level A")
		(tags "Capacitor 0603")
		(property "Reference" "C76"
			(at 1.1 0.34 90)
			(layer "F.SilkS")
			(effects
				(font
					(size 0.7 0.7)
					(thickness 0.15)
				)
				(justify right top)
			)
		)
		(property "Value" "C_22u_16V_0603"
			(at -1.42757 1.770288 90)
			(layer "F.Fab")
			(effects
				(font
					(size 0.7 0.7)
					(thickness 0.15)
				)
				(justify right top)
			)
		)
		(property "Datasheet" "https://product.samsungsem.com/mlcc/CL10A226MO7JZN.do"
			(at 0 0 90)
			(layer "F.Fab")
			(hide yes)
			(effects
				(font
					(size 1.27 1.27)
					(thickness 0.15)
				)
			)
		)
		(property "Description" "SMD Multilayer Ceramic Capacitor"
			(at 0 0 90)
			(layer "F.Fab")
			(hide yes)
			(effects
				(font
					(size 1.27 1.27)
					(thickness 0.15)
				)
			)
		)
		(property "MPN" "CL10A226MO7JZNC"
			(at 0 0 90)
			(unlocked yes)
			(layer "F.Fab")
			(hide yes)
			(effects
				(font
					(size 1 1)
					(thickness 0.15)
				)
			)
		)
		(property "Manufacturer" "Samsung Electro-Mechanics"
			(at 0 0 90)
			(unlocked yes)
			(layer "F.Fab")
			(hide yes)
			(effects
				(font
					(size 1 1)
					(thickness 0.15)
				)
			)
		)
		(property "License" "Apache-2.0"
			(at 0 0 90)
			(unlocked yes)
			(layer "F.Fab")
			(hide yes)
			(effects
				(font
					(size 1 1)
					(thickness 0.15)
				)
			)
		)
		(property "Author" "Antmicro"
			(at 0 0 90)
			(unlocked yes)
			(layer "F.Fab")
			(hide yes)
			(effects
				(font
					(size 1 1)
					(thickness 0.15)
				)
			)
		)
		(property "Val" "22u"
			(at 0 0 90)
			(unlocked yes)
			(layer "F.Fab")
			(hide yes)
			(effects
				(font
					(size 1 1)
					(thickness 0.15)
				)
			)
		)
		(property "Voltage" "16V"
			(at 0 0 90)
			(unlocked yes)
			(layer "F.Fab")
			(hide yes)
			(effects
				(font
					(size 1 1)
					(thickness 0.15)
				)
			)
		)
		(property "Dielectric" ""
			(at 0 0 90)
			(unlocked yes)
			(layer "F.Fab")
			(hide yes)
			(effects
				(font
					(size 1 1)
					(thickness 0.15)
				)
			)
		)
		(property "Public" "False"
			(at 0 0 90)
			(unlocked yes)
			(layer "F.Fab")
			(hide yes)
			(effects
				(font
					(size 1 1)
					(thickness 0.15)
				)
			)
		)
		(component_classes
			(class "DCDC_1V15")
		)
		(sheetname "/DCDC/")
		(sheetfile "dcdc.kicad_sch")
		(attr smd)
		(fp_line
			(start -0.15 0.55)
			(end 0.15 0.55)
			(stroke
				(width 0.15)
				(type solid)
			)
			(layer "F.SilkS")
		)
		(fp_line
			(start -0.15 -0.55)
			(end 0.15 -0.55)
			(stroke
				(width 0.15)
				(type solid)
			)
			(layer "F.SilkS")
		)
		(fp_rect
			(start -1.25 -0.65)
			(end 1.25 0.65)
			(stroke
				(width 0.05)
				(type solid)
			)
			(fill no)
			(layer "F.CrtYd")
		)
		(fp_rect
			(start -0.8 -0.45)
			(end 0.8 0.45)
			(stroke
				(width 0.15)
				(type solid)
			)
			(fill no)
			(layer "F.Fab")
		)
		(fp_text user "License: Apache-2.0"
			(at -1.682 5.895 90)
			(layer "F.Fab")
			(effects
				(font
					(size 0.7 0.7)
					(thickness 0.15)
				)
				(justify right top)
			)
		)
		(fp_text user "Author: Antmicro"
			(at -1.682 4.894 90)
			(layer "F.Fab")
			(effects
				(font
					(size 0.7 0.7)
					(thickness 0.15)
				)
				(justify right top)
			)
		)
		(fp_text user "${REFERENCE}"
			(at -1.682 3.895 90)
			(layer "F.Fab")
			(effects
				(font
					(size 0.7 0.7)
					(thickness 0.15)
				)
				(justify right top)
			)
		)
		(pad "1" smd roundrect
			(at -0.7 0 270)
			(size 0.8 1.1)
			(layers "F.Cu" "F.Mask" "F.Paste")
			(roundrect_rratio 0.2)
			(net 1 "GND")
			(pintype "passive")
		)
		(pad "2" smd roundrect
			(at 0.7 0 270)
			(size 0.8 1.1)
			(layers "F.Cu" "F.Mask" "F.Paste")
			(roundrect_rratio 0.2)
			(net 5 "+5V")
			(pintype "passive")
		)
	)
	(footprint "antmicro-footprints:R_0402_1005Metric"
		(layer "F.Cu")
		(at 90.03 148.199999)
		(descr "Resistor SMD 0402")
		(tags "resistor SMD 0402")
		(property "Reference" "R190"
			(at -1.83 2.800001 0)
			(layer "F.SilkS")
			(effects
				(font
					(size 0.7 0.7)
					(thickness 0.15)
				)
				(justify left bottom)
			)
		)
		(property "Value" "R_33R_0402"
			(at -1.011843 1.772046 0)
			(layer "F.Fab")
			(effects
				(font
					(size 0.7 0.7)
					(thickness 0.15)
				)
				(justify left bottom)
			)
		)
		(property "Datasheet" "https://www.bourns.com/docs/product-datasheets/cr.pdf"
			(at 0 0 0)
			(layer "F.Fab")
			(hide yes)
			(effects
				(font
					(size 1.27 1.27)
					(thickness 0.15)
				)
			)
		)
		(property "Description" "SMD Chip Resistor, 33 ohm, ± 1%, 62.5 mW, 0402 [1005 Metric], Thick Film, General Purpose"
			(at 0 0 0)
			(layer "F.Fab")
			(hide yes)
			(effects
				(font
					(size 1.27 1.27)
					(thickness 0.15)
				)
			)
		)
		(property "MPN" "CR0402-FX-33R0GLF"
			(at 0 0 0)
			(unlocked yes)
			(layer "F.Fab")
			(hide yes)
			(effects
				(font
					(size 1 1)
					(thickness 0.15)
				)
			)
		)
		(property "Manufacturer" "Bourns"
			(at 0 0 0)
			(unlocked yes)
			(layer "F.Fab")
			(hide yes)
			(effects
				(font
					(size 1 1)
					(thickness 0.15)
				)
			)
		)
		(property "License" "Apache-2.0"
			(at 0 0 0)
			(unlocked yes)
			(layer "F.Fab")
			(hide yes)
			(effects
				(font
					(size 1 1)
					(thickness 0.15)
				)
			)
		)
		(property "Author" "Antmicro"
			(at 0 0 0)
			(unlocked yes)
			(layer "F.Fab")
			(hide yes)
			(effects
				(font
					(size 1 1)
					(thickness 0.15)
				)
			)
		)
		(property "Val" "33R"
			(at 0 0 0)
			(unlocked yes)
			(layer "F.Fab")
			(hide yes)
			(effects
				(font
					(size 1 1)
					(thickness 0.15)
				)
			)
		)
		(property "Tolerance" "1%"
			(at 0 0 0)
			(unlocked yes)
			(layer "F.Fab")
			(hide yes)
			(effects
				(font
					(size 1 1)
					(thickness 0.15)
				)
			)
		)
		(sheetname "/SoM_IO2/")
		(sheetfile "som_io2.kicad_sch")
		(attr smd)
		(fp_poly
			(pts
				(xy -0.925 -0.47) (xy -0.925 0.47) (xy 0.925 0.47) (xy 0.925 -0.47)
			)
			(stroke
				(width 0.05)
				(type default)
			)
			(fill no)
			(layer "F.CrtYd")
		)
		(fp_poly
			(pts
				(xy -0.5 -0.25) (xy -0.5 0.25) (xy 0.5 0.25) (xy 0.5 -0.25)
			)
			(stroke
				(width 0.15)
				(type solid)
			)
			(fill no)
			(layer "F.Fab")
		)
		(fp_text user "${REFERENCE}"
			(at -0.95 3.168 0)
			(layer "F.Fab")
			(effects
				(font
					(size 0.7 0.7)
					(thickness 0.15)
				)
				(justify left bottom)
			)
		)
		(fp_text user "License: Apache-2.0"
			(at -0.949999 5.169 0)
			(layer "F.Fab")
			(effects
				(font
					(size 0.7 0.7)
					(thickness 0.15)
				)
				(justify left bottom)
			)
		)
		(fp_text user "Author: Antmicro"
			(at -0.95 4.169 0)
			(layer "F.Fab")
			(effects
				(font
					(size 0.7 0.7)
					(thickness 0.15)
				)
				(justify left bottom)
			)
		)
		(pad "1" smd roundrect
			(at -0.48 0)
			(size 0.59 0.64)
			(layers "F.Cu" "F.Mask" "F.Paste")
			(roundrect_rratio 0.25)
			(net 1001 "/SoM_IO2/C2_CLK-")
			(pintype "passive")
		)
		(pad "2" smd roundrect
			(at 0.48 0)
			(size 0.59 0.64)
			(layers "F.Cu" "F.Mask" "F.Paste")
			(roundrect_rratio 0.25)
			(net 1002 "/SoM_IO2/C2_REFCLK-")
			(pintype "passive")
		)
	)
	(footprint "antmicro-footprints:R_0402_1005Metric"
		(layer "F.Cu")
		(at 141.7 111.72 -90)
		(descr "Resistor SMD 0402")
		(tags "resistor SMD 0402")
		(property "Reference" "R406"
			(at 0.78 0.4 90)
			(layer "F.SilkS")
			(effects
				(font
					(size 0.7 0.7)
					(thickness 0.15)
				)
				(justify right top)
			)
		)
		(property "Value" "R_0R_0402"
			(at -1.011843 1.772047 90)
			(layer "F.Fab")
			(effects
				(font
					(size 0.7 0.7)
					(thickness 0.15)
				)
				(justify right top)
			)
		)
		(property "Datasheet" "https://industrial.panasonic.com/cdbs/www-data/pdf/RDA0000/AOA0000C301.pdf"
			(at 0 0 90)
			(layer "F.Fab")
			(hide yes)
			(effects
				(font
					(size 1.27 1.27)
					(thickness 0.15)
				)
			)
		)
		(property "Description" "SMD Chip Resistor, Jumper, 0 ohm, 100 mW, 0402 [1005 Metric], Thick Film, General Purpose"
			(at 0 0 90)
			(layer "F.Fab")
			(hide yes)
			(effects
				(font
					(size 1.27 1.27)
					(thickness 0.15)
				)
			)
		)
		(property "MPN" "ERJ2GE0R00X"
			(at 0 0 270)
			(unlocked yes)
			(layer "F.Fab")
			(hide yes)
			(effects
				(font
					(size 1 1)
					(thickness 0.15)
				)
			)
		)
		(property "Manufacturer" "Panasonic"
			(at 0 0 270)
			(unlocked yes)
			(layer "F.Fab")
			(hide yes)
			(effects
				(font
					(size 1 1)
					(thickness 0.15)
				)
			)
		)
		(property "License" "Apache-2.0"
			(at 0 0 270)
			(unlocked yes)
			(layer "F.Fab")
			(hide yes)
			(effects
				(font
					(size 1 1)
					(thickness 0.15)
				)
			)
		)
		(property "Author" "Antmicro"
			(at 0 0 270)
			(unlocked yes)
			(layer "F.Fab")
			(hide yes)
			(effects
				(font
					(size 1 1)
					(thickness 0.15)
				)
			)
		)
		(property "Val" "0R"
			(at 0 0 270)
			(unlocked yes)
			(layer "F.Fab")
			(hide yes)
			(effects
				(font
					(size 1 1)
					(thickness 0.15)
				)
			)
		)
		(property "Tolerance" "~"
			(at 0 0 270)
			(unlocked yes)
			(layer "F.Fab")
			(hide yes)
			(effects
				(font
					(size 1 1)
					(thickness 0.15)
				)
			)
		)
		(property "Current" "1A"
			(at 0 0 270)
			(unlocked yes)
			(layer "F.Fab")
			(hide yes)
			(effects
				(font
					(size 1 1)
					(thickness 0.15)
				)
			)
		)
		(sheetname "/Peripherals/")
		(sheetfile "peripherals.kicad_sch")
		(attr smd)
		(fp_rect
			(start -0.925 -0.47)
			(end 0.925 0.47)
			(stroke
				(width 0.05)
				(type default)
			)
			(fill no)
			(layer "F.CrtYd")
		)
		(fp_rect
			(start -0.5 -0.25)
			(end 0.5 0.25)
			(stroke
				(width 0.15)
				(type solid)
			)
			(fill no)
			(layer "F.Fab")
		)
		(fp_text user "Author: Antmicro"
			(at -0.95 4.169 90)
			(layer "F.Fab")
			(effects
				(font
					(size 0.7 0.7)
					(thickness 0.15)
				)
				(justify right top)
			)
		)
		(fp_text user "${REFERENCE}"
			(at -0.95 3.168 90)
			(layer "F.Fab")
			(effects
				(font
					(size 0.7 0.7)
					(thickness 0.15)
				)
				(justify right top)
			)
		)
		(fp_text user "License: Apache-2.0"
			(at -0.95 5.169 90)
			(layer "F.Fab")
			(effects
				(font
					(size 0.7 0.7)
					(thickness 0.15)
				)
				(justify right top)
			)
		)
		(pad "1" smd roundrect
			(at -0.48 0 270)
			(size 0.59 0.64)
			(layers "F.Cu" "F.Mask" "F.Paste")
			(roundrect_rratio 0.25)
			(net 1319 "/Peripherals/GPIOEX_P0_7")
			(pintype "passive")
		)
		(pad "2" smd roundrect
			(at 0.48 0 270)
			(size 0.59 0.64)
			(layers "F.Cu" "F.Mask" "F.Paste")
			(roundrect_rratio 0.25)
			(net 1378 "Net-(R406-Pad2)")
			(pintype "passive")
		)
	)
	(footprint "antmicro-footprints:XSON-8_1x1.95mm_P0.5mm"
		(layer "F.Cu")
		(at 157.31 143.43 90)
		(property "Reference" "U51"
			(at 3.43 -1.41 180)
			(layer "F.SilkS")
			(effects
				(font
					(size 0.7 0.7)
					(thickness 0.15)
				)
				(justify left bottom)
			)
		)
		(property "Value" "NTS0102_XSON"
			(at 0 2.2 90)
			(layer "F.Fab")
			(effects
				(font
					(size 0.7 0.7)
					(thickness 0.15)
				)
				(justify left bottom)
			)
		)
		(property "Datasheet" "http://www.farnell.com/datasheets/1760723.pdf"
			(at 0 0 90)
			(layer "F.Fab")
			(hide yes)
			(effects
				(font
					(size 1.27 1.27)
					(thickness 0.15)
				)
			)
		)
		(property "Description" "Transceiver, 1.65 V to 3.6 V, XSON-8"
			(at 0 0 90)
			(layer "F.Fab")
			(hide yes)
			(effects
				(font
					(size 1.27 1.27)
					(thickness 0.15)
				)
			)
		)
		(property "MPN" "NTS0102GT"
			(at 0 0 90)
			(unlocked yes)
			(layer "F.Fab")
			(hide yes)
			(effects
				(font
					(size 1 1)
					(thickness 0.15)
				)
			)
		)
		(property "Manufacturer" "NXP"
			(at 0 0 90)
			(unlocked yes)
			(layer "F.Fab")
			(hide yes)
			(effects
				(font
					(size 1 1)
					(thickness 0.15)
				)
			)
		)
		(property "Author" "Antmicro"
			(at 0 0 90)
			(unlocked yes)
			(layer "F.Fab")
			(hide yes)
			(effects
				(font
					(size 1 1)
					(thickness 0.15)
				)
			)
		)
		(property "License" "Apache-2.0"
			(at 0 0 90)
			(unlocked yes)
			(layer "F.Fab")
			(hide yes)
			(effects
				(font
					(size 1 1)
					(thickness 0.15)
				)
			)
		)
		(sheetname "/Peripherals/")
		(sheetfile "peripherals.kicad_sch")
		(attr smd)
		(fp_line
			(start -0.5 -1.1)
			(end 0.5 -1.1)
			(stroke
				(width 0.15)
				(type solid)
			)
			(layer "F.SilkS")
		)
		(fp_line
			(start 0.5 1.1)
			(end -0.5 1.1)
			(stroke
				(width 0.15)
				(type solid)
			)
			(layer "F.SilkS")
		)
		(fp_circle
			(center -0.75 -1.1)
			(end -0.701 -1.1)
			(stroke
				(width 0.15)
				(type solid)
			)
			(fill no)
			(layer "F.SilkS")
		)
		(fp_rect
			(start -0.8 -1.2)
			(end 0.8 1.2)
			(stroke
				(width 0.05)
				(type solid)
			)
			(fill no)
			(layer "F.CrtYd")
		)
		(fp_line
			(start 0.5305 -1.001)
			(end 0.5305 1)
			(stroke
				(width 0.15)
				(type solid)
			)
			(layer "F.Fab")
		)
		(fp_line
			(start -0.5305 -1.001)
			(end 0.5305 -1.001)
			(stroke
				(width 0.15)
				(type solid)
			)
			(layer "F.Fab")
		)
		(fp_line
			(start 0.5305 1)
			(end -0.5305 1)
			(stroke
				(width 0.15)
				(type solid)
			)
			(layer "F.Fab")
		)
		(fp_line
			(start -0.5305 1)
			(end -0.5305 -1.001)
			(stroke
				(width 0.15)
				(type solid)
			)
			(layer "F.Fab")
		)
		(fp_text user "License: Apache-2.0"
			(at -0.527 8.306 90)
			(layer "F.Fab")
			(effects
				(font
					(size 0.7 0.7)
					(thickness 0.15)
				)
				(justify left bottom)
			)
		)
		(fp_text user "${REFERENCE}"
			(at -0.527 5.905 90)
			(layer "F.Fab")
			(effects
				(font
					(size 0.7 0.7)
					(thickness 0.15)
				)
				(justify left bottom)
			)
		)
		(fp_text user "Author: Antmicro"
			(at -0.527 7.105 90)
			(layer "F.Fab")
			(effects
				(font
					(size 0.7 0.7)
					(thickness 0.15)
				)
				(justify left bottom)
			)
		)
		(pad "1" smd roundrect
			(at -0.45 -0.75 270)
			(size 0.6 0.3)
			(layers "F.Cu" "F.Mask" "F.Paste")
			(roundrect_rratio 0.25)
			(net 279 "/Peripherals/FAN_TACH_5V")
			(pinfunction "B_{2}")
			(pintype "bidirectional")
		)
		(pad "2" smd roundrect
			(at -0.45 -0.25 270)
			(size 0.6 0.25)
			(layers "F.Cu" "F.Mask" "F.Paste")
			(roundrect_rratio 0.25)
			(net 1 "GND")
			(pinfunction "GND")
			(pintype "power_in")
		)
		(pad "3" smd roundrect
			(at -0.45 0.25 270)
			(size 0.6 0.25)
			(layers "F.Cu" "F.Mask" "F.Paste")
			(roundrect_rratio 0.25)
			(net 11 "+1V8")
			(pinfunction "VCC_{A}")
			(pintype "power_in")
		)
		(pad "4" smd roundrect
			(at -0.45 0.75 270)
			(size 0.6 0.3)
			(layers "F.Cu" "F.Mask" "F.Paste")
			(roundrect_rratio 0.25)
			(net 100 "/Peripherals/FAN_TACH")
			(pinfunction "A_{2}")
			(pintype "bidirectional")
		)
		(pad "5" smd roundrect
			(at 0.45 0.75 270)
			(size 0.6 0.3)
			(layers "F.Cu" "F.Mask" "F.Paste")
			(roundrect_rratio 0.25)
			(net 97 "/Peripherals/FAN_PWM")
			(pinfunction "A_{1}")
			(pintype "bidirectional")
		)
		(pad "6" smd roundrect
			(at 0.45 0.25 270)
			(size 0.6 0.25)
			(layers "F.Cu" "F.Mask" "F.Paste")
			(roundrect_rratio 0.25)
			(net 11 "+1V8")
			(pinfunction "OE")
			(pintype "input")
		)
		(pad "7" smd roundrect
			(at 0.45 -0.25 270)
			(size 0.6 0.25)
			(layers "F.Cu" "F.Mask" "F.Paste")
			(roundrect_rratio 0.25)
			(net 5 "+5V")
			(pinfunction "VCC_{B}")
			(pintype "power_in")
		)
		(pad "8" smd roundrect
			(at 0.45 -0.75 270)
			(size 0.6 0.3)
			(layers "F.Cu" "F.Mask" "F.Paste")
			(roundrect_rratio 0.25)
			(net 281 "/Peripherals/FAN_PWM_5V")
			(pinfunction "B_{1}")
			(pintype "bidirectional")
		)
	)
	(footprint "antmicro-footprints:R_0402_1005Metric"
		(layer "F.Cu")
		(at 195.1 125.3)
		(descr "Resistor SMD 0402")
		(tags "resistor SMD 0402")
		(property "Reference" "R86"
			(at 0.15 -1.225 0)
			(layer "F.SilkS")
			(effects
				(font
					(size 0.7 0.7)
					(thickness 0.15)
				)
				(justify left bottom)
			)
		)
		(property "Value" "R_10k_0402"
			(at -1.011843 1.772047 0)
			(layer "F.Fab")
			(effects
				(font
					(size 0.7 0.7)
					(thickness 0.15)
				)
				(justify left bottom)
			)
		)
		(property "Datasheet" "https://www.bourns.com/docs/product-datasheets/cr.pdf"
			(at 0 0 0)
			(layer "F.Fab")
			(hide yes)
			(effects
				(font
					(size 1.27 1.27)
					(thickness 0.15)
				)
			)
		)
		(property "Description" "SMD Chip Resistor, 10 kohm, ± 1%, 62.5 mW, 0402 [1005 Metric], Thick Film, General Purpose"
			(at 0 0 0)
			(layer "F.Fab")
			(hide yes)
			(effects
				(font
					(size 1.27 1.27)
					(thickness 0.15)
				)
			)
		)
		(property "MPN" "CR0402-FX-1002GLF"
			(at 0 0 0)
			(unlocked yes)
			(layer "F.Fab")
			(hide yes)
			(effects
				(font
					(size 1 1)
					(thickness 0.15)
				)
			)
		)
		(property "Manufacturer" "Bourns"
			(at 0 0 0)
			(unlocked yes)
			(layer "F.Fab")
			(hide yes)
			(effects
				(font
					(size 1 1)
					(thickness 0.15)
				)
			)
		)
		(property "License" "Apache-2.0"
			(at 0 0 0)
			(unlocked yes)
			(layer "F.Fab")
			(hide yes)
			(effects
				(font
					(size 1 1)
					(thickness 0.15)
				)
			)
		)
		(property "Author" "Antmicro"
			(at 0 0 0)
			(unlocked yes)
			(layer "F.Fab")
			(hide yes)
			(effects
				(font
					(size 1 1)
					(thickness 0.15)
				)
			)
		)
		(property "Val" "10k"
			(at 0 0 0)
			(unlocked yes)
			(layer "F.Fab")
			(hide yes)
			(effects
				(font
					(size 1 1)
					(thickness 0.15)
				)
			)
		)
		(property "Tolerance" "1%"
			(at 0 0 0)
			(unlocked yes)
			(layer "F.Fab")
			(hide yes)
			(effects
				(font
					(size 1 1)
					(thickness 0.15)
				)
			)
		)
		(sheetname "/USB Hub/")
		(sheetfile "usb_hub.kicad_sch")
		(attr smd)
		(fp_rect
			(start -0.925 -0.47)
			(end 0.925 0.47)
			(stroke
				(width 0.05)
				(type default)
			)
			(fill no)
			(layer "F.CrtYd")
		)
		(fp_rect
			(start -0.5 -0.25)
			(end 0.5 0.25)
			(stroke
				(width 0.15)
				(type solid)
			)
			(fill no)
			(layer "F.Fab")
		)
		(fp_text user "Author: Antmicro"
			(at -0.95 4.169 0)
			(layer "F.Fab")
			(effects
				(font
					(size 0.7 0.7)
					(thickness 0.15)
				)
				(justify left bottom)
			)
		)
		(fp_text user "License: Apache-2.0"
			(at -0.95 5.169 0)
			(layer "F.Fab")
			(effects
				(font
					(size 0.7 0.7)
					(thickness 0.15)
				)
				(justify left bottom)
			)
		)
		(fp_text user "${REFERENCE}"
			(at -0.95 3.168 0)
			(layer "F.Fab")
			(effects
				(font
					(size 0.7 0.7)
					(thickness 0.15)
				)
				(justify left bottom)
			)
		)
		(pad "1" smd roundrect
			(at -0.48 0)
			(size 0.59 0.64)
			(layers "F.Cu" "F.Mask" "F.Paste")
			(roundrect_rratio 0.25)
			(net 2 "+3V3")
			(pintype "passive")
		)
		(pad "2" smd roundrect
			(at 0.48 0)
			(size 0.59 0.64)
			(layers "F.Cu" "F.Mask" "F.Paste")
			(roundrect_rratio 0.25)
			(net 920 "/USB Hub/TEST1")
			(pintype "passive")
		)
	)
	(footprint "antmicro-footprints:C_0402_1005Metric"
		(layer "F.Cu")
		(at 182.84 69.59 -90)
		(descr "Capacitor SMD 0402")
		(tags "capacitor SMD 0402")
		(property "Reference" "C279"
			(at -1.12 -1.779468 90)
			(layer "F.SilkS")
			(effects
				(font
					(size 0.7 0.7)
					(thickness 0.15)
				)
				(justify right top)
			)
		)
		(property "Value" "C_1u_0402"
			(at -1.022927 2.155213 90)
			(layer "F.Fab")
			(effects
				(font
					(size 0.7 0.7)
					(thickness 0.15)
				)
				(justify right top)
			)
		)
		(property "Datasheet" "https://product.tdk.com/en/search/capacitor/ceramic/mlcc/info?part_no=C1005X6S1A105K050BC"
			(at 0 0 90)
			(layer "F.Fab")
			(hide yes)
			(effects
				(font
					(size 1.27 1.27)
					(thickness 0.15)
				)
			)
		)
		(property "Description" "SMD Multilayer Ceramic Capacitor, 1 µF, 10 V, 0402 [1005 Metric], ± 10%, X6S, C"
			(at 0 0 90)
			(layer "F.Fab")
			(hide yes)
			(effects
				(font
					(size 1.27 1.27)
					(thickness 0.15)
				)
			)
		)
		(property "Manufacturer" "TDK"
			(at 0 0 270)
			(unlocked yes)
			(layer "F.Fab")
			(hide yes)
			(effects
				(font
					(size 1 1)
					(thickness 0.15)
				)
			)
		)
		(property "MPN" "C1005X6S1A105K050BC"
			(at 0 0 270)
			(unlocked yes)
			(layer "F.Fab")
			(hide yes)
			(effects
				(font
					(size 1 1)
					(thickness 0.15)
				)
			)
		)
		(property "Val" "1u"
			(at 0 0 270)
			(unlocked yes)
			(layer "F.Fab")
			(hide yes)
			(effects
				(font
					(size 1 1)
					(thickness 0.15)
				)
			)
		)
		(property "License" "Apache-2.0"
			(at 0 0 270)
			(unlocked yes)
			(layer "F.Fab")
			(hide yes)
			(effects
				(font
					(size 1 1)
					(thickness 0.15)
				)
			)
		)
		(property "Author" "Antmicro"
			(at 0 0 270)
			(unlocked yes)
			(layer "F.Fab")
			(hide yes)
			(effects
				(font
					(size 1 1)
					(thickness 0.15)
				)
			)
		)
		(property "Voltage" ""
			(at 0 0 270)
			(unlocked yes)
			(layer "F.Fab")
			(hide yes)
			(effects
				(font
					(size 1 1)
					(thickness 0.15)
				)
			)
		)
		(property "Dielectric" ""
			(at 0 0 270)
			(unlocked yes)
			(layer "F.Fab")
			(hide yes)
			(effects
				(font
					(size 1 1)
					(thickness 0.15)
				)
			)
		)
		(component_classes
			(class "DCDC_20V")
		)
		(sheetname "/DCDC/")
		(sheetfile "dcdc.kicad_sch")
		(attr smd)
		(fp_rect
			(start -0.925 -0.47)
			(end 0.925 0.47)
			(stroke
				(width 0.05)
				(type default)
			)
			(fill no)
			(layer "F.CrtYd")
		)
		(fp_line
			(start -0.494 0.248)
			(end -0.494 -0.25)
			(stroke
				(width 0.15)
				(type solid)
			)
			(layer "F.Fab")
		)
		(fp_line
			(start 0.504 0.248)
			(end -0.494 0.248)
			(stroke
				(width 0.15)
				(type solid)
			)
			(layer "F.Fab")
		)
		(fp_line
			(start -0.494 -0.25)
			(end 0.504 -0.25)
			(stroke
				(width 0.15)
				(type solid)
			)
			(layer "F.Fab")
		)
		(fp_line
			(start 0.504 -0.25)
			(end 0.504 0.248)
			(stroke
				(width 0.15)
				(type solid)
			)
			(layer "F.Fab")
		)
		(fp_text user "License: Apache-2.0"
			(at -0.939 5.799 90)
			(layer "F.Fab")
			(effects
				(font
					(size 0.7 0.7)
					(thickness 0.15)
				)
				(justify right top)
			)
		)
		(fp_text user "${REFERENCE}"
			(at -0.939 4.599 90)
			(layer "F.Fab")
			(effects
				(font
					(size 0.7 0.7)
					(thickness 0.15)
				)
				(justify right top)
			)
		)
		(fp_text user "Author: Antmicro"
			(at -0.939 3.399 90)
			(layer "F.Fab")
			(effects
				(font
					(size 0.7 0.7)
					(thickness 0.15)
				)
				(justify right top)
			)
		)
		(pad "1" smd roundrect
			(at -0.48 0 270)
			(size 0.59 0.64)
			(layers "F.Cu" "F.Mask" "F.Paste")
			(roundrect_rratio 0.25)
			(net 1 "GND")
			(pintype "passive")
		)
		(pad "2" smd roundrect
			(at 0.48 0 270)
			(size 0.59 0.64)
			(layers "F.Cu" "F.Mask" "F.Paste")
			(roundrect_rratio 0.25)
			(net 905 "/DCDC/20V_VDD")
			(pintype "passive")
		)
	)
	(footprint "antmicro-footprints:Module_Jetson-Thor-AGX-T5000"
		(layer "F.Cu")
		(at 116.41 103.676 180)
		(descr "Jetson Thor series")
		(tags "Jetson Thor")
		(property "Reference" "A3"
			(at -3.182 -52.1535 0)
			(layer "F.SilkS")
			(hide yes)
			(effects
				(font
					(size 0.7 0.7)
					(thickness 0.15)
				)
				(justify right top)
			)
		)
		(property "Value" "Jetson-Thor-AGX-T5000"
			(at 1.768 54.9945 0)
			(layer "F.Fab")
			(effects
				(font
					(size 0.7 0.7)
					(thickness 0.15)
				)
				(justify right top)
			)
		)
		(property "Datasheet" "https://developer.nvidia.com/embedded/downloads#?tx=$product,jetson_thor"
			(at -166.182 -192.6685 0)
			(layer "F.Fab")
			(hide yes)
			(effects
				(font
					(size 0.7 0.7)
					(thickness 0.15)
				)
				(justify right top)
			)
		)
		(property "Description" "Jetson Thor, System-on-Module, 2560-core NVIDIA Blackwell GPU with 96 fifth-gen Tensor Cores, Multi-Instance GPU with 10TPCs, 14-core Arm Neoverse-V3AE 64-bit CPU, 128 GB LPDDR5X"
			(at -166.182 -192.6685 0)
			(layer "F.Fab")
			(hide yes)
			(effects
				(font
					(size 0.7 0.7)
					(thickness 0.15)
				)
				(justify right top)
			)
		)
		(property "Manufacturer" "Nvidia"
			(at 0 0 180)
			(unlocked yes)
			(layer "F.Fab")
			(hide yes)
			(effects
				(font
					(size 1 1)
					(thickness 0.15)
				)
			)
		)
		(property "MPN" "900-13834-0080-000"
			(at 0 0 180)
			(unlocked yes)
			(layer "F.Fab")
			(hide yes)
			(effects
				(font
					(size 1 1)
					(thickness 0.15)
				)
			)
		)
		(property "Author" "Antmicro"
			(at 0 0 180)
			(unlocked yes)
			(layer "F.Fab")
			(hide yes)
			(effects
				(font
					(size 1 1)
					(thickness 0.15)
				)
			)
		)
		(property "License" "Apache-2.0"
			(at 0 0 180)
			(unlocked yes)
			(layer "F.Fab")
			(hide yes)
			(effects
				(font
					(size 1 1)
					(thickness 0.15)
				)
			)
		)
		(property "Displayed name" "Jetson Thor AGX T5000"
			(at 0 0 180)
			(unlocked yes)
			(layer "F.Fab")
			(hide yes)
			(effects
				(font
					(size 1 1)
					(thickness 0.15)
				)
			)
		)
		(sheetname "/SoM_Power/")
		(sheetfile "som_power.kicad_sch")
		(attr exclude_from_pos_files exclude_from_bom allow_missing_courtyard dnp)
		(fp_circle
			(center 39.5 -46)
			(end 41 -46)
			(stroke
				(width 0.15)
				(type solid)
			)
			(fill no)
			(layer "F.SilkS")
		)
		(fp_text user "License: Apache-2.0"
			(at -43.332 55.1465 0)
			(layer "F.Fab")
			(effects
				(font
					(size 0.7 0.7)
					(thickness 0.15)
				)
				(justify right top)
			)
		)
		(fp_text user "${REFERENCE}"
			(at -43.332 52.7465 0)
			(layer "F.Fab")
			(effects
				(font
					(size 0.7 0.7)
					(thickness 0.15)
				)
				(justify right top)
			)
		)
		(fp_text user "Author: Antmicro"
			(at -43.332 53.9465 0)
			(layer "F.Fab")
			(effects
				(font
					(size 0.7 0.7)
					(thickness 0.15)
				)
				(justify right top)
			)
		)
		(dimension
			(type aligned)
			(layer "Dwgs.User")
			(pts
				(xy 159.91 103.676) (xy 72.91 103.676)
			)
			(height -59.1)
			(format
				(prefix "")
				(suffix "")
				(units 3)
				(units_format 1)
				(precision 2)
			)
			(style
				(thickness 0.1)
				(arrow_length 1.27)
				(text_position_mode 0)
				(arrow_direction outward)
				(extension_height 0.58642)
				(extension_offset 0.5)
				(keep_text_aligned yes)
			)
			(gr_text "87.00 mm"
				(at 116.41 161.626 0)
				(layer "Dwgs.User")
				(effects
					(font
						(size 1 1)
						(thickness 0.15)
					)
				)
			)
		)
		(dimension
			(type aligned)
			(layer "Dwgs.User")
			(pts
				(xy 116.41 53.676) (xy 116.41 153.676)
			)
			(height 54.5)
			(format
				(prefix "")
				(suffix "")
				(units 3)
				(units_format 1)
				(precision 2)
			)
			(style
				(thickness 0.1)
				(arrow_length 1.27)
				(text_position_mode 0)
				(arrow_direction outward)
				(extension_height 0.58642)
				(extension_offset 0.5)
				(keep_text_aligned yes)
			)
			(gr_text "100.00 mm"
				(at 60.76 103.676 90)
				(layer "Dwgs.User")
				(effects
					(font
						(size 1 1)
						(thickness 0.15)
					)
				)
			)
		)
		(dimension
			(type aligned)
			(layer "Dwgs.User")
			(pts
				(xy 155.91 57.676) (xy 159.91 57.676)
			)
			(height -9.5)
			(format
				(prefix "")
				(suffix "")
				(units 3)
				(units_format 1)
				(precision 2)
			)
			(style
				(thickness 0.1)
				(arrow_length 1.27)
				(text_position_mode 2)
				(arrow_direction outward)
				(extension_height 0.58642)
				(extension_offset 0.5)
				(keep_text_aligned yes)
			)
			(gr_text "4.00 mm"
				(at 157.91 46.676 0)
				(layer "Dwgs.User")
				(effects
					(font
						(size 1 1)
						(thickness 0.15)
					)
				)
			)
		)
		(dimension
			(type aligned)
			(layer "Dwgs.User")
			(pts
				(xy 76.91 57.676) (xy 76.91 78.116)
			)
			(height 0)
			(format
				(prefix "")
				(suffix "")
				(units 3)
				(units_format 1)
				(precision 2)
			)
			(style
				(thickness 0.1)
				(arrow_length 1.27)
				(text_position_mode 0)
				(arrow_direction outward)
				(extension_height 0.58642)
				(extension_offset 0.5)
				(keep_text_aligned yes)
			)
			(gr_text "20.44 mm"
				(at 75.76 67.896 90)
				(layer "Dwgs.User")
				(effects
					(font
						(size 1 1)
						(thickness 0.15)
					)
				)
			)
		)
		(dimension
			(type aligned)
			(layer "Dwgs.User")
			(pts
				(xy 155.91 57.676) (xy 155.91 53.676)
			)
			(height 7.5)
			(format
				(prefix "")
				(suffix "")
				(units 3)
				(units_format 1)
				(precision 2)
			)
			(style
				(thickness 0.1)
				(arrow_length 1.27)
				(text_position_mode 2)
				(arrow_direction outward)
				(extension_height 0.58642)
				(extension_offset 0.5)
				(keep_text_aligned yes)
			)
			(gr_text "4.00 mm"
				(at 164.909999 55.676 90)
				(layer "Dwgs.User")
				(effects
					(font
						(size 1 1)
						(thickness 0.15)
					)
				)
			)
		)
		(dimension
			(type aligned)
			(layer "Dwgs.User")
			(pts
				(xy 148.759999 67.116) (xy 148.76 87.216)
			)
			(height -3)
			(format
				(prefix "")
				(suffix "")
				(units 3)
				(units_format 1)
				(precision 2)
			)
			(style
				(thickness 0.1)
				(arrow_length 1.27)
				(text_position_mode 0)
				(arrow_direction outward)
				(extension_height 0.58642)
				(extension_offset 0.5)
				(keep_text_aligned yes)
			)
			(gr_text "20.10 mm"
				(at 152.91 77.166 270.0000057)
				(layer "Dwgs.User")
				(effects
					(font
						(size 1 1)
						(thickness 0.15)
					)
				)
			)
		)
		(dimension
			(type aligned)
			(layer "Dwgs.User")
			(pts
				(xy 148.76 87.216) (xy 84.06 87.216)
			)
			(height -3.96)
			(format
				(prefix "")
				(suffix "")
				(units 3)
				(units_format 1)
				(precision 2)
			)
			(style
				(thickness 0.1)
				(arrow_length 1.27)
				(text_position_mode 2)
				(arrow_direction outward)
				(extension_height 0.58642)
				(extension_offset 0.5)
				(keep_text_aligned yes)
			)
			(gr_text "64.70 mm"
				(at 120.91 92.676 0)
				(layer "Dwgs.User")
				(effects
					(font
						(size 1 1)
						(thickness 0.15)
					)
				)
			)
		)
		(dimension
			(type radial)
			(layer "Dwgs.User")
			(pts
				(xy 74.91 151.676) (xy 73.495786 153.090214)
			)
			(leader_length 6.45934)
			(format
				(prefix "4x R ")
				(suffix "")
				(units 3)
				(units_format 1)
				(precision 2)
			)
			(style
				(thickness 0.1)
				(arrow_length 1.27)
				(text_position_mode 0)
				(extension_offset 0.5)
				(keep_text_aligned yes)
			)
			(gr_text "4x R 2.00 mm"
				(at 59.64 157.657657 0)
				(layer "Dwgs.User")
				(effects
					(font
						(size 1 1)
						(thickness 0.15)
					)
				)
			)
		)
		(dimension
			(type radial)
			(layer "Dwgs.User")
			(pts
				(xy 76.91 57.676) (xy 75.16 57.676)
			)
			(leader_length 5.251023)
			(format
				(prefix "4x ∅")
				(suffix "")
				(units 3)
				(units_format 1)
				(precision 4)
				(override_value "3.50±0.20")
			)
			(style
				(thickness 0.1)
				(arrow_length 1.27)
				(text_position_mode 0)
				(extension_offset 0.5)
				(keep_text_aligned yes)
			)
			(gr_text "4x ∅3.50±0.20 mm"
				(at 59.292206 47.059229 -45)
				(layer "Dwgs.User")
				(effects
					(font
						(size 1 1)
						(thickness 0.15)
					)
				)
			)
		)
	)
	(footprint "antmicro-footprints:R_0402_1005Metric"
		(layer "F.Cu")
		(at 198.9 98.82 -90)
		(descr "Resistor SMD 0402")
		(tags "resistor SMD 0402")
		(property "Reference" "R100"
			(at -0.72 3.5 90)
			(layer "F.SilkS")
			(effects
				(font
					(size 0.7 0.7)
					(thickness 0.15)
				)
				(justify right top)
			)
		)
		(property "Value" "R_0R_0402"
			(at -1.011843 1.772047 90)
			(layer "F.Fab")
			(effects
				(font
					(size 0.7 0.7)
					(thickness 0.15)
				)
				(justify right top)
			)
		)
		(property "Datasheet" "https://industrial.panasonic.com/cdbs/www-data/pdf/RDA0000/AOA0000C301.pdf"
			(at 0 0 90)
			(layer "F.Fab")
			(hide yes)
			(effects
				(font
					(size 1.27 1.27)
					(thickness 0.15)
				)
			)
		)
		(property "Description" "SMD Chip Resistor, Jumper, 0 ohm, 100 mW, 0402 [1005 Metric], Thick Film, General Purpose"
			(at 0 0 90)
			(layer "F.Fab")
			(hide yes)
			(effects
				(font
					(size 1.27 1.27)
					(thickness 0.15)
				)
			)
		)
		(property "MPN" "ERJ2GE0R00X"
			(at 0 0 270)
			(unlocked yes)
			(layer "F.Fab")
			(hide yes)
			(effects
				(font
					(size 1 1)
					(thickness 0.15)
				)
			)
		)
		(property "Manufacturer" "Panasonic"
			(at 0 0 270)
			(unlocked yes)
			(layer "F.Fab")
			(hide yes)
			(effects
				(font
					(size 1 1)
					(thickness 0.15)
				)
			)
		)
		(property "License" "Apache-2.0"
			(at 0 0 270)
			(unlocked yes)
			(layer "F.Fab")
			(hide yes)
			(effects
				(font
					(size 1 1)
					(thickness 0.15)
				)
			)
		)
		(property "Author" "Antmicro"
			(at 0 0 270)
			(unlocked yes)
			(layer "F.Fab")
			(hide yes)
			(effects
				(font
					(size 1 1)
					(thickness 0.15)
				)
			)
		)
		(property "Val" "0R"
			(at 0 0 270)
			(unlocked yes)
			(layer "F.Fab")
			(hide yes)
			(effects
				(font
					(size 1 1)
					(thickness 0.15)
				)
			)
		)
		(property "Tolerance" "~"
			(at 0 0 270)
			(unlocked yes)
			(layer "F.Fab")
			(hide yes)
			(effects
				(font
					(size 1 1)
					(thickness 0.15)
				)
			)
		)
		(property "Current" "1A"
			(at 0 0 270)
			(unlocked yes)
			(layer "F.Fab")
			(hide yes)
			(effects
				(font
					(size 1 1)
					(thickness 0.15)
				)
			)
		)
		(sheetname "/USB Debug, PD/")
		(sheetfile "usb_debug_pd.kicad_sch")
		(attr smd exclude_from_pos_files exclude_from_bom dnp)
		(fp_rect
			(start -0.925 -0.47)
			(end 0.925 0.47)
			(stroke
				(width 0.05)
				(type default)
			)
			(fill no)
			(layer "F.CrtYd")
		)
		(fp_rect
			(start -0.5 -0.25)
			(end 0.5 0.25)
			(stroke
				(width 0.15)
				(type solid)
			)
			(fill no)
			(layer "F.Fab")
		)
		(fp_text user "${REFERENCE}"
			(at -0.95 3.168 90)
			(layer "F.Fab")
			(effects
				(font
					(size 0.7 0.7)
					(thickness 0.15)
				)
				(justify right top)
			)
		)
		(fp_text user "License: Apache-2.0"
			(at -0.95 5.169 90)
			(layer "F.Fab")
			(effects
				(font
					(size 0.7 0.7)
					(thickness 0.15)
				)
				(justify right top)
			)
		)
		(fp_text user "Author: Antmicro"
			(at -0.95 4.169 90)
			(layer "F.Fab")
			(effects
				(font
					(size 0.7 0.7)
					(thickness 0.15)
				)
				(justify right top)
			)
		)
		(pad "1" smd roundrect
			(at -0.48 0 270)
			(size 0.59 0.64)
			(layers "F.Cu" "F.Mask" "F.Paste")
			(roundrect_rratio 0.25)
			(net 531 "Net-(D16-A)")
			(pintype "passive")
		)
		(pad "2" smd roundrect
			(at 0.48 0 270)
			(size 0.59 0.64)
			(layers "F.Cu" "F.Mask" "F.Paste")
			(roundrect_rratio 0.25)
			(net 853 "/I2C_{SYS}.SCL")
			(pintype "passive")
		)
	)
	(footprint "antmicro-footprints:L_MPS-MPL-AL5050"
		(layer "F.Cu")
		(at 180.14 148.83 180)
		(property "Reference" "L6"
			(at -3.369468 -1.33 90)
			(layer "F.SilkS")
			(effects
				(font
					(size 0.7 0.7)
					(thickness 0.15)
				)
				(justify right top)
			)
		)
		(property "Value" "L_6u8_6.1A_MPS-MPL-AL5050"
			(at 0.1 4.25 0)
			(layer "F.Fab")
			(effects
				(font
					(size 0.7 0.7)
					(thickness 0.15)
				)
				(justify right top)
			)
		)
		(property "Datasheet" "https://www.monolithicpower.com/en/documentview/productdocument/index/version/2/document_type/Datasheet/lang/en/sku/MPL-AL5050-6R8/document_id/5811/"
			(at 0 0 0)
			(layer "F.Fab")
			(hide yes)
			(effects
				(font
					(size 1.27 1.27)
					(thickness 0.15)
				)
			)
		)
		(property "Description" "Power Inductor (SMT), 6.8 µH, 6.1 A, Shielded, 7.6 A, MPL-AL"
			(at 0 0 0)
			(layer "F.Fab")
			(hide yes)
			(effects
				(font
					(size 1.27 1.27)
					(thickness 0.15)
				)
			)
		)
		(property "Val" "6u8/6.1A"
			(at 0 0 180)
			(unlocked yes)
			(layer "F.Fab")
			(hide yes)
			(effects
				(font
					(size 1 1)
					(thickness 0.15)
				)
			)
		)
		(property "Manufacturer" "Monolithic Power Systems"
			(at 0 0 180)
			(unlocked yes)
			(layer "F.Fab")
			(hide yes)
			(effects
				(font
					(size 1 1)
					(thickness 0.15)
				)
			)
		)
		(property "MPN" "MPL-AL5050-6R8"
			(at 0 0 180)
			(unlocked yes)
			(layer "F.Fab")
			(hide yes)
			(effects
				(font
					(size 1 1)
					(thickness 0.15)
				)
			)
		)
		(property "ISat" "7.6 A"
			(at 0 0 180)
			(unlocked yes)
			(layer "F.Fab")
			(hide yes)
			(effects
				(font
					(size 1 1)
					(thickness 0.15)
				)
			)
		)
		(property "IMax" "6.1 A"
			(at 0 0 180)
			(unlocked yes)
			(layer "F.Fab")
			(hide yes)
			(effects
				(font
					(size 1 1)
					(thickness 0.15)
				)
			)
		)
		(property "Size" "5.5x5.3"
			(at 0 0 180)
			(unlocked yes)
			(layer "F.Fab")
			(hide yes)
			(effects
				(font
					(size 1 1)
					(thickness 0.15)
				)
			)
		)
		(property "Author" "Antmicro"
			(at 0 0 180)
			(unlocked yes)
			(layer "F.Fab")
			(hide yes)
			(effects
				(font
					(size 1 1)
					(thickness 0.15)
				)
			)
		)
		(property "License" "Apache-2.0"
			(at 0 0 180)
			(unlocked yes)
			(layer "F.Fab")
			(hide yes)
			(effects
				(font
					(size 1 1)
					(thickness 0.15)
				)
			)
		)
		(sheetname "/DCDC/")
		(sheetfile "dcdc.kicad_sch")
		(attr smd)
		(fp_rect
			(start -2.75 -2.85)
			(end 2.75 2.85)
			(stroke
				(width 0.15)
				(type solid)
			)
			(fill no)
			(layer "F.SilkS")
		)
		(fp_rect
			(start -2.9 -3)
			(end 2.9 3)
			(stroke
				(width 0.05)
				(type solid)
			)
			(fill no)
			(layer "F.CrtYd")
		)
		(fp_rect
			(start -2.65 -2.75)
			(end 2.65 2.75)
			(stroke
				(width 0.15)
				(type solid)
			)
			(fill no)
			(layer "F.Fab")
		)
		(fp_text user "License: Apache-2.0"
			(at -2.9 8.65 0)
			(layer "F.Fab")
			(effects
				(font
					(size 0.7 0.7)
					(thickness 0.15)
				)
				(justify right top)
			)
		)
		(fp_text user "Author: Antmicro"
			(at -2.9 6.25 0)
			(layer "F.Fab")
			(effects
				(font
					(size 0.7 0.7)
					(thickness 0.15)
				)
				(justify right top)
			)
		)
		(fp_text user "${REFERENCE}"
			(at -2.9 7.45 0)
			(layer "F.Fab")
			(effects
				(font
					(size 0.7 0.7)
					(thickness 0.15)
				)
				(justify right top)
			)
		)
		(pad "1" smd roundrect
			(at -1.625 0 180)
			(size 1.25 4.7)
			(layers "F.Cu" "F.Mask" "F.Paste")
			(roundrect_rratio 0.1)
			(net 1186 "/DCDC/12V_SW")
			(pintype "passive")
		)
		(pad "2" smd roundrect
			(at 1.625 0 180)
			(size 1.25 4.7)
			(layers "F.Cu" "F.Mask" "F.Paste")
			(roundrect_rratio 0.1)
			(net 880 "/DCDC/12V_OUT")
			(pintype "passive")
		)
	)
	(footprint "antmicro-footprints:LED_0603_1608Metric_G"
		(layer "F.Cu")
		(at 196.17 88.22 90)
		(descr "LED SMD 0603 Green")
		(tags "LED SMD 0603 Green")
		(property "Reference" "D18"
			(at -3.42 0.35 90)
			(layer "F.SilkS")
			(effects
				(font
					(size 0.7 0.7)
					(thickness 0.15)
				)
				(justify left bottom)
			)
		)
		(property "Value" "LED_G_0603_LTST-C190GKT"
			(at -0.001 1.599 90)
			(layer "F.Fab")
			(effects
				(font
					(size 0.7 0.7)
					(thickness 0.15)
				)
				(justify left bottom)
			)
		)
		(property "Datasheet" "https://media.digikey.com/pdf/Data%20Sheets/Lite-On%20PDFs/LTST-C190GKT.pdf"
			(at 0 0 90)
			(layer "F.Fab")
			(hide yes)
			(effects
				(font
					(size 1.27 1.27)
					(thickness 0.15)
				)
			)
		)
		(property "Description" "LED, Green, SMD, 0603, 20 mA, 2.1 V, 569 nm"
			(at 0 0 90)
			(layer "F.Fab")
			(hide yes)
			(effects
				(font
					(size 1.27 1.27)
					(thickness 0.15)
				)
			)
		)
		(property "MPN" "LTST-C190GKT"
			(at 0 0 90)
			(unlocked yes)
			(layer "F.Fab")
			(hide yes)
			(effects
				(font
					(size 1 1)
					(thickness 0.15)
				)
			)
		)
		(property "Manufacturer" "Lite-On"
			(at 0 0 90)
			(unlocked yes)
			(layer "F.Fab")
			(hide yes)
			(effects
				(font
					(size 1 1)
					(thickness 0.15)
				)
			)
		)
		(property "Author" "Antmicro"
			(at 0 0 90)
			(unlocked yes)
			(layer "F.Fab")
			(hide yes)
			(effects
				(font
					(size 1 1)
					(thickness 0.15)
				)
			)
		)
		(property "License" "Apache-2.0"
			(at 0 0 90)
			(unlocked yes)
			(layer "F.Fab")
			(hide yes)
			(effects
				(font
					(size 1 1)
					(thickness 0.15)
				)
			)
		)
		(property "Color" "Green"
			(at 0 0 90)
			(unlocked yes)
			(layer "F.Fab")
			(hide yes)
			(effects
				(font
					(size 1 1)
					(thickness 0.15)
				)
			)
		)
		(sheetname "/USB Debug, PD/")
		(sheetfile "usb_debug_pd.kicad_sch")
		(attr smd)
		(fp_line
			(start 0.22 -0.35)
			(end -0.22 -0.35)
			(stroke
				(width 0.15)
				(type solid)
			)
			(layer "F.SilkS")
		)
		(fp_line
			(start -1.18 -0.319)
			(end -1.18 0.321)
			(stroke
				(width 0.15)
				(type solid)
			)
			(layer "F.SilkS")
		)
		(fp_line
			(start 0.105328 0.001008)
			(end 0.24 0.001)
			(stroke
				(width 0.1)
				(type solid)
			)
			(layer "F.SilkS")
		)
		(fp_line
			(start -0.094672 0.001008)
			(end 0.105328 -0.198992)
			(stroke
				(width 0.1)
				(type solid)
			)
			(layer "F.SilkS")
		)
		(fp_line
			(start -0.094672 0.001008)
			(end -0.24 0.001008)
			(stroke
				(width 0.1)
				(type solid)
			)
			(layer "F.SilkS")
		)
		(fp_line
			(start 0.105328 0.201008)
			(end 0.105328 -0.198992)
			(stroke
				(width 0.1)
				(type solid)
			)
			(layer "F.SilkS")
		)
		(fp_line
			(start 0.105328 0.201008)
			(end -0.094672 0.001008)
			(stroke
				(width 0.1)
				(type solid)
			)
			(layer "F.SilkS")
		)
		(fp_line
			(start -0.094672 0.201008)
			(end -0.094672 -0.198992)
			(stroke
				(width 0.1)
				(type solid)
			)
			(layer "F.SilkS")
		)
		(fp_line
			(start 0.22 0.35)
			(end -0.22 0.35)
			(stroke
				(width 0.15)
				(type solid)
			)
			(layer "F.SilkS")
		)
		(fp_rect
			(start 1.25 0.65)
			(end -1.25 -0.65)
			(stroke
				(width 0.05)
				(type solid)
			)
			(fill no)
			(layer "F.CrtYd")
		)
		(fp_line
			(start 0.201 -0.202)
			(end -0.101 0)
			(stroke
				(width 0.15)
				(type solid)
			)
			(layer "F.Fab")
		)
		(fp_line
			(start -0.199 -0.202)
			(end -0.199 0.1)
			(stroke
				(width 0.15)
				(type solid)
			)
			(layer "F.Fab")
		)
		(fp_line
			(start 0.599 0)
			(end 0.201 0)
			(stroke
				(width 0.15)
				(type solid)
			)
			(layer "F.Fab")
		)
		(fp_line
			(start 0.201 0)
			(end 0.201 -0.202)
			(stroke
				(width 0.15)
				(type solid)
			)
			(layer "F.Fab")
		)
		(fp_line
			(start -0.101 0)
			(end 0.201 0.2)
			(stroke
				(width 0.15)
				(type solid)
			)
			(layer "F.Fab")
		)
		(fp_line
			(start -0.199 0)
			(end -0.597 0)
			(stroke
				(width 0.15)
				(type solid)
			)
			(layer "F.Fab")
		)
		(fp_line
			(start 0.201 0.2)
			(end 0.201 0)
			(stroke
				(width 0.15)
				(type solid)
			)
			(layer "F.Fab")
		)
		(fp_line
			(start -0.199 0.2)
			(end -0.199 0.1)
			(stroke
				(width 0.15)
				(type solid)
			)
			(layer "F.Fab")
		)
		(fp_rect
			(start 0.848 0.4)
			(end -0.85 -0.402)
			(stroke
				(width 0.15)
				(type solid)
			)
			(fill no)
			(layer "F.Fab")
		)
		(fp_text user "${REFERENCE}"
			(at -1.4224 5.999 90)
			(layer "F.Fab")
			(effects
				(font
					(size 0.7 0.7)
					(thickness 0.15)
				)
				(justify left bottom)
			)
		)
		(fp_text user "License: Apache-2.0"
			(at -1.4224 3.599 90)
			(layer "F.Fab")
			(effects
				(font
					(size 0.7 0.7)
					(thickness 0.15)
				)
				(justify left bottom)
			)
		)
		(fp_text user "Author: Antmicro"
			(at -1.4224 4.799 90)
			(layer "F.Fab")
			(effects
				(font
					(size 0.7 0.7)
					(thickness 0.15)
				)
				(justify left bottom)
			)
		)
		(pad "1" smd roundrect
			(at -0.7 0 270)
			(size 0.8 1)
			(layers "F.Cu" "F.Mask" "F.Paste")
			(roundrect_rratio 0.2)
			(net 1 "GND")
			(pinfunction "C")
			(pintype "passive")
		)
		(pad "2" smd roundrect
			(at 0.7 0 270)
			(size 0.8 1)
			(layers "F.Cu" "F.Mask" "F.Paste")
			(roundrect_rratio 0.2)
			(net 533 "Net-(D18-A)")
			(pinfunction "A")
			(pintype "passive")
		)
	)
	(footprint "antmicro-footprints:DHVQFN-14-1EP_2.5x3mm"
		(layer "F.Cu")
		(at 152.48 112.25)
		(property "Reference" "U80"
			(at 1.32 -1.05 0)
			(layer "F.SilkS")
			(effects
				(font
					(size 0.7 0.7)
					(thickness 0.15)
				)
				(justify left bottom)
			)
		)
		(property "Value" "NTS0104_DHVQFN"
			(at 0 2.897999 0)
			(layer "F.Fab")
			(effects
				(font
					(size 0.7 0.7)
					(thickness 0.15)
				)
				(justify left bottom)
			)
		)
		(property "Datasheet" "https://www.nxp.com/docs/en/data-sheet/NTS0104.pdf"
			(at 0 0 0)
			(layer "F.Fab")
			(hide yes)
			(effects
				(font
					(size 1.27 1.27)
					(thickness 0.15)
				)
			)
		)
		(property "Description" "Voltage Level Translator Bidirectional 1 Circuit 4 Channel 50Mbps 14-DHVQFN (2.5x3)"
			(at 0 0 0)
			(layer "F.Fab")
			(hide yes)
			(effects
				(font
					(size 1.27 1.27)
					(thickness 0.15)
				)
			)
		)
		(property "MPN" "NTS0104BQ"
			(at 0 0 0)
			(unlocked yes)
			(layer "F.Fab")
			(hide yes)
			(effects
				(font
					(size 1 1)
					(thickness 0.15)
				)
			)
		)
		(property "Manufacturer" "NXP"
			(at 0 0 0)
			(unlocked yes)
			(layer "F.Fab")
			(hide yes)
			(effects
				(font
					(size 1 1)
					(thickness 0.15)
				)
			)
		)
		(property "Author" "Antmicro"
			(at 0 0 0)
			(unlocked yes)
			(layer "F.Fab")
			(hide yes)
			(effects
				(font
					(size 1 1)
					(thickness 0.15)
				)
			)
		)
		(property "License" "Apache-2.0"
			(at 0 0 0)
			(unlocked yes)
			(layer "F.Fab")
			(hide yes)
			(effects
				(font
					(size 1 1)
					(thickness 0.15)
				)
			)
		)
		(sheetname "/SoM_IO/")
		(sheetfile "som_io.kicad_sch")
		(attr smd)
		(fp_line
			(start -1.351 -1.601)
			(end -0.499999 -1.601)
			(stroke
				(width 0.15)
				(type solid)
			)
			(layer "F.SilkS")
		)
		(fp_line
			(start -1.351 1.6)
			(end -1.351 1.249)
			(stroke
				(width 0.15)
				(type solid)
			)
			(layer "F.SilkS")
		)
		(fp_line
			(start -1.351 1.6)
			(end -0.5 1.6)
			(stroke
				(width 0.15)
				(type solid)
			)
			(layer "F.SilkS")
		)
		(fp_line
			(start -1.35 -1.601)
			(end -1.35 -1.25)
			(stroke
				(width 0.15)
				(type solid)
			)
			(layer "F.SilkS")
		)
		(fp_line
			(start 0.494 1.6)
			(end 1.35 1.6)
			(stroke
				(width 0.15)
				(type solid)
			)
			(layer "F.SilkS")
		)
		(fp_line
			(start 1.35 -1.601)
			(end 0.494 -1.601)
			(stroke
				(width 0.15)
				(type solid)
			)
			(layer "F.SilkS")
		)
		(fp_line
			(start 1.35 -1.601)
			(end 1.35 -1.25)
			(stroke
				(width 0.15)
				(type solid)
			)
			(layer "F.SilkS")
		)
		(fp_line
			(start 1.35 1.6)
			(end 1.35 1.249)
			(stroke
				(width 0.15)
				(type solid)
			)
			(layer "F.SilkS")
		)
		(fp_circle
			(center -0.7 -1.85)
			(end -0.653 -1.85)
			(stroke
				(width 0.15)
				(type solid)
			)
			(fill yes)
			(layer "F.SilkS")
		)
		(fp_poly
			(pts
				(xy -1.85 -2) (xy 1.8 -2) (xy 1.8 1.95) (xy -1.85 1.95)
			)
			(stroke
				(width 0.05)
				(type solid)
			)
			(fill no)
			(layer "F.CrtYd")
		)
		(fp_line
			(start -1.25 -1.25)
			(end -1 -1.5)
			(stroke
				(width 0.15)
				(type solid)
			)
			(layer "F.Fab")
		)
		(fp_line
			(start -1.25 1.499001)
			(end -1.25 -1.25)
			(stroke
				(width 0.15)
				(type solid)
			)
			(layer "F.Fab")
		)
		(fp_line
			(start -1 -1.5)
			(end 1.249 -1.5)
			(stroke
				(width 0.15)
				(type solid)
			)
			(layer "F.Fab")
		)
		(fp_line
			(start 1.248999 1.499)
			(end -1.25 1.499001)
			(stroke
				(width 0.15)
				(type solid)
			)
			(layer "F.Fab")
		)
		(fp_line
			(start 1.249 -1.5)
			(end 1.248999 1.499)
			(stroke
				(width 0.15)
				(type solid)
			)
			(layer "F.Fab")
		)
		(fp_text user "Author: Antmicro"
			(at -1.841001 7.296 0)
			(layer "F.Fab")
			(effects
				(font
					(size 0.7 0.7)
					(thickness 0.15)
				)
				(justify left bottom)
			)
		)
		(fp_text user "${REFERENCE}"
			(at -1.841 4.896999 0)
			(layer "F.Fab")
			(effects
				(font
					(size 0.7 0.7)
					(thickness 0.15)
				)
				(justify left bottom)
			)
		)
		(fp_text user "License: Apache-2.0"
			(at -1.841001 6.097 0)
			(layer "F.Fab")
			(effects
				(font
					(size 0.7 0.7)
					(thickness 0.15)
				)
				(justify left bottom)
			)
		)
		(pad "1" smd oval
			(at -0.25 -1.5)
			(size 0.3 0.8)
			(layers "F.Cu" "F.Mask" "F.Paste")
			(net 11 "+1V8")
			(pinfunction "VCC_A")
			(pintype "power_in")
		)
		(pad "2" smd oval
			(at -1.25 -1 90)
			(size 0.3 0.8)
			(layers "F.Cu" "F.Mask" "F.Paste")
			(net 139 "/SoM_IO/I2C2_SCL_1V8")
			(pinfunction "A1")
			(pintype "passive")
		)
		(pad "3" smd oval
			(at -1.25 -0.5 90)
			(size 0.3 0.8)
			(layers "F.Cu" "F.Mask" "F.Paste")
			(net 167 "/SoM_IO/I2C2_SDA_1V8")
			(pinfunction "A2")
			(pintype "passive")
		)
		(pad "4" smd oval
			(at -1.249999 0 90)
			(size 0.3 0.8)
			(layers "F.Cu" "F.Mask" "F.Paste")
			(net 133 "/SoM_IO/I2C5_SCL_1V8")
			(pinfunction "A3")
			(pintype "passive")
		)
		(pad "5" smd oval
			(at -1.25 0.494 90)
			(size 0.3 0.8)
			(layers "F.Cu" "F.Mask" "F.Paste")
			(net 112 "/SoM_IO/I2C5_SDA_1V8")
			(pinfunction "A4")
			(pintype "passive")
		)
		(pad "6" smd oval
			(at -1.25 0.994001 90)
			(size 0.3 0.8)
			(layers "F.Cu" "F.Mask" "F.Paste")
			(net 1329 "unconnected-(U80-NC-Pad6)")
			(pinfunction "NC")
			(pintype "no_connect")
		)
		(pad "7" smd oval
			(at -0.25 1.499)
			(size 0.3 0.8)
			(layers "F.Cu" "F.Mask" "F.Paste")
			(net 1 "GND")
			(pinfunction "GND")
			(pintype "power_in")
		)
		(pad "8" smd oval
			(at 0.244 1.499)
			(size 0.3 0.8)
			(layers "F.Cu" "F.Mask" "F.Paste")
			(net 11 "+1V8")
			(pinfunction "OE")
			(pintype "passive")
		)
		(pad "9" smd oval
			(at 1.249 0.994001 90)
			(size 0.3 0.8)
			(layers "F.Cu" "F.Mask" "F.Paste")
			(net 1328 "unconnected-(U80-NC-Pad9)")
			(pinfunction "NC")
			(pintype "no_connect")
		)
		(pad "10" smd oval
			(at 1.249 0.494 90)
			(size 0.3 0.8)
			(layers "F.Cu" "F.Mask" "F.Paste")
			(net 43 "/Peripherals/I2C_{CONN}.SDA")
			(pinfunction "B4")
			(pintype "passive")
		)
		(pad "11" smd oval
			(at 1.248999 0 90)
			(size 0.3 0.8)
			(layers "F.Cu" "F.Mask" "F.Paste")
			(net 42 "/Peripherals/I2C_{CONN}.SCL")
			(pinfunction "B3")
			(pintype "passive")
		)
		(pad "12" smd oval
			(at 1.249 -0.5 90)
			(size 0.3 0.8)
			(layers "F.Cu" "F.Mask" "F.Paste")
			(net 850 "/I2C_{SYS}.SDA")
			(pinfunction "B2")
			(pintype "passive")
		)
		(pad "13" smd oval
			(at 1.249 -1 90)
			(size 0.3 0.8)
			(layers "F.Cu" "F.Mask" "F.Paste")
			(net 853 "/I2C_{SYS}.SCL")
			(pinfunction "B1")
			(pintype "passive")
		)
		(pad "14" smd oval
			(at 0.244 -1.5)
			(size 0.3 0.8)
			(layers "F.Cu" "F.Mask" "F.Paste")
			(net 2 "+3V3")
			(pinfunction "VCC_B")
			(pintype "power_in")
		)
		(pad "15" smd rect
			(at 0 0)
			(size 1 1.5)
			(layers "F.Cu" "F.Mask" "F.Paste")
			(net 1 "GND")
			(pinfunction "GNDPAD")
			(pintype "power_in")
		)
	)
	(footprint "antmicro-footprints:R_0402_1005Metric"
		(layer "F.Cu")
		(at 180.8 107.15 -90)
		(descr "Resistor SMD 0402")
		(tags "resistor SMD 0402")
		(property "Reference" "R37"
			(at -3.15 0.4 90)
			(layer "F.SilkS")
			(effects
				(font
					(size 0.7 0.7)
					(thickness 0.15)
				)
				(justify right top)
			)
		)
		(property "Value" "R_499k_0402"
			(at -1.011843 1.772047 90)
			(layer "F.Fab")
			(effects
				(font
					(size 0.7 0.7)
					(thickness 0.15)
				)
				(justify right top)
			)
		)
		(property "Datasheet" "https://www.mouser.com/datasheet/2/54/cr-1858361.pdf"
			(at 0 0 90)
			(layer "F.Fab")
			(hide yes)
			(effects
				(font
					(size 1.27 1.27)
					(thickness 0.15)
				)
			)
		)
		(property "Description" "SMD Chip Resistor, 499 kohm, ± 1%, 63 mW, 0402 [1005 Metric], Thick Film, General Purpose"
			(at 0 0 90)
			(layer "F.Fab")
			(hide yes)
			(effects
				(font
					(size 1.27 1.27)
					(thickness 0.15)
				)
			)
		)
		(property "MPN" "CR0402-FX-4993GLF"
			(at 0 0 270)
			(unlocked yes)
			(layer "F.Fab")
			(hide yes)
			(effects
				(font
					(size 1 1)
					(thickness 0.15)
				)
			)
		)
		(property "Manufacturer" "Bourns"
			(at 0 0 270)
			(unlocked yes)
			(layer "F.Fab")
			(hide yes)
			(effects
				(font
					(size 1 1)
					(thickness 0.15)
				)
			)
		)
		(property "License" "Apache-2.0"
			(at 0 0 270)
			(unlocked yes)
			(layer "F.Fab")
			(hide yes)
			(effects
				(font
					(size 1 1)
					(thickness 0.15)
				)
			)
		)
		(property "Author" "Antmicro"
			(at 0 0 270)
			(unlocked yes)
			(layer "F.Fab")
			(hide yes)
			(effects
				(font
					(size 1 1)
					(thickness 0.15)
				)
			)
		)
		(property "Val" "499k"
			(at 0 0 270)
			(unlocked yes)
			(layer "F.Fab")
			(hide yes)
			(effects
				(font
					(size 1 1)
					(thickness 0.15)
				)
			)
		)
		(property "Tolerance" "1%"
			(at 0 0 270)
			(unlocked yes)
			(layer "F.Fab")
			(hide yes)
			(effects
				(font
					(size 1 1)
					(thickness 0.15)
				)
			)
		)
		(sheetname "/DCDC/")
		(sheetfile "dcdc.kicad_sch")
		(attr smd)
		(fp_rect
			(start -0.925 -0.47)
			(end 0.925 0.47)
			(stroke
				(width 0.05)
				(type default)
			)
			(fill no)
			(layer "F.CrtYd")
		)
		(fp_rect
			(start -0.5 -0.25)
			(end 0.5 0.25)
			(stroke
				(width 0.15)
				(type solid)
			)
			(fill no)
			(layer "F.Fab")
		)
		(fp_text user "License: Apache-2.0"
			(at -0.95 5.169 90)
			(layer "F.Fab")
			(effects
				(font
					(size 0.7 0.7)
					(thickness 0.15)
				)
				(justify right top)
			)
		)
		(fp_text user "${REFERENCE}"
			(at -0.95 3.168 90)
			(layer "F.Fab")
			(effects
				(font
					(size 0.7 0.7)
					(thickness 0.15)
				)
				(justify right top)
			)
		)
		(fp_text user "Author: Antmicro"
			(at -0.95 4.169 90)
			(layer "F.Fab")
			(effects
				(font
					(size 0.7 0.7)
					(thickness 0.15)
				)
				(justify right top)
			)
		)
		(pad "1" smd roundrect
			(at -0.48 0 270)
			(size 0.59 0.64)
			(layers "F.Cu" "F.Mask" "F.Paste")
			(roundrect_rratio 0.25)
			(net 1 "GND")
			(pintype "passive")
		)
		(pad "2" smd roundrect
			(at 0.48 0 270)
			(size 0.59 0.64)
			(layers "F.Cu" "F.Mask" "F.Paste")
			(roundrect_rratio 0.25)
			(net 1212 "/DCDC/5V_MODE1")
			(pintype "passive")
		)
	)
	(footprint "antmicro-footprints:USON-10_2.5x1mm_P0.5mm"
		(layer "F.Cu")
		(at 220.855 128.5)
		(descr "USON-10 2.5x1mm_ Pitch 0.5mm")
		(tags "USON-10 2.5x1mm Pitch 0.5mm")
		(property "Reference" "U25"
			(at 1.025 -4.24 90)
			(layer "F.SilkS")
			(effects
				(font
					(size 0.7 0.7)
					(thickness 0.15)
				)
				(justify right top)
			)
		)
		(property "Value" "TPD4E05U06QDQARQ1"
			(at 0.018 2.499 0)
			(layer "F.Fab")
			(effects
				(font
					(size 0.7 0.7)
					(thickness 0.15)
				)
				(justify left bottom)
			)
		)
		(property "Datasheet" "https://www.ti.com/lit/ds/symlink/tpd4e05u06-q1.pdf?HQS=dis-mous-null-mousermode-dsf-pf-null-wwe&ts=1663591265741&ref_url=https%253A%252F%252Fwww.mouser.com%252F"
			(at 0 0 0)
			(layer "F.Fab")
			(hide yes)
			(effects
				(font
					(size 1.27 1.27)
					(thickness 0.15)
				)
			)
		)
		(property "Description" "TVS diode array, 12 kV, USON-10, 5.5 V, 0.5 pF"
			(at 0 0 0)
			(layer "F.Fab")
			(hide yes)
			(effects
				(font
					(size 1.27 1.27)
					(thickness 0.15)
				)
			)
		)
		(property "Manufacturer" "Texas Instruments"
			(at 0 0 0)
			(unlocked yes)
			(layer "F.Fab")
			(hide yes)
			(effects
				(font
					(size 1 1)
					(thickness 0.15)
				)
			)
		)
		(property "MPN" "TPD4E05U06QDQARQ1"
			(at 0 0 0)
			(unlocked yes)
			(layer "F.Fab")
			(hide yes)
			(effects
				(font
					(size 1 1)
					(thickness 0.15)
				)
			)
		)
		(property "Author" "Antmicro"
			(at 0 0 0)
			(unlocked yes)
			(layer "F.Fab")
			(hide yes)
			(effects
				(font
					(size 1 1)
					(thickness 0.15)
				)
			)
		)
		(property "License" "Apache-2.0"
			(at 0 0 0)
			(unlocked yes)
			(layer "F.Fab")
			(hide yes)
			(effects
				(font
					(size 1 1)
					(thickness 0.15)
				)
			)
		)
		(sheetname "/USB Hub/")
		(sheetfile "usb_hub.kicad_sch")
		(attr smd)
		(fp_line
			(start 0.498 -1.401)
			(end -0.5 -1.401)
			(stroke
				(width 0.15)
				(type solid)
			)
			(layer "F.SilkS")
		)
		(fp_line
			(start 0.498 1.398)
			(end -0.5 1.398)
			(stroke
				(width 0.15)
				(type solid)
			)
			(layer "F.SilkS")
		)
		(fp_circle
			(center -0.68 -1.27)
			(end -0.63 -1.27)
			(stroke
				(width 0.15)
				(type solid)
			)
			(fill yes)
			(layer "F.SilkS")
		)
		(fp_rect
			(start -0.8 -1.5)
			(end 0.8 1.499)
			(stroke
				(width 0.05)
				(type solid)
			)
			(fill no)
			(layer "F.CrtYd")
		)
		(fp_line
			(start -0.5 -1)
			(end -0.5 1.249)
			(stroke
				(width 0.15)
				(type solid)
			)
			(layer "F.Fab")
		)
		(fp_line
			(start -0.5 1.249)
			(end 0.498 1.249)
			(stroke
				(width 0.15)
				(type solid)
			)
			(layer "F.Fab")
		)
		(fp_line
			(start -0.25 -1.25)
			(end -0.5 -1)
			(stroke
				(width 0.15)
				(type solid)
			)
			(layer "F.Fab")
		)
		(fp_line
			(start 0.498 -1.25)
			(end -0.25 -1.25)
			(stroke
				(width 0.15)
				(type solid)
			)
			(layer "F.Fab")
		)
		(fp_line
			(start 0.498 -1.25)
			(end 0.498 1.249)
			(stroke
				(width 0.15)
				(type solid)
			)
			(layer "F.Fab")
		)
		(fp_text user "License: Apache-2.0"
			(at -0.802 6.9 0)
			(layer "F.Fab")
			(effects
				(font
					(size 0.7 0.7)
					(thickness 0.15)
				)
				(justify left bottom)
			)
		)
		(fp_text user "Author: Antmicro"
			(at -0.802 5.7 0)
			(layer "F.Fab")
			(effects
				(font
					(size 0.7 0.7)
					(thickness 0.15)
				)
				(justify left bottom)
			)
		)
		(fp_text user "${REFERENCE}"
			(at -0.802 4.498 0)
			(layer "F.Fab")
			(effects
				(font
					(size 0.7 0.7)
					(thickness 0.15)
				)
				(justify left bottom)
			)
		)
		(pad "1" smd roundrect
			(at -0.387 -1 270)
			(size 0.25 0.55)
			(layers "F.Cu" "F.Mask" "F.Paste")
			(roundrect_rratio 0.25)
			(net 505 "/USB Hub/USBC4_D+")
			(pintype "passive")
		)
		(pad "2" smd roundrect
			(at -0.387 -0.5 270)
			(size 0.25 0.55)
			(layers "F.Cu" "F.Mask" "F.Paste")
			(roundrect_rratio 0.25)
			(net 499 "/USB Hub/USBC4_D-")
			(pintype "passive")
		)
		(pad "3" smd roundrect
			(at -0.387 0 270)
			(size 0.4 0.55)
			(layers "F.Cu" "F.Mask" "F.Paste")
			(roundrect_rratio 0.25)
			(net 1 "GND")
			(pintype "power_in")
		)
		(pad "4" smd roundrect
			(at -0.387 0.498 270)
			(size 0.25 0.55)
			(layers "F.Cu" "F.Mask" "F.Paste")
			(roundrect_rratio 0.25)
			(net 502 "/USB Hub/USBC4_CC_{2}")
			(pintype "passive")
		)
		(pad "5" smd roundrect
			(at -0.387 0.998 270)
			(size 0.25 0.55)
			(layers "F.Cu" "F.Mask" "F.Paste")
			(roundrect_rratio 0.25)
			(net 503 "/USB Hub/USBC4_CC_{1}")
			(pintype "passive")
		)
		(pad "6" smd roundrect
			(at 0.385 0.998 270)
			(size 0.25 0.55)
			(layers "F.Cu" "F.Mask" "F.Paste")
			(roundrect_rratio 0.25)
			(net 503 "/USB Hub/USBC4_CC_{1}")
			(pintype "passive")
		)
		(pad "7" smd roundrect
			(at 0.385 0.498 270)
			(size 0.25 0.55)
			(layers "F.Cu" "F.Mask" "F.Paste")
			(roundrect_rratio 0.25)
			(net 502 "/USB Hub/USBC4_CC_{2}")
			(pintype "passive")
		)
		(pad "8" smd roundrect
			(at 0.385 0 270)
			(size 0.4 0.55)
			(layers "F.Cu" "F.Mask" "F.Paste")
			(roundrect_rratio 0.25)
			(net 1 "GND")
			(pintype "passive")
		)
		(pad "9" smd roundrect
			(at 0.385 -0.5 270)
			(size 0.25 0.55)
			(layers "F.Cu" "F.Mask" "F.Paste")
			(roundrect_rratio 0.25)
			(net 499 "/USB Hub/USBC4_D-")
			(pintype "passive")
		)
		(pad "10" smd roundrect
			(at 0.385 -1 270)
			(size 0.25 0.55)
			(layers "F.Cu" "F.Mask" "F.Paste")
			(roundrect_rratio 0.25)
			(net 505 "/USB Hub/USBC4_D+")
			(pintype "passive")
		)
	)
	(footprint "antmicro-footprints:SOT-23-8"
		(layer "F.Cu")
		(at 161.404468 102.075 -90)
		(descr "http://www.ti.com/lit/ds/symlink/ina219.pdf")
		(property "Reference" "U22"
			(at -0.205 2.645 90)
			(layer "F.SilkS")
			(effects
				(font
					(size 0.7 0.7)
					(thickness 0.15)
				)
				(justify right top)
			)
		)
		(property "Value" "INA219AIDCNR"
			(at -2.925 2.8 90)
			(layer "F.Fab")
			(effects
				(font
					(size 0.7 0.7)
					(thickness 0.15)
				)
				(justify right top)
			)
		)
		(property "Datasheet" "https://www.ti.com/lit/ds/symlink/ina219.pdf?ts=1713856455637&ref_url=https%253A%252F%252Fwww.mouser.es%252F"
			(at 0 0 90)
			(layer "F.Fab")
			(hide yes)
			(effects
				(font
					(size 1.27 1.27)
					(thickness 0.15)
				)
			)
		)
		(property "Description" "Zerø-Drift, Bidirectional Current/Power Monitor With I2C Interface"
			(at 0 0 90)
			(layer "F.Fab")
			(hide yes)
			(effects
				(font
					(size 1.27 1.27)
					(thickness 0.15)
				)
			)
		)
		(property "Manufacturer" "Texas Instruments"
			(at 0 0 90)
			(unlocked yes)
			(layer "F.Fab")
			(hide yes)
			(effects
				(font
					(size 1 1)
					(thickness 0.15)
				)
			)
		)
		(property "MPN" "INA219AIDCNR"
			(at 0 0 90)
			(unlocked yes)
			(layer "F.Fab")
			(hide yes)
			(effects
				(font
					(size 1 1)
					(thickness 0.15)
				)
			)
		)
		(property "Author" "Antmicro"
			(at 0 0 90)
			(unlocked yes)
			(layer "F.Fab")
			(hide yes)
			(effects
				(font
					(size 1 1)
					(thickness 0.15)
				)
			)
		)
		(property "License" "Apache-2.0"
			(at 0 0 90)
			(unlocked yes)
			(layer "F.Fab")
			(hide yes)
			(effects
				(font
					(size 1 1)
					(thickness 0.15)
				)
			)
		)
		(component_classes
			(class "DCDC_SOM")
		)
		(sheetname "/DCDC/")
		(sheetfile "dcdc.kicad_sch")
		(attr smd)
		(fp_line
			(start -0.987 1.6)
			(end -0.987 1.324)
			(stroke
				(width 0.15)
				(type solid)
			)
			(layer "F.SilkS")
		)
		(fp_line
			(start -0.613 1.6)
			(end -0.987 1.6)
			(stroke
				(width 0.15)
				(type solid)
			)
			(layer "F.SilkS")
		)
		(fp_line
			(start 1 1.6)
			(end 0.6 1.6)
			(stroke
				(width 0.15)
				(type solid)
			)
			(layer "F.SilkS")
		)
		(fp_line
			(start 1 1.3)
			(end 1 1.6)
			(stroke
				(width 0.15)
				(type solid)
			)
			(layer "F.SilkS")
		)
		(fp_line
			(start -1 -1.3)
			(end -1 -1.6)
			(stroke
				(width 0.15)
				(type solid)
			)
			(layer "F.SilkS")
		)
		(fp_line
			(start 1 -1.3)
			(end 1 -1.6)
			(stroke
				(width 0.15)
				(type solid)
			)
			(layer "F.SilkS")
		)
		(fp_line
			(start -1 -1.6)
			(end -0.6 -1.6)
			(stroke
				(width 0.15)
				(type solid)
			)
			(layer "F.SilkS")
		)
		(fp_line
			(start 1 -1.6)
			(end 0.625 -1.6)
			(stroke
				(width 0.15)
				(type solid)
			)
			(layer "F.SilkS")
		)
		(fp_circle
			(center -1.3 -1.4)
			(end -1.25 -1.4)
			(stroke
				(width 0.15)
				(type solid)
			)
			(fill yes)
			(layer "F.SilkS")
		)
		(fp_rect
			(start -1.9 -1.75)
			(end 1.898 1.75)
			(stroke
				(width 0.05)
				(type solid)
			)
			(fill no)
			(layer "F.CrtYd")
		)
		(fp_line
			(start -1.4 -1.25)
			(end -1.2 -1.45)
			(stroke
				(width 0.15)
				(type solid)
			)
			(layer "F.Fab")
		)
		(fp_rect
			(start -1.401 -1.45)
			(end 1.398 1.449)
			(stroke
				(width 0.15)
				(type solid)
			)
			(fill no)
			(layer "F.Fab")
		)
		(fp_text user "Author: Antmicro"
			(at -2.925 7.2 90)
			(layer "F.Fab")
			(effects
				(font
					(size 0.7 0.7)
					(thickness 0.15)
				)
				(justify right top)
			)
		)
		(fp_text user "License: Apache-2.0"
			(at -2.925 6 90)
			(layer "F.Fab")
			(effects
				(font
					(size 0.7 0.7)
					(thickness 0.15)
				)
				(justify right top)
			)
		)
		(fp_text user "${REFERENCE}"
			(at -2.925 4.8 90)
			(layer "F.Fab")
			(effects
				(font
					(size 0.7 0.7)
					(thickness 0.15)
				)
				(justify right top)
			)
		)
		(pad "1" smd roundrect
			(at -1.3 -0.975 180)
			(size 0.45 1.1)
			(layers "F.Cu" "F.Mask" "F.Paste")
			(roundrect_rratio 0.25)
			(net 1283 "Net-(U22-IN+)")
			(pinfunction "IN+")
			(pintype "passive")
		)
		(pad "2" smd roundrect
			(at -1.3 -0.325 180)
			(size 0.45 1.1)
			(layers "F.Cu" "F.Mask" "F.Paste")
			(roundrect_rratio 0.25)
			(net 1187 "Net-(U22-IN-)")
			(pinfunction "IN-")
			(pintype "passive")
		)
		(pad "3" smd roundrect
			(at -1.3 0.325 180)
			(size 0.45 1.1)
			(layers "F.Cu" "F.Mask" "F.Paste")
			(roundrect_rratio 0.25)
			(net 1 "GND")
			(pinfunction "GND")
			(pintype "power_in")
		)
		(pad "4" smd roundrect
			(at -1.3 0.975 180)
			(size 0.45 1.1)
			(layers "F.Cu" "F.Mask" "F.Paste")
			(roundrect_rratio 0.25)
			(net 4 "+3V3_AON")
			(pinfunction "V_{S}")
			(pintype "power_in")
		)
		(pad "5" smd roundrect
			(at 1.3 0.975 180)
			(size 0.45 1.1)
			(layers "F.Cu" "F.Mask" "F.Paste")
			(roundrect_rratio 0.25)
			(net 853 "/I2C_{SYS}.SCL")
			(pinfunction "SCL")
			(pintype "open_collector")
		)
		(pad "6" smd roundrect
			(at 1.3 0.325 180)
			(size 0.45 1.1)
			(layers "F.Cu" "F.Mask" "F.Paste")
			(roundrect_rratio 0.25)
			(net 850 "/I2C_{SYS}.SDA")
			(pinfunction "SDA")
			(pintype "open_collector")
		)
		(pad "7" smd roundrect
			(at 1.3 -0.325 180)
			(size 0.45 1.1)
			(layers "F.Cu" "F.Mask" "F.Paste")
			(roundrect_rratio 0.25)
			(net 4 "+3V3_AON")
			(pinfunction "A0")
			(pintype "passive")
		)
		(pad "8" smd roundrect
			(at 1.3 -0.975 180)
			(size 0.45 1.1)
			(layers "F.Cu" "F.Mask" "F.Paste")
			(roundrect_rratio 0.25)
			(net 4 "+3V3_AON")
			(pinfunction "A1")
			(pintype "passive")
		)
	)
	(footprint "antmicro-footprints:C_0805_2012Metric"
		(layer "F.Cu")
		(at 174.99 73.32 -90)
		(descr "Capacitor SMD 0805")
		(tags "capacitor SMD 0805")
		(property "Reference" "C289"
			(at 1.81 9.64 90)
			(layer "F.SilkS")
			(effects
				(font
					(size 0.7 0.7)
					(thickness 0.15)
				)
				(justify right top)
			)
		)
		(property "Value" "C_22u_25V_0805"
			(at -2.055717 1.963152 90)
			(layer "F.Fab")
			(effects
				(font
					(size 0.7 0.7)
					(thickness 0.15)
				)
				(justify right top)
			)
		)
		(property "Datasheet" "https://product.samsungsem.com/mlcc/CL21A226MAYNNN.do"
			(at 0 0 90)
			(layer "F.Fab")
			(hide yes)
			(effects
				(font
					(size 1.27 1.27)
					(thickness 0.15)
				)
			)
		)
		(property "Description" "SMT Multilayer Ceramic Capacitor, 22uF, +/-20%, 25V, X5R, 0805 [2012 Metric]"
			(at 0 0 90)
			(layer "F.Fab")
			(hide yes)
			(effects
				(font
					(size 1.27 1.27)
					(thickness 0.15)
				)
			)
		)
		(property "MPN" "CL21A226MAYNNNE"
			(at 0 0 270)
			(unlocked yes)
			(layer "F.Fab")
			(hide yes)
			(effects
				(font
					(size 1 1)
					(thickness 0.15)
				)
			)
		)
		(property "Manufacturer" "Samsung Electro-Mechanics"
			(at 0 0 270)
			(unlocked yes)
			(layer "F.Fab")
			(hide yes)
			(effects
				(font
					(size 1 1)
					(thickness 0.15)
				)
			)
		)
		(property "License" "Apache-2.0"
			(at 0 0 270)
			(unlocked yes)
			(layer "F.Fab")
			(hide yes)
			(effects
				(font
					(size 1 1)
					(thickness 0.15)
				)
			)
		)
		(property "Author" "Antmicro"
			(at 0 0 270)
			(unlocked yes)
			(layer "F.Fab")
			(hide yes)
			(effects
				(font
					(size 1 1)
					(thickness 0.15)
				)
			)
		)
		(property "Val" "22u"
			(at 0 0 270)
			(unlocked yes)
			(layer "F.Fab")
			(hide yes)
			(effects
				(font
					(size 1 1)
					(thickness 0.15)
				)
			)
		)
		(property "Voltage" "25V"
			(at 0 0 270)
			(unlocked yes)
			(layer "F.Fab")
			(hide yes)
			(effects
				(font
					(size 1 1)
					(thickness 0.15)
				)
			)
		)
		(property "Dielectric" "X5R"
			(at 0 0 270)
			(unlocked yes)
			(layer "F.Fab")
			(hide yes)
			(effects
				(font
					(size 1 1)
					(thickness 0.15)
				)
			)
		)
		(property "Public" "False"
			(at 0 0 270)
			(unlocked yes)
			(layer "F.Fab")
			(hide yes)
			(effects
				(font
					(size 1 1)
					(thickness 0.15)
				)
			)
		)
		(component_classes
			(class "DCDC_20V")
		)
		(sheetname "/DCDC/")
		(sheetfile "dcdc.kicad_sch")
		(attr smd)
		(fp_line
			(start -0.3 0.7)
			(end 0.3 0.7)
			(stroke
				(width 0.15)
				(type solid)
			)
			(layer "F.SilkS")
		)
		(fp_line
			(start -0.3 -0.7)
			(end 0.3 -0.7)
			(stroke
				(width 0.15)
				(type solid)
			)
			(layer "F.SilkS")
		)
		(fp_rect
			(start 1.95 -0.9)
			(end -1.95 0.9)
			(stroke
				(width 0.05)
				(type default)
			)
			(fill no)
			(layer "F.CrtYd")
		)
		(fp_rect
			(start -0.95 -0.675)
			(end 0.95 0.675)
			(stroke
				(width 0.15)
				(type solid)
			)
			(fill no)
			(layer "F.Fab")
		)
		(fp_text user "${REFERENCE}"
			(at -1.9 3.947 90)
			(layer "F.Fab")
			(effects
				(font
					(size 0.7 0.7)
					(thickness 0.15)
				)
				(justify right top)
			)
		)
		(fp_text user "License: Apache-2.0"
			(at -1.9 4.947 90)
			(layer "F.Fab")
			(effects
				(font
					(size 0.7 0.7)
					(thickness 0.15)
				)
				(justify right top)
			)
		)
		(fp_text user "Author: Antmicro"
			(at -1.9 5.947 90)
			(layer "F.Fab")
			(effects
				(font
					(size 0.7 0.7)
					(thickness 0.15)
				)
				(justify right top)
			)
		)
		(pad "1" smd roundrect
			(at -1.1 0 270)
			(size 1.2 1.3)
			(layers "F.Cu" "F.Mask" "F.Paste")
			(roundrect_rratio 0.25)
			(net 1 "GND")
			(pintype "passive")
		)
		(pad "2" smd roundrect
			(at 1.1 0 270)
			(size 1.2 1.3)
			(layers "F.Cu" "F.Mask" "F.Paste")
			(roundrect_rratio 0.25)
			(net 1105 "/DCDC/20V_OUT")
			(pintype "passive")
		)
	)
	(footprint "antmicro-footprints:L_Bourns-SRP6050CA"
		(layer "F.Cu")
		(at 178.86 118.426 180)
		(property "Reference" "L1"
			(at -3.629468 0.626 90)
			(layer "F.SilkS")
			(effects
				(font
					(size 0.7 0.7)
					(thickness 0.15)
				)
				(justify right top)
			)
		)
		(property "Value" "L_1u_20A_Bourns-SRP6050CA"
			(at -0.025 4.85 0)
			(layer "F.Fab")
			(effects
				(font
					(size 0.7 0.7)
					(thickness 0.15)
				)
				(justify right top)
			)
		)
		(property "Datasheet" "https://www.bourns.com/docs/Product-Datasheets/SRP6050CA.pdf"
			(at 0 0 0)
			(layer "F.Fab")
			(hide yes)
			(effects
				(font
					(size 1.27 1.27)
					(thickness 0.15)
				)
			)
		)
		(property "Description" "Power Inductor (SMT), 1 µH, 20 A, Shielded, 23 A, SRP6050CA"
			(at 0 0 0)
			(layer "F.Fab")
			(hide yes)
			(effects
				(font
					(size 1.27 1.27)
					(thickness 0.15)
				)
			)
		)
		(property "Val" "1u/20A"
			(at 0 0 180)
			(unlocked yes)
			(layer "F.Fab")
			(hide yes)
			(effects
				(font
					(size 1 1)
					(thickness 0.15)
				)
			)
		)
		(property "Manufacturer" "Bourns"
			(at 0 0 180)
			(unlocked yes)
			(layer "F.Fab")
			(hide yes)
			(effects
				(font
					(size 1 1)
					(thickness 0.15)
				)
			)
		)
		(property "MPN" "SRP6050CA-1R0M"
			(at 0 0 180)
			(unlocked yes)
			(layer "F.Fab")
			(hide yes)
			(effects
				(font
					(size 1 1)
					(thickness 0.15)
				)
			)
		)
		(property "ISat" "23 A"
			(at 0 0 180)
			(unlocked yes)
			(layer "F.Fab")
			(hide yes)
			(effects
				(font
					(size 1 1)
					(thickness 0.15)
				)
			)
		)
		(property "IMax" "20 A"
			(at 0 0 180)
			(unlocked yes)
			(layer "F.Fab")
			(hide yes)
			(effects
				(font
					(size 1 1)
					(thickness 0.15)
				)
			)
		)
		(property "Size" "6.6x6.4"
			(at 0 0 180)
			(unlocked yes)
			(layer "F.Fab")
			(hide yes)
			(effects
				(font
					(size 1 1)
					(thickness 0.15)
				)
			)
		)
		(property "Author" "Antmicro"
			(at 0 0 180)
			(unlocked yes)
			(layer "F.Fab")
			(hide yes)
			(effects
				(font
					(size 1 1)
					(thickness 0.15)
				)
			)
		)
		(property "License" "Apache-2.0"
			(at 0 0 180)
			(unlocked yes)
			(layer "F.Fab")
			(hide yes)
			(effects
				(font
					(size 1 1)
					(thickness 0.15)
				)
			)
		)
		(sheetname "/DCDC/")
		(sheetfile "dcdc.kicad_sch")
		(attr smd)
		(fp_line
			(start 3.2 3.298)
			(end -3.2 3.298)
			(stroke
				(width 0.15)
				(type solid)
			)
			(layer "F.SilkS")
		)
		(fp_line
			(start 3.2 -3.301)
			(end 3.2 3.298)
			(stroke
				(width 0.15)
				(type solid)
			)
			(layer "F.SilkS")
		)
		(fp_line
			(start -3.2 -3.301)
			(end 3.2 -3.301)
			(stroke
				(width 0.15)
				(type solid)
			)
			(layer "F.SilkS")
		)
		(fp_line
			(start -3.2 -3.301)
			(end -3.2 3.298)
			(stroke
				(width 0.15)
				(type solid)
			)
			(layer "F.SilkS")
		)
		(fp_rect
			(start -3.45 -3.55)
			(end 3.45 3.55)
			(stroke
				(width 0.05)
				(type solid)
			)
			(fill no)
			(layer "F.CrtYd")
		)
		(fp_rect
			(start -3.202 -3.301)
			(end 3.2 3.298)
			(stroke
				(width 0.15)
				(type solid)
			)
			(fill no)
			(layer "F.Fab")
		)
		(fp_text user "Author: Antmicro"
			(at -3.45 9.25 0)
			(layer "F.Fab")
			(effects
				(font
					(size 0.7 0.7)
					(thickness 0.15)
				)
				(justify right top)
			)
		)
		(fp_text user "${REFERENCE}"
			(at -3.45 6.85 0)
			(layer "F.Fab")
			(effects
				(font
					(size 0.7 0.7)
					(thickness 0.15)
				)
				(justify right top)
			)
		)
		(fp_text user "License: Apache-2.0"
			(at -3.45 8.05 0)
			(layer "F.Fab")
			(effects
				(font
					(size 0.7 0.7)
					(thickness 0.15)
				)
				(justify right top)
			)
		)
		(pad "1" smd roundrect
			(at -2.025 0 180)
			(size 1.55 5.6)
			(layers "F.Cu" "F.Mask" "F.Paste")
			(roundrect_rratio 0.1)
			(net 1181 "/DCDC/5V_SW")
			(pintype "passive")
		)
		(pad "2" smd roundrect
			(at 2.025 0 180)
			(size 1.55 5.6)
			(layers "F.Cu" "F.Mask" "F.Paste")
			(roundrect_rratio 0.1)
			(net 253 "/DCDC/5V_OUT")
			(pintype "passive")
		)
	)
	(footprint "antmicro-footprints:R_0402_1005Metric"
		(layer "F.Cu")
		(at 182.829468 67.72 90)
		(descr "Resistor SMD 0402")
		(tags "resistor SMD 0402")
		(property "Reference" "R94"
			(at -0.75 2.54 90)
			(layer "F.SilkS")
			(effects
				(font
					(size 0.7 0.7)
					(thickness 0.15)
				)
				(justify left bottom)
			)
		)
		(property "Value" "R_330k_0402"
			(at -1.011843 1.772047 90)
			(layer "F.Fab")
			(effects
				(font
					(size 0.7 0.7)
					(thickness 0.15)
				)
				(justify left bottom)
			)
		)
		(property "Datasheet" "https://www.bourns.com/docs/product-datasheets/cr.pdf"
			(at 0 0 90)
			(layer "F.Fab")
			(hide yes)
			(effects
				(font
					(size 1.27 1.27)
					(thickness 0.15)
				)
			)
		)
		(property "Description" "SMD Chip Resistor"
			(at 0 0 90)
			(layer "F.Fab")
			(hide yes)
			(effects
				(font
					(size 1.27 1.27)
					(thickness 0.15)
				)
			)
		)
		(property "MPN" "CR0402-FX-3303GLF"
			(at 0 0 90)
			(unlocked yes)
			(layer "F.Fab")
			(hide yes)
			(effects
				(font
					(size 1 1)
					(thickness 0.15)
				)
			)
		)
		(property "Manufacturer" "Bourns"
			(at 0 0 90)
			(unlocked yes)
			(layer "F.Fab")
			(hide yes)
			(effects
				(font
					(size 1 1)
					(thickness 0.15)
				)
			)
		)
		(property "License" "Apache-2.0"
			(at 0 0 90)
			(unlocked yes)
			(layer "F.Fab")
			(hide yes)
			(effects
				(font
					(size 1 1)
					(thickness 0.15)
				)
			)
		)
		(property "Author" "Antmicro"
			(at 0 0 90)
			(unlocked yes)
			(layer "F.Fab")
			(hide yes)
			(effects
				(font
					(size 1 1)
					(thickness 0.15)
				)
			)
		)
		(property "Val" "330k"
			(at 0 0 90)
			(unlocked yes)
			(layer "F.Fab")
			(hide yes)
			(effects
				(font
					(size 1 1)
					(thickness 0.15)
				)
			)
		)
		(property "Tolerance" "1%"
			(at 0 0 90)
			(unlocked yes)
			(layer "F.Fab")
			(hide yes)
			(effects
				(font
					(size 1 1)
					(thickness 0.15)
				)
			)
		)
		(component_classes
			(class "DCDC_20V")
		)
		(sheetname "/DCDC/")
		(sheetfile "dcdc.kicad_sch")
		(attr smd)
		(fp_rect
			(start -0.925 -0.47)
			(end 0.925 0.47)
			(stroke
				(width 0.05)
				(type default)
			)
			(fill no)
			(layer "F.CrtYd")
		)
		(fp_rect
			(start -0.5 -0.25)
			(end 0.5 0.25)
			(stroke
				(width 0.15)
				(type solid)
			)
			(fill no)
			(layer "F.Fab")
		)
		(fp_text user "License: Apache-2.0"
			(at -0.95 5.169 90)
			(layer "F.Fab")
			(effects
				(font
					(size 0.7 0.7)
					(thickness 0.15)
				)
				(justify left bottom)
			)
		)
		(fp_text user "Author: Antmicro"
			(at -0.95 4.169 90)
			(layer "F.Fab")
			(effects
				(font
					(size 0.7 0.7)
					(thickness 0.15)
				)
				(justify left bottom)
			)
		)
		(fp_text user "${REFERENCE}"
			(at -0.95 3.168 90)
			(layer "F.Fab")
			(effects
				(font
					(size 0.7 0.7)
					(thickness 0.15)
				)
				(justify left bottom)
			)
		)
		(pad "1" smd roundrect
			(at -0.48 0 90)
			(size 0.59 0.64)
			(layers "F.Cu" "F.Mask" "F.Paste")
			(roundrect_rratio 0.25)
			(net 1220 "/DCDC/20V_FB")
			(pintype "passive")
		)
		(pad "2" smd roundrect
			(at 0.48 0 90)
			(size 0.59 0.64)
			(layers "F.Cu" "F.Mask" "F.Paste")
			(roundrect_rratio 0.25)
			(net 1105 "/DCDC/20V_OUT")
			(pintype "passive")
		)
	)
	(footprint "antmicro-footprints:C_0402_1005Metric"
		(layer "F.Cu")
		(at 91.1 94.5)
		(descr "Capacitor SMD 0402")
		(tags "capacitor SMD 0402")
		(property "Reference" "C346"
			(at 1.1 0.500001 0)
			(layer "F.SilkS")
			(effects
				(font
					(size 0.7 0.7)
					(thickness 0.15)
				)
				(justify left bottom)
			)
		)
		(property "Value" "C_100n_0402"
			(at -1.022927 2.155213 0)
			(layer "F.Fab")
			(effects
				(font
					(size 0.7 0.7)
					(thickness 0.15)
				)
				(justify left bottom)
			)
		)
		(property "Datasheet" "https://www.murata.com/products/productdetail?partno=GRM155R61H104KE14%23"
			(at 0 0 0)
			(layer "F.Fab")
			(hide yes)
			(effects
				(font
					(size 1.27 1.27)
					(thickness 0.15)
				)
			)
		)
		(property "Description" "SMD Multilayer Ceramic Capacitor, 0.1 µF, 50 V, 0402 [1005 Metric], ± 10%, X5R, GRM Series"
			(at 0 0 0)
			(layer "F.Fab")
			(hide yes)
			(effects
				(font
					(size 1.27 1.27)
					(thickness 0.15)
				)
			)
		)
		(property "Manufacturer" "Murata"
			(at 0 0 0)
			(unlocked yes)
			(layer "F.Fab")
			(hide yes)
			(effects
				(font
					(size 1 1)
					(thickness 0.15)
				)
			)
		)
		(property "MPN" "GRM155R61H104KE14D"
			(at 0 0 0)
			(unlocked yes)
			(layer "F.Fab")
			(hide yes)
			(effects
				(font
					(size 1 1)
					(thickness 0.15)
				)
			)
		)
		(property "Val" "100n"
			(at 0 0 0)
			(unlocked yes)
			(layer "F.Fab")
			(hide yes)
			(effects
				(font
					(size 1 1)
					(thickness 0.15)
				)
			)
		)
		(property "License" "Apache-2.0"
			(at 0 0 0)
			(unlocked yes)
			(layer "F.Fab")
			(hide yes)
			(effects
				(font
					(size 1 1)
					(thickness 0.15)
				)
			)
		)
		(property "Author" "Antmicro"
			(at 0 0 0)
			(unlocked yes)
			(layer "F.Fab")
			(hide yes)
			(effects
				(font
					(size 1 1)
					(thickness 0.15)
				)
			)
		)
		(property "Voltage" "50V"
			(at 0 0 0)
			(unlocked yes)
			(layer "F.Fab")
			(hide yes)
			(effects
				(font
					(size 1 1)
					(thickness 0.15)
				)
			)
		)
		(property "Dielectric" "X5R"
			(at 0 0 0)
			(unlocked yes)
			(layer "F.Fab")
			(hide yes)
			(effects
				(font
					(size 1 1)
					(thickness 0.15)
				)
			)
		)
		(sheetname "/SoM_IO2/")
		(sheetfile "som_io2.kicad_sch")
		(attr smd)
		(fp_rect
			(start -0.925 -0.47)
			(end 0.925 0.47)
			(stroke
				(width 0.05)
				(type default)
			)
			(fill no)
			(layer "F.CrtYd")
		)
		(fp_line
			(start -0.494 -0.25)
			(end 0.504 -0.25)
			(stroke
				(width 0.15)
				(type solid)
			)
			(layer "F.Fab")
		)
		(fp_line
			(start -0.494 0.248)
			(end -0.494 -0.25)
			(stroke
				(width 0.15)
				(type solid)
			)
			(layer "F.Fab")
		)
		(fp_line
			(start 0.504 -0.25)
			(end 0.504 0.248)
			(stroke
				(width 0.15)
				(type solid)
			)
			(layer "F.Fab")
		)
		(fp_line
			(start 0.504 0.248)
			(end -0.494 0.248)
			(stroke
				(width 0.15)
				(type solid)
			)
			(layer "F.Fab")
		)
		(fp_text user "Author: Antmicro"
			(at -0.939 3.399 0)
			(layer "F.Fab")
			(effects
				(font
					(size 0.7 0.7)
					(thickness 0.15)
				)
				(justify left bottom)
			)
		)
		(fp_text user "${REFERENCE}"
			(at -0.939 4.599 0)
			(layer "F.Fab")
			(effects
				(font
					(size 0.7 0.7)
					(thickness 0.15)
				)
				(justify left bottom)
			)
		)
		(fp_text user "License: Apache-2.0"
			(at -0.939 5.799 0)
			(layer "F.Fab")
			(effects
				(font
					(size 0.7 0.7)
					(thickness 0.15)
				)
				(justify left bottom)
			)
		)
		(pad "1" smd roundrect
			(at -0.48 0)
			(size 0.59 0.64)
			(layers "F.Cu" "F.Mask" "F.Paste")
			(roundrect_rratio 0.25)
			(net 593 "/Expansion connector/DP3.TX2+")
			(pintype "passive")
		)
		(pad "2" smd roundrect
			(at 0.48 0)
			(size 0.59 0.64)
			(layers "F.Cu" "F.Mask" "F.Paste")
			(roundrect_rratio 0.25)
			(net 1266 "/SoM_IO2/DP3.TX2_C+")
			(pintype "passive")
		)
	)
	(footprint "antmicro-footprints:R_0402_1005Metric"
		(layer "F.Cu")
		(at 61.6 63.2)
		(descr "Resistor SMD 0402")
		(tags "resistor SMD 0402")
		(property "Reference" "R160"
			(at -1.4 3.6 0)
			(layer "F.SilkS")
			(effects
				(font
					(size 0.7 0.7)
					(thickness 0.15)
				)
				(justify left bottom)
			)
		)
		(property "Value" "R_0R_0402"
			(at -1.011843 1.772046 0)
			(layer "F.Fab")
			(effects
				(font
					(size 0.7 0.7)
					(thickness 0.15)
				)
				(justify left bottom)
			)
		)
		(property "Datasheet" "https://industrial.panasonic.com/cdbs/www-data/pdf/RDA0000/AOA0000C301.pdf"
			(at 0 0 0)
			(layer "F.Fab")
			(hide yes)
			(effects
				(font
					(size 1.27 1.27)
					(thickness 0.15)
				)
			)
		)
		(property "Description" "SMD Chip Resistor, Jumper, 0 ohm, 100 mW, 0402 [1005 Metric], Thick Film, General Purpose"
			(at 0 0 0)
			(layer "F.Fab")
			(hide yes)
			(effects
				(font
					(size 1.27 1.27)
					(thickness 0.15)
				)
			)
		)
		(property "Manufacturer" "Panasonic"
			(at 0 0 0)
			(unlocked yes)
			(layer "F.Fab")
			(hide yes)
			(effects
				(font
					(size 1 1)
					(thickness 0.15)
				)
			)
		)
		(property "MPN" "ERJ2GE0R00X"
			(at 0 0 0)
			(unlocked yes)
			(layer "F.Fab")
			(hide yes)
			(effects
				(font
					(size 1 1)
					(thickness 0.15)
				)
			)
		)
		(property "Val" "0R"
			(at 0 0 0)
			(unlocked yes)
			(layer "F.Fab")
			(hide yes)
			(effects
				(font
					(size 1 1)
					(thickness 0.15)
				)
			)
		)
		(property "License" "Apache-2.0"
			(at 0 0 0)
			(unlocked yes)
			(layer "F.Fab")
			(hide yes)
			(effects
				(font
					(size 1 1)
					(thickness 0.15)
				)
			)
		)
		(property "Author" "Antmicro"
			(at 0 0 0)
			(unlocked yes)
			(layer "F.Fab")
			(hide yes)
			(effects
				(font
					(size 1 1)
					(thickness 0.15)
				)
			)
		)
		(property "Tolerance" "~"
			(at 0 0 0)
			(unlocked yes)
			(layer "F.Fab")
			(hide yes)
			(effects
				(font
					(size 1 1)
					(thickness 0.15)
				)
			)
		)
		(property "Current" "1A"
			(at 0 0 0)
			(unlocked yes)
			(layer "F.Fab")
			(hide yes)
			(effects
				(font
					(size 1 1)
					(thickness 0.15)
				)
			)
		)
		(sheetname "/CSI/")
		(sheetfile "csi.kicad_sch")
		(attr smd)
		(fp_poly
			(pts
				(xy -0.925 -0.47) (xy -0.925 0.47) (xy 0.925 0.47) (xy 0.925 -0.47)
			)
			(stroke
				(width 0.05)
				(type default)
			)
			(fill no)
			(layer "F.CrtYd")
		)
		(fp_poly
			(pts
				(xy -0.5 -0.25) (xy -0.5 0.25) (xy 0.5 0.25) (xy 0.5 -0.25)
			)
			(stroke
				(width 0.15)
				(type solid)
			)
			(fill no)
			(layer "F.Fab")
		)
		(fp_text user "${REFERENCE}"
			(at -0.95 3.168 0)
			(layer "F.Fab")
			(effects
				(font
					(size 0.7 0.7)
					(thickness 0.15)
				)
				(justify left bottom)
			)
		)
		(fp_text user "License: Apache-2.0"
			(at -0.949999 5.169 0)
			(layer "F.Fab")
			(effects
				(font
					(size 0.7 0.7)
					(thickness 0.15)
				)
				(justify left bottom)
			)
		)
		(fp_text user "Author: Antmicro"
			(at -0.95 4.169 0)
			(layer "F.Fab")
			(effects
				(font
					(size 0.7 0.7)
					(thickness 0.15)
				)
				(justify left bottom)
			)
		)
		(pad "1" smd roundrect
			(at -0.48 0)
			(size 0.59 0.64)
			(layers "F.Cu" "F.Mask" "F.Paste")
			(roundrect_rratio 0.25)
			(net 1 "GND")
			(pintype "passive")
		)
		(pad "2" smd roundrect
			(at 0.48 0)
			(size 0.59 0.64)
			(layers "F.Cu" "F.Mask" "F.Paste")
			(roundrect_rratio 0.25)
			(net 980 "/CSI/I2C_MUX_A0")
			(pintype "passive")
		)
	)
	(footprint "antmicro-footprints:XDFN-2_1x0.60mm"
		(layer "F.Cu")
		(at 187.3 61 90)
		(property "Reference" "D38"
			(at -0.651 -0.25 90)
			(layer "F.SilkS")
			(effects
				(font
					(size 0.7 0.7)
					(thickness 0.15)
				)
				(justify right top)
			)
		)
		(property "Value" "TPD1E0B04_XDFN-2"
			(at 0 1.5 90)
			(layer "F.Fab")
			(effects
				(font
					(size 0.7 0.7)
					(thickness 0.15)
				)
				(justify left bottom)
			)
		)
		(property "Datasheet" "https://www.ti.com/general/docs/suppproductinfo.tsp?distId=26&gotoUrl=https://www.ti.com/lit/gpn/tpd1e0b04"
			(at 0 0 90)
			(layer "F.Fab")
			(hide yes)
			(effects
				(font
					(size 1.27 1.27)
					(thickness 0.15)
				)
			)
		)
		(property "Description" "Bidirectional TVS, 8 kV,  XDFN-2, 3.6 V, 0.18 pF"
			(at 0 0 90)
			(layer "F.Fab")
			(hide yes)
			(effects
				(font
					(size 1.27 1.27)
					(thickness 0.15)
				)
			)
		)
		(property "MPN" "TPD1E0B04DPYR"
			(at 0 0 90)
			(layer "F.Fab")
			(hide yes)
			(effects
				(font
					(size 1.27 1.27)
					(thickness 0.15)
				)
			)
		)
		(property "Manufacturer" "Texas Instruments"
			(at 0 0 90)
			(layer "F.Fab")
			(hide yes)
			(effects
				(font
					(size 1.27 1.27)
					(thickness 0.15)
				)
			)
		)
		(property "Author" "Antmicro"
			(at 0 0 90)
			(unlocked yes)
			(layer "F.Fab")
			(hide yes)
			(effects
				(font
					(size 1 1)
					(thickness 0.15)
				)
			)
		)
		(property "License" "Apache-2.0"
			(at 0 0 90)
			(unlocked yes)
			(layer "F.Fab")
			(hide yes)
			(effects
				(font
					(size 1 1)
					(thickness 0.15)
				)
			)
		)
		(sheetname "/Peripherals/")
		(sheetfile "peripherals.kicad_sch")
		(attr smd)
		(fp_poly
			(pts
				(xy -0.725 -0.475) (xy 0.725 -0.475) (xy 0.725 0.475) (xy -0.725 0.475)
			)
			(stroke
				(width 0.05)
				(type solid)
			)
			(fill no)
			(layer "F.CrtYd")
		)
		(fp_poly
			(pts
				(xy -0.55 -0.35) (xy 0.55 -0.35) (xy 0.55 0.35) (xy -0.55 0.35)
			)
			(stroke
				(width 0.15)
				(type solid)
			)
			(fill no)
			(layer "F.Fab")
		)
		(fp_text user "${REFERENCE}"
			(at -0.8 3.2 90)
			(layer "F.Fab")
			(effects
				(font
					(size 0.7 0.7)
					(thickness 0.15)
				)
				(justify left bottom)
			)
		)
		(fp_text user "License: Apache-2.0"
			(at -0.799999 5.6 90)
			(layer "F.Fab")
			(effects
				(font
					(size 0.7 0.7)
					(thickness 0.15)
				)
				(justify left bottom)
			)
		)
		(fp_text user "Author: Antmicro"
			(at -0.8 4.4 90)
			(layer "F.Fab")
			(effects
				(font
					(size 0.7 0.7)
					(thickness 0.15)
				)
				(justify left bottom)
			)
		)
		(pad "1" smd roundrect
			(at -0.350999 0 90)
			(size 0.3 0.5)
			(layers "F.Cu" "F.Mask" "F.Paste")
			(roundrect_rratio 0.25)
			(net 1 "GND")
			(pinfunction "C")
			(pintype "passive")
		)
		(pad "2" smd roundrect
			(at 0.349 0 90)
			(size 0.3 0.5)
			(layers "F.Cu" "F.Mask" "F.Paste")
			(roundrect_rratio 0.25)
			(net 356 "/Expansion connector/GPIO.USER_BTN1")
			(pinfunction "A")
			(pintype "passive")
		)
	)
	(footprint "antmicro-footprints:C_0805_2012Metric"
		(layer "F.Cu")
		(at 165.91 79.81 90)
		(descr "Capacitor SMD 0805")
		(tags "capacitor SMD 0805")
		(property "Reference" "C291"
			(at -4.59 0.39 90)
			(layer "F.SilkS")
			(effects
				(font
					(size 0.7 0.7)
					(thickness 0.15)
				)
				(justify left bottom)
			)
		)
		(property "Value" "C_22u_25V_0805"
			(at -2.055717 1.963152 90)
			(layer "F.Fab")
			(effects
				(font
					(size 0.7 0.7)
					(thickness 0.15)
				)
				(justify left bottom)
			)
		)
		(property "Datasheet" "https://product.samsungsem.com/mlcc/CL21A226MAYNNN.do"
			(at 0 0 90)
			(layer "F.Fab")
			(hide yes)
			(effects
				(font
					(size 1.27 1.27)
					(thickness 0.15)
				)
			)
		)
		(property "Description" "SMT Multilayer Ceramic Capacitor, 22uF, +/-20%, 25V, X5R, 0805 [2012 Metric]"
			(at 0 0 90)
			(layer "F.Fab")
			(hide yes)
			(effects
				(font
					(size 1.27 1.27)
					(thickness 0.15)
				)
			)
		)
		(property "MPN" "CL21A226MAYNNNE"
			(at 0 0 90)
			(unlocked yes)
			(layer "F.Fab")
			(hide yes)
			(effects
				(font
					(size 1 1)
					(thickness 0.15)
				)
			)
		)
		(property "Manufacturer" "Samsung Electro-Mechanics"
			(at 0 0 90)
			(unlocked yes)
			(layer "F.Fab")
			(hide yes)
			(effects
				(font
					(size 1 1)
					(thickness 0.15)
				)
			)
		)
		(property "License" "Apache-2.0"
			(at 0 0 90)
			(unlocked yes)
			(layer "F.Fab")
			(hide yes)
			(effects
				(font
					(size 1 1)
					(thickness 0.15)
				)
			)
		)
		(property "Author" "Antmicro"
			(at 0 0 90)
			(unlocked yes)
			(layer "F.Fab")
			(hide yes)
			(effects
				(font
					(size 1 1)
					(thickness 0.15)
				)
			)
		)
		(property "Val" "22u"
			(at 0 0 90)
			(unlocked yes)
			(layer "F.Fab")
			(hide yes)
			(effects
				(font
					(size 1 1)
					(thickness 0.15)
				)
			)
		)
		(property "Voltage" "25V"
			(at 0 0 90)
			(unlocked yes)
			(layer "F.Fab")
			(hide yes)
			(effects
				(font
					(size 1 1)
					(thickness 0.15)
				)
			)
		)
		(property "Dielectric" "X5R"
			(at 0 0 90)
			(unlocked yes)
			(layer "F.Fab")
			(hide yes)
			(effects
				(font
					(size 1 1)
					(thickness 0.15)
				)
			)
		)
		(property "Public" "False"
			(at 0 0 90)
			(unlocked yes)
			(layer "F.Fab")
			(hide yes)
			(effects
				(font
					(size 1 1)
					(thickness 0.15)
				)
			)
		)
		(component_classes
			(class "DCDC_20V")
		)
		(sheetname "/DCDC/")
		(sheetfile "dcdc.kicad_sch")
		(attr smd)
		(fp_line
			(start -0.3 -0.7)
			(end 0.3 -0.7)
			(stroke
				(width 0.15)
				(type solid)
			)
			(layer "F.SilkS")
		)
		(fp_line
			(start -0.3 0.7)
			(end 0.3 0.7)
			(stroke
				(width 0.15)
				(type solid)
			)
			(layer "F.SilkS")
		)
		(fp_rect
			(start 1.95 -0.9)
			(end -1.95 0.9)
			(stroke
				(width 0.05)
				(type default)
			)
			(fill no)
			(layer "F.CrtYd")
		)
		(fp_rect
			(start -0.95 -0.675)
			(end 0.95 0.675)
			(stroke
				(width 0.15)
				(type solid)
			)
			(fill no)
			(layer "F.Fab")
		)
		(fp_text user "License: Apache-2.0"
			(at -1.9 4.947 90)
			(layer "F.Fab")
			(effects
				(font
					(size 0.7 0.7)
					(thickness 0.15)
				)
				(justify left bottom)
			)
		)
		(fp_text user "Author: Antmicro"
			(at -1.9 5.947 90)
			(layer "F.Fab")
			(effects
				(font
					(size 0.7 0.7)
					(thickness 0.15)
				)
				(justify left bottom)
			)
		)
		(fp_text user "${REFERENCE}"
			(at -1.9 3.947 90)
			(layer "F.Fab")
			(effects
				(font
					(size 0.7 0.7)
					(thickness 0.15)
				)
				(justify left bottom)
			)
		)
		(pad "1" smd roundrect
			(at -1.1 0 90)
			(size 1.2 1.3)
			(layers "F.Cu" "F.Mask" "F.Paste")
			(roundrect_rratio 0.25)
			(net 1 "GND")
			(pintype "passive")
		)
		(pad "2" smd roundrect
			(at 1.1 0 90)
			(size 1.2 1.3)
			(layers "F.Cu" "F.Mask" "F.Paste")
			(roundrect_rratio 0.25)
			(net 1105 "/DCDC/20V_OUT")
			(pintype "passive")
		)
	)
	(footprint "antmicro-footprints:C_0402_1005Metric"
		(layer "F.Cu")
		(at 213.6 127.2 180)
		(descr "Capacitor SMD 0402")
		(tags "capacitor SMD 0402")
		(property "Reference" "C88"
			(at 1.1 0.5 180)
			(layer "F.SilkS")
			(effects
				(font
					(size 0.7 0.7)
					(thickness 0.15)
				)
				(justify left bottom)
			)
		)
		(property "Value" "C_100n_0402"
			(at -1.022927 2.155213 180)
			(layer "F.Fab")
			(effects
				(font
					(size 0.7 0.7)
					(thickness 0.15)
				)
				(justify left bottom)
			)
		)
		(property "Datasheet" "https://www.murata.com/products/productdetail?partno=GRM155R61H104KE14%23"
			(at 0 0 180)
			(layer "F.Fab")
			(hide yes)
			(effects
				(font
					(size 1.27 1.27)
					(thickness 0.15)
				)
			)
		)
		(property "Description" "SMD Multilayer Ceramic Capacitor, 0.1 µF, 50 V, 0402 [1005 Metric], ± 10%, X5R, GRM Series"
			(at 0 0 180)
			(layer "F.Fab")
			(hide yes)
			(effects
				(font
					(size 1.27 1.27)
					(thickness 0.15)
				)
			)
		)
		(property "MPN" "GRM155R61H104KE14D"
			(at 0 0 180)
			(unlocked yes)
			(layer "F.Fab")
			(hide yes)
			(effects
				(font
					(size 1 1)
					(thickness 0.15)
				)
			)
		)
		(property "Val" "100n"
			(at 0 0 180)
			(unlocked yes)
			(layer "F.Fab")
			(hide yes)
			(effects
				(font
					(size 1 1)
					(thickness 0.15)
				)
			)
		)
		(property "Voltage" "50V"
			(at 0 0 180)
			(unlocked yes)
			(layer "F.Fab")
			(hide yes)
			(effects
				(font
					(size 1 1)
					(thickness 0.15)
				)
			)
		)
		(property "Dielectric" "X5R"
			(at 0 0 180)
			(unlocked yes)
			(layer "F.Fab")
			(hide yes)
			(effects
				(font
					(size 1 1)
					(thickness 0.15)
				)
			)
		)
		(property "Manufacturer" "Murata"
			(at 0 0 180)
			(unlocked yes)
			(layer "F.Fab")
			(hide yes)
			(effects
				(font
					(size 1 1)
					(thickness 0.15)
				)
			)
		)
		(property "License" "Apache-2.0"
			(at 0 0 180)
			(unlocked yes)
			(layer "F.Fab")
			(hide yes)
			(effects
				(font
					(size 1 1)
					(thickness 0.15)
				)
			)
		)
		(property "Author" "Antmicro"
			(at 0 0 180)
			(unlocked yes)
			(layer "F.Fab")
			(hide yes)
			(effects
				(font
					(size 1 1)
					(thickness 0.15)
				)
			)
		)
		(sheetname "/USB Hub/")
		(sheetfile "usb_hub.kicad_sch")
		(attr smd)
		(fp_poly
			(pts
				(xy -0.925 -0.47) (xy 0.925 -0.47) (xy 0.925 0.47) (xy -0.925 0.47)
			)
			(stroke
				(width 0.05)
				(type default)
			)
			(fill no)
			(layer "F.CrtYd")
		)
		(fp_line
			(start 0.504 0.248)
			(end -0.494 0.248)
			(stroke
				(width 0.15)
				(type solid)
			)
			(layer "F.Fab")
		)
		(fp_line
			(start 0.504 -0.25)
			(end 0.504 0.248)
			(stroke
				(width 0.15)
				(type solid)
			)
			(layer "F.Fab")
		)
		(fp_line
			(start -0.494 0.248)
			(end -0.494 -0.25)
			(stroke
				(width 0.15)
				(type solid)
			)
			(layer "F.Fab")
		)
		(fp_line
			(start -0.494 -0.25)
			(end 0.504 -0.25)
			(stroke
				(width 0.15)
				(type solid)
			)
			(layer "F.Fab")
		)
		(fp_text user "License: Apache-2.0"
			(at -0.939 5.799 180)
			(layer "F.Fab")
			(effects
				(font
					(size 0.7 0.7)
					(thickness 0.15)
				)
				(justify left bottom)
			)
		)
		(fp_text user "${REFERENCE}"
			(at -0.939 4.599 180)
			(layer "F.Fab")
			(effects
				(font
					(size 0.7 0.7)
					(thickness 0.15)
				)
				(justify left bottom)
			)
		)
		(fp_text user "Author: Antmicro"
			(at -0.939 3.399 180)
			(layer "F.Fab")
			(effects
				(font
					(size 0.7 0.7)
					(thickness 0.15)
				)
				(justify left bottom)
			)
		)
		(pad "1" smd roundrect
			(at -0.48 0 180)
			(size 0.59 0.64)
			(layers "F.Cu" "F.Mask" "F.Paste")
			(roundrect_rratio 0.25)
			(net 1 "GND")
			(pintype "passive")
		)
		(pad "2" smd roundrect
			(at 0.48 0 180)
			(size 0.59 0.64)
			(layers "F.Cu" "F.Mask" "F.Paste")
			(roundrect_rratio 0.25)
			(net 282 "+1V15")
			(pintype "passive")
		)
	)
	(footprint "antmicro-footprints:C_0603_1608Metric_EIA"
		(layer "F.Cu")
		(at 192.47 125.5 180)
		(descr "Capacitor SMD 0603, IPC-7351 Density Level A")
		(tags "Capacitor 0603")
		(property "Reference" "C224"
			(at -1.42757 -7.9 0)
			(layer "F.SilkS")
			(effects
				(font
					(size 0.7 0.7)
					(thickness 0.15)
				)
				(justify right top)
			)
		)
		(property "Value" "C_22u_16V_0603"
			(at -1.42757 1.770288 0)
			(layer "F.Fab")
			(effects
				(font
					(size 0.7 0.7)
					(thickness 0.15)
				)
				(justify right top)
			)
		)
		(property "Datasheet" "https://product.samsungsem.com/mlcc/CL10A226MO7JZN.do"
			(at 0 0 0)
			(layer "F.Fab")
			(hide yes)
			(effects
				(font
					(size 1.27 1.27)
					(thickness 0.15)
				)
			)
		)
		(property "Description" "SMD Multilayer Ceramic Capacitor"
			(at 0 0 0)
			(layer "F.Fab")
			(hide yes)
			(effects
				(font
					(size 1.27 1.27)
					(thickness 0.15)
				)
			)
		)
		(property "Val" "22u"
			(at 0 0 0)
			(unlocked yes)
			(layer "F.Fab")
			(hide yes)
			(effects
				(font
					(size 1 1)
					(thickness 0.15)
				)
			)
		)
		(property "MPN" "CL10A226MO7JZNC"
			(at 0 0 0)
			(unlocked yes)
			(layer "F.Fab")
			(hide yes)
			(effects
				(font
					(size 1 1)
					(thickness 0.15)
				)
			)
		)
		(property "Manufacturer" "Samsung Electro-Mechanics"
			(at 0 0 0)
			(unlocked yes)
			(layer "F.Fab")
			(hide yes)
			(effects
				(font
					(size 1 1)
					(thickness 0.15)
				)
			)
		)
		(property "License" "Apache-2.0"
			(at 0 0 0)
			(unlocked yes)
			(layer "F.Fab")
			(hide yes)
			(effects
				(font
					(size 1 1)
					(thickness 0.15)
				)
			)
		)
		(property "Author" "Antmicro"
			(at 0 0 0)
			(unlocked yes)
			(layer "F.Fab")
			(hide yes)
			(effects
				(font
					(size 1 1)
					(thickness 0.15)
				)
			)
		)
		(property "Voltage" "16V"
			(at 0 0 0)
			(unlocked yes)
			(layer "F.Fab")
			(hide yes)
			(effects
				(font
					(size 1 1)
					(thickness 0.15)
				)
			)
		)
		(property "Dielectric" ""
			(at 0 0 0)
			(unlocked yes)
			(layer "F.Fab")
			(hide yes)
			(effects
				(font
					(size 1 1)
					(thickness 0.15)
				)
			)
		)
		(component_classes
			(class "DCDC_1V15")
		)
		(sheetname "/DCDC/")
		(sheetfile "dcdc.kicad_sch")
		(attr smd)
		(fp_line
			(start -0.15 0.55)
			(end 0.15 0.55)
			(stroke
				(width 0.15)
				(type solid)
			)
			(layer "F.SilkS")
		)
		(fp_line
			(start -0.15 -0.55)
			(end 0.15 -0.55)
			(stroke
				(width 0.15)
				(type solid)
			)
			(layer "F.SilkS")
		)
		(fp_rect
			(start -1.25 -0.65)
			(end 1.25 0.65)
			(stroke
				(width 0.05)
				(type solid)
			)
			(fill no)
			(layer "F.CrtYd")
		)
		(fp_rect
			(start -0.8 -0.45)
			(end 0.8 0.45)
			(stroke
				(width 0.15)
				(type solid)
			)
			(fill no)
			(layer "F.Fab")
		)
		(fp_text user "${REFERENCE}"
			(at -1.682 3.895 0)
			(layer "F.Fab")
			(effects
				(font
					(size 0.7 0.7)
					(thickness 0.15)
				)
				(justify right top)
			)
		)
		(fp_text user "Author: Antmicro"
			(at -1.682 4.894 0)
			(layer "F.Fab")
			(effects
				(font
					(size 0.7 0.7)
					(thickness 0.15)
				)
				(justify right top)
			)
		)
		(fp_text user "License: Apache-2.0"
			(at -1.682 5.895 0)
			(layer "F.Fab")
			(effects
				(font
					(size 0.7 0.7)
					(thickness 0.15)
				)
				(justify right top)
			)
		)
		(pad "1" smd roundrect
			(at -0.7 0 180)
			(size 0.8 1.1)
			(layers "F.Cu" "F.Mask" "F.Paste")
			(roundrect_rratio 0.2)
			(net 280 "/DCDC/1V15_OUT")
			(pintype "passive")
		)
		(pad "2" smd roundrect
			(at 0.7 0 180)
			(size 0.8 1.1)
			(layers "F.Cu" "F.Mask" "F.Paste")
			(roundrect_rratio 0.2)
			(net 1 "GND")
			(pintype "passive")
		)
	)
	(footprint "antmicro-footprints:R_0402_1005Metric"
		(layer "F.Cu")
		(at 182.933525 123.947019)
		(descr "Resistor SMD 0402")
		(tags "resistor SMD 0402")
		(property "Reference" "R55"
			(at -0.333525 -1.347019 0)
			(layer "F.SilkS")
			(effects
				(font
					(size 0.7 0.7)
					(thickness 0.15)
				)
				(justify left bottom)
			)
		)
		(property "Value" "R_10k_0402"
			(at -1.011843 1.772047 0)
			(layer "F.Fab")
			(effects
				(font
					(size 0.7 0.7)
					(thickness 0.15)
				)
				(justify left bottom)
			)
		)
		(property "Datasheet" "https://www.bourns.com/docs/product-datasheets/cr.pdf"
			(at 0 0 0)
			(layer "F.Fab")
			(hide yes)
			(effects
				(font
					(size 1.27 1.27)
					(thickness 0.15)
				)
			)
		)
		(property "Description" "SMD Chip Resistor, 10 kohm, ± 1%, 62.5 mW, 0402 [1005 Metric], Thick Film, General Purpose"
			(at 0 0 0)
			(layer "F.Fab")
			(hide yes)
			(effects
				(font
					(size 1.27 1.27)
					(thickness 0.15)
				)
			)
		)
		(property "MPN" "CR0402-FX-1002GLF"
			(at 0 0 0)
			(unlocked yes)
			(layer "F.Fab")
			(hide yes)
			(effects
				(font
					(size 1 1)
					(thickness 0.15)
				)
			)
		)
		(property "Manufacturer" "Bourns"
			(at 0 0 0)
			(unlocked yes)
			(layer "F.Fab")
			(hide yes)
			(effects
				(font
					(size 1 1)
					(thickness 0.15)
				)
			)
		)
		(property "License" "Apache-2.0"
			(at 0 0 0)
			(unlocked yes)
			(layer "F.Fab")
			(hide yes)
			(effects
				(font
					(size 1 1)
					(thickness 0.15)
				)
			)
		)
		(property "Author" "Antmicro"
			(at 0 0 0)
			(unlocked yes)
			(layer "F.Fab")
			(hide yes)
			(effects
				(font
					(size 1 1)
					(thickness 0.15)
				)
			)
		)
		(property "Val" "10k"
			(at 0 0 0)
			(unlocked yes)
			(layer "F.Fab")
			(hide yes)
			(effects
				(font
					(size 1 1)
					(thickness 0.15)
				)
			)
		)
		(property "Tolerance" "1%"
			(at 0 0 0)
			(unlocked yes)
			(layer "F.Fab")
			(hide yes)
			(effects
				(font
					(size 1 1)
					(thickness 0.15)
				)
			)
		)
		(sheetname "/DCDC/")
		(sheetfile "dcdc.kicad_sch")
		(attr smd)
		(fp_rect
			(start -0.925 -0.47)
			(end 0.925 0.47)
			(stroke
				(width 0.05)
				(type default)
			)
			(fill no)
			(layer "F.CrtYd")
		)
		(fp_rect
			(start -0.5 -0.25)
			(end 0.5 0.25)
			(stroke
				(width 0.15)
				(type solid)
			)
			(fill no)
			(layer "F.Fab")
		)
		(fp_text user "License: Apache-2.0"
			(at -0.95 5.169 0)
			(layer "F.Fab")
			(effects
				(font
					(size 0.7 0.7)
					(thickness 0.15)
				)
				(justify left bottom)
			)
		)
		(fp_text user "${REFERENCE}"
			(at -0.95 3.168 0)
			(layer "F.Fab")
			(effects
				(font
					(size 0.7 0.7)
					(thickness 0.15)
				)
				(justify left bottom)
			)
		)
		(fp_text user "Author: Antmicro"
			(at -0.95 4.169 0)
			(layer "F.Fab")
			(effects
				(font
					(size 0.7 0.7)
					(thickness 0.15)
				)
				(justify left bottom)
			)
		)
		(pad "1" smd roundrect
			(at -0.48 0)
			(size 0.59 0.64)
			(layers "F.Cu" "F.Mask" "F.Paste")
			(roundrect_rratio 0.25)
			(net 1 "GND")
			(pintype "passive")
		)
		(pad "2" smd roundrect
			(at 0.48 0)
			(size 0.59 0.64)
			(layers "F.Cu" "F.Mask" "F.Paste")
			(roundrect_rratio 0.25)
			(net 1218 "/DCDC/3V3_FB")
			(pintype "passive")
		)
	)
	(footprint "antmicro-footprints:R_0402_1005Metric"
		(layer "F.Cu")
		(at 130.549999 62.97 180)
		(descr "Resistor SMD 0402")
		(tags "resistor SMD 0402")
		(property "Reference" "R312"
			(at 0.929999 -2.36 0)
			(layer "F.SilkS")
			(effects
				(font
					(size 0.7 0.7)
					(thickness 0.15)
				)
				(justify left bottom)
			)
		)
		(property "Value" "R_73k2_0402"
			(at -1.011843 1.772046 0)
			(layer "F.Fab")
			(effects
				(font
					(size 0.7 0.7)
					(thickness 0.15)
				)
				(justify right top)
			)
		)
		(property "Datasheet" "https://www.bourns.com/docs/product-datasheets/cr.pdf"
			(at 0 0 0)
			(layer "F.Fab")
			(hide yes)
			(effects
				(font
					(size 1.27 1.27)
					(thickness 0.15)
				)
			)
		)
		(property "Description" "SMD Chip Resistor"
			(at 0 0 0)
			(layer "F.Fab")
			(hide yes)
			(effects
				(font
					(size 1.27 1.27)
					(thickness 0.15)
				)
			)
		)
		(property "MPN" "CR0402-FX-7322GLF"
			(at 0 0 180)
			(unlocked yes)
			(layer "F.Fab")
			(hide yes)
			(effects
				(font
					(size 1 1)
					(thickness 0.15)
				)
			)
		)
		(property "Manufacturer" "Bourns"
			(at 0 0 180)
			(unlocked yes)
			(layer "F.Fab")
			(hide yes)
			(effects
				(font
					(size 1 1)
					(thickness 0.15)
				)
			)
		)
		(property "License" "Apache-2.0"
			(at 0 0 180)
			(unlocked yes)
			(layer "F.Fab")
			(hide yes)
			(effects
				(font
					(size 1 1)
					(thickness 0.15)
				)
			)
		)
		(property "Author" "Antmicro"
			(at 0 0 180)
			(unlocked yes)
			(layer "F.Fab")
			(hide yes)
			(effects
				(font
					(size 1 1)
					(thickness 0.15)
				)
			)
		)
		(property "Val" "73k2"
			(at 0 0 180)
			(unlocked yes)
			(layer "F.Fab")
			(hide yes)
			(effects
				(font
					(size 1 1)
					(thickness 0.15)
				)
			)
		)
		(property "Tolerance" "1%"
			(at 0 0 180)
			(unlocked yes)
			(layer "F.Fab")
			(hide yes)
			(effects
				(font
					(size 1 1)
					(thickness 0.15)
				)
			)
		)
		(sheetname "/DCDC/")
		(sheetfile "dcdc.kicad_sch")
		(attr smd)
		(fp_poly
			(pts
				(xy -0.925 -0.47) (xy 0.925 -0.47) (xy 0.925 0.47) (xy -0.925 0.47)
			)
			(stroke
				(width 0.05)
				(type default)
			)
			(fill no)
			(layer "F.CrtYd")
		)
		(fp_poly
			(pts
				(xy -0.5 -0.25) (xy 0.5 -0.25) (xy 0.5 0.25) (xy -0.5 0.25)
			)
			(stroke
				(width 0.15)
				(type solid)
			)
			(fill no)
			(layer "F.Fab")
		)
		(fp_text user "License: Apache-2.0"
			(at -0.949999 5.169 0)
			(layer "F.Fab")
			(effects
				(font
					(size 0.7 0.7)
					(thickness 0.15)
				)
				(justify right top)
			)
		)
		(fp_text user "Author: Antmicro"
			(at -0.95 4.169 0)
			(layer "F.Fab")
			(effects
				(font
					(size 0.7 0.7)
					(thickness 0.15)
				)
				(justify right top)
			)
		)
		(fp_text user "${REFERENCE}"
			(at -0.95 3.168 0)
			(layer "F.Fab")
			(effects
				(font
					(size 0.7 0.7)
					(thickness 0.15)
				)
				(justify right top)
			)
		)
		(pad "1" smd roundrect
			(at -0.48 0 180)
			(size 0.59 0.64)
			(layers "F.Cu" "F.Mask" "F.Paste")
			(roundrect_rratio 0.25)
			(net 1308 "/DCDC/5V_{AON}_FB")
			(pintype "passive")
		)
		(pad "2" smd roundrect
			(at 0.48 0 180)
			(size 0.59 0.64)
			(layers "F.Cu" "F.Mask" "F.Paste")
			(roundrect_rratio 0.25)
			(net 1278 "/DCDC/5V_{AON}_OUT")
			(pintype "passive")
		)
	)
	(footprint "antmicro-footprints:USON-10_2.5x1mm_P0.5mm"
		(layer "F.Cu")
		(at 221.402132 86.512 180)
		(descr "USON-10 2.5x1mm_ Pitch 0.5mm")
		(tags "USON-10 2.5x1mm Pitch 0.5mm")
		(property "Reference" "U37"
			(at -1.14 1.15 90)
			(layer "F.SilkS")
			(effects
				(font
					(size 0.7 0.7)
					(thickness 0.15)
				)
				(justify right top)
			)
		)
		(property "Value" "TPD4E05U06QDQARQ1"
			(at 0.018 2.499 0)
			(layer "F.Fab")
			(effects
				(font
					(size 0.7 0.7)
					(thickness 0.15)
				)
				(justify right top)
			)
		)
		(property "Datasheet" "https://www.ti.com/lit/ds/symlink/tpd4e05u06-q1.pdf?HQS=dis-mous-null-mousermode-dsf-pf-null-wwe&ts=1663591265741&ref_url=https%253A%252F%252Fwww.mouser.com%252F"
			(at 0 0 0)
			(layer "F.Fab")
			(hide yes)
			(effects
				(font
					(size 1.27 1.27)
					(thickness 0.15)
				)
			)
		)
		(property "Description" "TVS diode array, 12 kV, USON-10, 5.5 V, 0.5 pF"
			(at 0 0 0)
			(layer "F.Fab")
			(hide yes)
			(effects
				(font
					(size 1.27 1.27)
					(thickness 0.15)
				)
			)
		)
		(property "Manufacturer" "Texas Instruments"
			(at 0 0 180)
			(unlocked yes)
			(layer "F.Fab")
			(hide yes)
			(effects
				(font
					(size 1 1)
					(thickness 0.15)
				)
			)
		)
		(property "MPN" "TPD4E05U06QDQARQ1"
			(at 0 0 180)
			(unlocked yes)
			(layer "F.Fab")
			(hide yes)
			(effects
				(font
					(size 1 1)
					(thickness 0.15)
				)
			)
		)
		(property "Author" "Antmicro"
			(at 0 0 180)
			(unlocked yes)
			(layer "F.Fab")
			(hide yes)
			(effects
				(font
					(size 1 1)
					(thickness 0.15)
				)
			)
		)
		(property "License" "Apache-2.0"
			(at 0 0 180)
			(unlocked yes)
			(layer "F.Fab")
			(hide yes)
			(effects
				(font
					(size 1 1)
					(thickness 0.15)
				)
			)
		)
		(sheetname "/USB DP Alt mode/")
		(sheetfile "usb_dp.kicad_sch")
		(attr smd)
		(fp_line
			(start 0.498 1.398)
			(end -0.5 1.398)
			(stroke
				(width 0.15)
				(type solid)
			)
			(layer "F.SilkS")
		)
		(fp_line
			(start 0.498 -1.401)
			(end -0.5 -1.401)
			(stroke
				(width 0.15)
				(type solid)
			)
			(layer "F.SilkS")
		)
		(fp_circle
			(center -0.68 -1.27)
			(end -0.63 -1.27)
			(stroke
				(width 0.15)
				(type solid)
			)
			(fill yes)
			(layer "F.SilkS")
		)
		(fp_rect
			(start -0.8 -1.5)
			(end 0.8 1.499)
			(stroke
				(width 0.05)
				(type solid)
			)
			(fill no)
			(layer "F.CrtYd")
		)
		(fp_line
			(start 0.498 -1.25)
			(end 0.498 1.249)
			(stroke
				(width 0.15)
				(type solid)
			)
			(layer "F.Fab")
		)
		(fp_line
			(start 0.498 -1.25)
			(end -0.25 -1.25)
			(stroke
				(width 0.15)
				(type solid)
			)
			(layer "F.Fab")
		)
		(fp_line
			(start -0.25 -1.25)
			(end -0.5 -1)
			(stroke
				(width 0.15)
				(type solid)
			)
			(layer "F.Fab")
		)
		(fp_line
			(start -0.5 1.249)
			(end 0.498 1.249)
			(stroke
				(width 0.15)
				(type solid)
			)
			(layer "F.Fab")
		)
		(fp_line
			(start -0.5 -1)
			(end -0.5 1.249)
			(stroke
				(width 0.15)
				(type solid)
			)
			(layer "F.Fab")
		)
		(fp_text user "Author: Antmicro"
			(at -0.802 5.7 0)
			(layer "F.Fab")
			(effects
				(font
					(size 0.7 0.7)
					(thickness 0.15)
				)
				(justify right top)
			)
		)
		(fp_text user "License: Apache-2.0"
			(at -0.802 6.9 0)
			(layer "F.Fab")
			(effects
				(font
					(size 0.7 0.7)
					(thickness 0.15)
				)
				(justify right top)
			)
		)
		(fp_text user "${REFERENCE}"
			(at -0.802 4.498 0)
			(layer "F.Fab")
			(effects
				(font
					(size 0.7 0.7)
					(thickness 0.15)
				)
				(justify right top)
			)
		)
		(pad "1" smd roundrect
			(at -0.387 -1 90)
			(size 0.25 0.55)
			(layers "F.Cu" "F.Mask" "F.Paste")
			(roundrect_rratio 0.25)
			(net 374 "/USB DP Alt mode/USBC1_CONN_TX2_N")
			(pintype "passive")
		)
		(pad "2" smd roundrect
			(at -0.387 -0.5 90)
			(size 0.25 0.55)
			(layers "F.Cu" "F.Mask" "F.Paste")
			(roundrect_rratio 0.25)
			(net 347 "/USB DP Alt mode/USBC1_CONN_TX2_P")
			(pintype "passive")
		)
		(pad "3" smd roundrect
			(at -0.387 0 90)
			(size 0.4 0.55)
			(layers "F.Cu" "F.Mask" "F.Paste")
			(roundrect_rratio 0.25)
			(net 1 "GND")
			(pintype "power_in")
		)
		(pad "4" smd roundrect
			(at -0.387 0.498 90)
			(size 0.25 0.55)
			(layers "F.Cu" "F.Mask" "F.Paste")
			(roundrect_rratio 0.25)
			(net 820 "/USB DP Alt mode/USBC1_RX2_N")
			(pintype "passive")
		)
		(pad "5" smd roundrect
			(at -0.387 0.998 90)
			(size 0.25 0.55)
			(layers "F.Cu" "F.Mask" "F.Paste")
			(roundrect_rratio 0.25)
			(net 818 "/USB DP Alt mode/USBC1_RX2_P")
			(pintype "passive")
		)
		(pad "6" smd roundrect
			(at 0.385 0.998 90)
			(size 0.25 0.55)
			(layers "F.Cu" "F.Mask" "F.Paste")
			(roundrect_rratio 0.25)
			(net 818 "/USB DP Alt mode/USBC1_RX2_P")
			(pintype "passive")
		)
		(pad "7" smd roundrect
			(at 0.385 0.498 90)
			(size 0.25 0.55)
			(layers "F.Cu" "F.Mask" "F.Paste")
			(roundrect_rratio 0.25)
			(net 820 "/USB DP Alt mode/USBC1_RX2_N")
			(pintype "passive")
		)
		(pad "8" smd roundrect
			(at 0.385 0 90)
			(size 0.4 0.55)
			(layers "F.Cu" "F.Mask" "F.Paste")
			(roundrect_rratio 0.25)
			(net 1 "GND")
			(pintype "passive")
		)
		(pad "9" smd roundrect
			(at 0.385 -0.5 90)
			(size 0.25 0.55)
			(layers "F.Cu" "F.Mask" "F.Paste")
			(roundrect_rratio 0.25)
			(net 347 "/USB DP Alt mode/USBC1_CONN_TX2_P")
			(pintype "passive")
		)
		(pad "10" smd roundrect
			(at 0.385 -1 90)
			(size 0.25 0.55)
			(layers "F.Cu" "F.Mask" "F.Paste")
			(roundrect_rratio 0.25)
			(net 374 "/USB DP Alt mode/USBC1_CONN_TX2_N")
			(pintype "passive")
		)
	)
	(footprint "antmicro-footprints:XDFN-2_1x0.60mm"
		(layer "F.Cu")
		(at 187.248 55.497999 -90)
		(property "Reference" "D37"
			(at 0.402001 0.548 90)
			(layer "F.SilkS")
			(effects
				(font
					(size 0.7 0.7)
					(thickness 0.15)
				)
				(justify left bottom)
			)
		)
		(property "Value" "TPD1E0B04_XDFN-2"
			(at 0 1.5 90)
			(layer "F.Fab")
			(effects
				(font
					(size 0.7 0.7)
					(thickness 0.15)
				)
				(justify right top)
			)
		)
		(property "Datasheet" "https://www.ti.com/general/docs/suppproductinfo.tsp?distId=26&gotoUrl=https://www.ti.com/lit/gpn/tpd1e0b04"
			(at 0 0 90)
			(layer "F.Fab")
			(hide yes)
			(effects
				(font
					(size 1.27 1.27)
					(thickness 0.15)
				)
			)
		)
		(property "Description" "Bidirectional TVS, 8 kV,  XDFN-2, 3.6 V, 0.18 pF"
			(at 0 0 90)
			(layer "F.Fab")
			(hide yes)
			(effects
				(font
					(size 1.27 1.27)
					(thickness 0.15)
				)
			)
		)
		(property "MPN" "TPD1E0B04DPYR"
			(at 0 0 90)
			(layer "F.Fab")
			(hide yes)
			(effects
				(font
					(size 1.27 1.27)
					(thickness 0.15)
				)
			)
		)
		(property "Manufacturer" "Texas Instruments"
			(at 0 0 90)
			(layer "F.Fab")
			(hide yes)
			(effects
				(font
					(size 1.27 1.27)
					(thickness 0.15)
				)
			)
		)
		(property "Author" "Antmicro"
			(at 0 0 270)
			(unlocked yes)
			(layer "F.Fab")
			(hide yes)
			(effects
				(font
					(size 1 1)
					(thickness 0.15)
				)
			)
		)
		(property "License" "Apache-2.0"
			(at 0 0 270)
			(unlocked yes)
			(layer "F.Fab")
			(hide yes)
			(effects
				(font
					(size 1 1)
					(thickness 0.15)
				)
			)
		)
		(sheetname "/Peripherals/")
		(sheetfile "peripherals.kicad_sch")
		(attr smd)
		(fp_poly
			(pts
				(xy -0.725 -0.475) (xy 0.725 -0.475) (xy 0.725 0.475) (xy -0.725 0.475)
			)
			(stroke
				(width 0.05)
				(type solid)
			)
			(fill no)
			(layer "F.CrtYd")
		)
		(fp_poly
			(pts
				(xy -0.55 -0.35) (xy 0.55 -0.35) (xy 0.55 0.35) (xy -0.55 0.35)
			)
			(stroke
				(width 0.15)
				(type solid)
			)
			(fill no)
			(layer "F.Fab")
		)
		(fp_text user "Author: Antmicro"
			(at -0.8 4.4 90)
			(layer "F.Fab")
			(effects
				(font
					(size 0.7 0.7)
					(thickness 0.15)
				)
				(justify right top)
			)
		)
		(fp_text user "${REFERENCE}"
			(at -0.8 3.2 90)
			(layer "F.Fab")
			(effects
				(font
					(size 0.7 0.7)
					(thickness 0.15)
				)
				(justify right top)
			)
		)
		(fp_text user "License: Apache-2.0"
			(at -0.799999 5.6 90)
			(layer "F.Fab")
			(effects
				(font
					(size 0.7 0.7)
					(thickness 0.15)
				)
				(justify right top)
			)
		)
		(pad "1" smd roundrect
			(at -0.350999 0 270)
			(size 0.3 0.5)
			(layers "F.Cu" "F.Mask" "F.Paste")
			(roundrect_rratio 0.25)
			(net 1 "GND")
			(pinfunction "C")
			(pintype "passive")
		)
		(pad "2" smd roundrect
			(at 0.349 0 270)
			(size 0.3 0.5)
			(layers "F.Cu" "F.Mask" "F.Paste")
			(roundrect_rratio 0.25)
			(net 448 "/Expansion connector/GPIO.USER_BTN0")
			(pinfunction "A")
			(pintype "passive")
		)
	)
	(footprint "antmicro-footprints:C_0402_1005Metric"
		(layer "F.Cu")
		(at 89.1 102.6 180)
		(descr "Capacitor SMD 0402")
		(tags "capacitor SMD 0402")
		(property "Reference" "C353"
			(at 3.8 -0.4 180)
			(layer "F.SilkS")
			(effects
				(font
					(size 0.7 0.7)
					(thickness 0.15)
				)
				(justify left bottom)
			)
		)
		(property "Value" "C_100n_0402"
			(at -1.022927 2.155213 180)
			(layer "F.Fab")
			(effects
				(font
					(size 0.7 0.7)
					(thickness 0.15)
				)
				(justify left bottom)
			)
		)
		(property "Datasheet" "https://www.murata.com/products/productdetail?partno=GRM155R61H104KE14%23"
			(at 0 0 180)
			(layer "F.Fab")
			(hide yes)
			(effects
				(font
					(size 1.27 1.27)
					(thickness 0.15)
				)
			)
		)
		(property "Description" "SMD Multilayer Ceramic Capacitor, 0.1 µF, 50 V, 0402 [1005 Metric], ± 10%, X5R, GRM Series"
			(at 0 0 180)
			(layer "F.Fab")
			(hide yes)
			(effects
				(font
					(size 1.27 1.27)
					(thickness 0.15)
				)
			)
		)
		(property "Manufacturer" "Murata"
			(at 0 0 180)
			(unlocked yes)
			(layer "F.Fab")
			(hide yes)
			(effects
				(font
					(size 1 1)
					(thickness 0.15)
				)
			)
		)
		(property "MPN" "GRM155R61H104KE14D"
			(at 0 0 180)
			(unlocked yes)
			(layer "F.Fab")
			(hide yes)
			(effects
				(font
					(size 1 1)
					(thickness 0.15)
				)
			)
		)
		(property "Val" "100n"
			(at 0 0 180)
			(unlocked yes)
			(layer "F.Fab")
			(hide yes)
			(effects
				(font
					(size 1 1)
					(thickness 0.15)
				)
			)
		)
		(property "License" "Apache-2.0"
			(at 0 0 180)
			(unlocked yes)
			(layer "F.Fab")
			(hide yes)
			(effects
				(font
					(size 1 1)
					(thickness 0.15)
				)
			)
		)
		(property "Author" "Antmicro"
			(at 0 0 180)
			(unlocked yes)
			(layer "F.Fab")
			(hide yes)
			(effects
				(font
					(size 1 1)
					(thickness 0.15)
				)
			)
		)
		(property "Voltage" "50V"
			(at 0 0 180)
			(unlocked yes)
			(layer "F.Fab")
			(hide yes)
			(effects
				(font
					(size 1 1)
					(thickness 0.15)
				)
			)
		)
		(property "Dielectric" "X5R"
			(at 0 0 180)
			(unlocked yes)
			(layer "F.Fab")
			(hide yes)
			(effects
				(font
					(size 1 1)
					(thickness 0.15)
				)
			)
		)
		(sheetname "/SoM_IO2/")
		(sheetfile "som_io2.kicad_sch")
		(attr smd)
		(fp_poly
			(pts
				(xy -0.925 -0.47) (xy 0.925 -0.47) (xy 0.925 0.47) (xy -0.925 0.47)
			)
			(stroke
				(width 0.05)
				(type default)
			)
			(fill no)
			(layer "F.CrtYd")
		)
		(fp_line
			(start 0.504 0.248)
			(end -0.494 0.248)
			(stroke
				(width 0.15)
				(type solid)
			)
			(layer "F.Fab")
		)
		(fp_line
			(start 0.504 -0.25)
			(end 0.504 0.248)
			(stroke
				(width 0.15)
				(type solid)
			)
			(layer "F.Fab")
		)
		(fp_line
			(start -0.494 0.248)
			(end -0.494 -0.25)
			(stroke
				(width 0.15)
				(type solid)
			)
			(layer "F.Fab")
		)
		(fp_line
			(start -0.494 -0.25)
			(end 0.504 -0.25)
			(stroke
				(width 0.15)
				(type solid)
			)
			(layer "F.Fab")
		)
		(fp_text user "License: Apache-2.0"
			(at -0.939 5.799 180)
			(layer "F.Fab")
			(effects
				(font
					(size 0.7 0.7)
					(thickness 0.15)
				)
				(justify left bottom)
			)
		)
		(fp_text user "${REFERENCE}"
			(at -0.939 4.599 180)
			(layer "F.Fab")
			(effects
				(font
					(size 0.7 0.7)
					(thickness 0.15)
				)
				(justify left bottom)
			)
		)
		(fp_text user "Author: Antmicro"
			(at -0.939 3.399 180)
			(layer "F.Fab")
			(effects
				(font
					(size 0.7 0.7)
					(thickness 0.15)
				)
				(justify left bottom)
			)
		)
		(pad "1" smd roundrect
			(at -0.48 0 180)
			(size 0.59 0.64)
			(layers "F.Cu" "F.Mask" "F.Paste")
			(roundrect_rratio 0.25)
			(net 1273 "/SoM_IO2/DP3.AUX_C-")
			(pintype "passive")
		)
		(pad "2" smd roundrect
			(at 0.48 0 180)
			(size 0.59 0.64)
			(layers "F.Cu" "F.Mask" "F.Paste")
			(roundrect_rratio 0.25)
			(net 657 "/Expansion connector/DP3.AUX-")
			(pintype "passive")
		)
	)
	(footprint "antmicro-footprints:L_WE-MAPI-4020"
		(layer "F.Cu")
		(at 146.814391 131.81)
		(property "Reference" "L7"
			(at 3.385609 0.59 270)
			(layer "F.SilkS")
			(effects
				(font
					(size 0.7 0.7)
					(thickness 0.15)
				)
				(justify left bottom)
			)
		)
		(property "Value" "L_1u8_6.8A_WE-MAPI-4020"
			(at -2.4 3.4 180)
			(layer "F.Fab")
			(effects
				(font
					(size 0.7 0.7)
					(thickness 0.15)
				)
				(justify left bottom)
			)
		)
		(property "Datasheet" "https://www.we-online.com/components/products/datasheet/74438356018.pdf"
			(at 0 0 0)
			(layer "F.Fab")
			(hide yes)
			(effects
				(font
					(size 1.27 1.27)
					(thickness 0.15)
				)
			)
		)
		(property "Description" "Power Inductors - SMD WE-MAPI 1.8uH 4.6A DCR=30mOhms AEC-Q200"
			(at 0 0 0)
			(layer "F.Fab")
			(hide yes)
			(effects
				(font
					(size 1.27 1.27)
					(thickness 0.15)
				)
			)
		)
		(property "Val" "1u8/6.8A"
			(at 0 0 0)
			(unlocked yes)
			(layer "F.Fab")
			(hide yes)
			(effects
				(font
					(size 1 1)
					(thickness 0.15)
				)
			)
		)
		(property "Manufacturer" "Würth Elektronik"
			(at 0 0 0)
			(unlocked yes)
			(layer "F.Fab")
			(hide yes)
			(effects
				(font
					(size 1 1)
					(thickness 0.15)
				)
			)
		)
		(property "MPN" "74438356018"
			(at 0 0 0)
			(unlocked yes)
			(layer "F.Fab")
			(hide yes)
			(effects
				(font
					(size 1 1)
					(thickness 0.15)
				)
			)
		)
		(property "ISat" "6.5 A"
			(at 0 0 0)
			(unlocked yes)
			(layer "F.Fab")
			(hide yes)
			(effects
				(font
					(size 1 1)
					(thickness 0.15)
				)
			)
		)
		(property "IMax" "6.8 A"
			(at 0 0 0)
			(unlocked yes)
			(layer "F.Fab")
			(hide yes)
			(effects
				(font
					(size 1 1)
					(thickness 0.15)
				)
			)
		)
		(property "Size" "4.1x4.1mm"
			(at 0 0 0)
			(unlocked yes)
			(layer "F.Fab")
			(hide yes)
			(effects
				(font
					(size 1 1)
					(thickness 0.15)
				)
			)
		)
		(property "Author" "Antmicro"
			(at 0 0 0)
			(unlocked yes)
			(layer "F.Fab")
			(hide yes)
			(effects
				(font
					(size 1 1)
					(thickness 0.15)
				)
			)
		)
		(property "License" "Apache-2.0"
			(at 0 0 0)
			(unlocked yes)
			(layer "F.Fab")
			(hide yes)
			(effects
				(font
					(size 1 1)
					(thickness 0.15)
				)
			)
		)
		(component_classes
			(class "DCDC_1V8")
		)
		(sheetname "/DCDC/")
		(sheetfile "dcdc.kicad_sch")
		(attr smd)
		(fp_rect
			(start -2.2 -2.2)
			(end 2.2 2.2)
			(stroke
				(width 0.15)
				(type solid)
			)
			(fill no)
			(layer "F.SilkS")
		)
		(fp_rect
			(start -2.3 -2.3)
			(end 2.3 2.3)
			(stroke
				(width 0.05)
				(type solid)
			)
			(fill no)
			(layer "F.CrtYd")
		)
		(fp_rect
			(start -2.05 -2.05)
			(end 2.05 2.05)
			(stroke
				(width 0.15)
				(type solid)
			)
			(fill no)
			(layer "F.Fab")
		)
		(fp_text user "Author: Antmicro"
			(at -2.4 6.6 0)
			(layer "F.Fab")
			(effects
				(font
					(size 0.7 0.7)
					(thickness 0.15)
				)
				(justify left bottom)
			)
		)
		(fp_text user "License: Apache-2.0"
			(at -2.4 5.4 0)
			(layer "F.Fab")
			(effects
				(font
					(size 0.7 0.7)
					(thickness 0.15)
				)
				(justify left bottom)
			)
		)
		(fp_text user "${REFERENCE}"
			(at -2.4 7.8 0)
			(layer "F.Fab")
			(effects
				(font
					(size 0.7 0.7)
					(thickness 0.15)
				)
				(justify left bottom)
			)
		)
		(pad "1" smd roundrect
			(at -1.185 0 90)
			(size 3.7 1)
			(layers "F.Cu" "F.Mask" "F.Paste")
			(roundrect_rratio 0.1)
			(net 1185 "/DCDC/1V8_SW")
			(pintype "passive")
		)
		(pad "2" smd roundrect
			(at 1.185 0 90)
			(size 3.7 1)
			(layers "F.Cu" "F.Mask" "F.Paste")
			(roundrect_rratio 0.1)
			(net 17 "/DCDC/1V8_OUT")
			(pintype "passive")
		)
	)
	(footprint "antmicro-footprints:C_0402_1005Metric"
		(layer "F.Cu")
		(at 208 76.2 90)
		(descr "Capacitor SMD 0402")
		(tags "capacitor SMD 0402")
		(property "Reference" "C146"
			(at 0.9 0.4 90)
			(layer "F.SilkS")
			(effects
				(font
					(size 0.7 0.7)
					(thickness 0.15)
				)
				(justify left bottom)
			)
		)
		(property "Value" "C_4u7_25V_0402"
			(at -1.022927 2.155213 90)
			(layer "F.Fab")
			(effects
				(font
					(size 0.7 0.7)
					(thickness 0.15)
				)
				(justify left bottom)
			)
		)
		(property "Datasheet" "https://www.murata.com/products/productdetail?partno=GRM155C61E475ME15%23"
			(at 0 0 90)
			(layer "F.Fab")
			(hide yes)
			(effects
				(font
					(size 1.27 1.27)
					(thickness 0.15)
				)
			)
		)
		(property "Description" "SMD Multilayer Ceramic Capacitor"
			(at 0 0 90)
			(layer "F.Fab")
			(hide yes)
			(effects
				(font
					(size 1.27 1.27)
					(thickness 0.15)
				)
			)
		)
		(property "Manufacturer" "Murata"
			(at 0 0 90)
			(unlocked yes)
			(layer "F.Fab")
			(hide yes)
			(effects
				(font
					(size 1 1)
					(thickness 0.15)
				)
			)
		)
		(property "MPN" "GRM155C61E475ME15J"
			(at 0 0 90)
			(unlocked yes)
			(layer "F.Fab")
			(hide yes)
			(effects
				(font
					(size 1 1)
					(thickness 0.15)
				)
			)
		)
		(property "Val" "4u7"
			(at 0 0 90)
			(unlocked yes)
			(layer "F.Fab")
			(hide yes)
			(effects
				(font
					(size 1 1)
					(thickness 0.15)
				)
			)
		)
		(property "License" "Apache-2.0"
			(at 0 0 90)
			(unlocked yes)
			(layer "F.Fab")
			(hide yes)
			(effects
				(font
					(size 1 1)
					(thickness 0.15)
				)
			)
		)
		(property "Author" "Antmicro"
			(at 0 0 90)
			(unlocked yes)
			(layer "F.Fab")
			(hide yes)
			(effects
				(font
					(size 1 1)
					(thickness 0.15)
				)
			)
		)
		(property "Voltage" "25V"
			(at 0 0 90)
			(unlocked yes)
			(layer "F.Fab")
			(hide yes)
			(effects
				(font
					(size 1 1)
					(thickness 0.15)
				)
			)
		)
		(property "Dielectric" "X5S"
			(at 0 0 90)
			(unlocked yes)
			(layer "F.Fab")
			(hide yes)
			(effects
				(font
					(size 1 1)
					(thickness 0.15)
				)
			)
		)
		(sheetname "/USB Debug, PD/")
		(sheetfile "usb_debug_pd.kicad_sch")
		(attr smd)
		(fp_rect
			(start -0.925 -0.47)
			(end 0.925 0.47)
			(stroke
				(width 0.05)
				(type default)
			)
			(fill no)
			(layer "F.CrtYd")
		)
		(fp_line
			(start 0.504 -0.25)
			(end 0.504 0.248)
			(stroke
				(width 0.15)
				(type solid)
			)
			(layer "F.Fab")
		)
		(fp_line
			(start -0.494 -0.25)
			(end 0.504 -0.25)
			(stroke
				(width 0.15)
				(type solid)
			)
			(layer "F.Fab")
		)
		(fp_line
			(start 0.504 0.248)
			(end -0.494 0.248)
			(stroke
				(width 0.15)
				(type solid)
			)
			(layer "F.Fab")
		)
		(fp_line
			(start -0.494 0.248)
			(end -0.494 -0.25)
			(stroke
				(width 0.15)
				(type solid)
			)
			(layer "F.Fab")
		)
		(fp_text user "Author: Antmicro"
			(at -0.939 3.399 90)
			(layer "F.Fab")
			(effects
				(font
					(size 0.7 0.7)
					(thickness 0.15)
				)
				(justify left bottom)
			)
		)
		(fp_text user "${REFERENCE}"
			(at -0.939 4.599 90)
			(layer "F.Fab")
			(effects
				(font
					(size 0.7 0.7)
					(thickness 0.15)
				)
				(justify left bottom)
			)
		)
		(fp_text user "License: Apache-2.0"
			(at -0.939 5.799 90)
			(layer "F.Fab")
			(effects
				(font
					(size 0.7 0.7)
					(thickness 0.15)
				)
				(justify left bottom)
			)
		)
		(pad "1" smd roundrect
			(at -0.48 0 90)
			(size 0.59 0.64)
			(layers "F.Cu" "F.Mask" "F.Paste")
			(roundrect_rratio 0.25)
			(net 525 "/Power/USBPD2_HV")
			(pintype "passive")
		)
		(pad "2" smd roundrect
			(at 0.48 0 90)
			(size 0.59 0.64)
			(layers "F.Cu" "F.Mask" "F.Paste")
			(roundrect_rratio 0.25)
			(net 1 "GND")
			(pintype "passive")
		)
	)
	(footprint "antmicro-footprints:C_0402_1005Metric"
		(layer "F.Cu")
		(at 204.75 90.970856 180)
		(descr "Capacitor SMD 0402")
		(tags "capacitor SMD 0402")
		(property "Reference" "C319"
			(at 5.25 -0.429144 180)
			(layer "F.SilkS")
			(effects
				(font
					(size 0.7 0.7)
					(thickness 0.15)
				)
				(justify left bottom)
			)
		)
		(property "Value" "C_100n_0402"
			(at -1.022927 2.155213 180)
			(layer "F.Fab")
			(effects
				(font
					(size 0.7 0.7)
					(thickness 0.15)
				)
				(justify left bottom)
			)
		)
		(property "Datasheet" "https://www.murata.com/products/productdetail?partno=GRM155R61H104KE14%23"
			(at 0 0 180)
			(layer "F.Fab")
			(hide yes)
			(effects
				(font
					(size 1.27 1.27)
					(thickness 0.15)
				)
			)
		)
		(property "Description" "SMD Multilayer Ceramic Capacitor, 0.1 µF, 50 V, 0402 [1005 Metric], ± 10%, X5R, GRM Series"
			(at 0 0 180)
			(layer "F.Fab")
			(hide yes)
			(effects
				(font
					(size 1.27 1.27)
					(thickness 0.15)
				)
			)
		)
		(property "Manufacturer" "Murata"
			(at 0 0 180)
			(unlocked yes)
			(layer "F.Fab")
			(hide yes)
			(effects
				(font
					(size 1 1)
					(thickness 0.15)
				)
			)
		)
		(property "MPN" "GRM155R61H104KE14D"
			(at 0 0 180)
			(unlocked yes)
			(layer "F.Fab")
			(hide yes)
			(effects
				(font
					(size 1 1)
					(thickness 0.15)
				)
			)
		)
		(property "Val" "100n"
			(at 0 0 180)
			(unlocked yes)
			(layer "F.Fab")
			(hide yes)
			(effects
				(font
					(size 1 1)
					(thickness 0.15)
				)
			)
		)
		(property "License" "Apache-2.0"
			(at 0 0 180)
			(unlocked yes)
			(layer "F.Fab")
			(hide yes)
			(effects
				(font
					(size 1 1)
					(thickness 0.15)
				)
			)
		)
		(property "Author" "Antmicro"
			(at 0 0 180)
			(unlocked yes)
			(layer "F.Fab")
			(hide yes)
			(effects
				(font
					(size 1 1)
					(thickness 0.15)
				)
			)
		)
		(property "Voltage" "50V"
			(at 0 0 180)
			(unlocked yes)
			(layer "F.Fab")
			(hide yes)
			(effects
				(font
					(size 1 1)
					(thickness 0.15)
				)
			)
		)
		(property "Dielectric" "X5R"
			(at 0 0 180)
			(unlocked yes)
			(layer "F.Fab")
			(hide yes)
			(effects
				(font
					(size 1 1)
					(thickness 0.15)
				)
			)
		)
		(sheetname "/SoM_IO2/")
		(sheetfile "som_io2.kicad_sch")
		(attr smd)
		(fp_rect
			(start -0.925 -0.47)
			(end 0.925 0.47)
			(stroke
				(width 0.05)
				(type default)
			)
			(fill no)
			(layer "F.CrtYd")
		)
		(fp_line
			(start 0.504 0.248)
			(end -0.494 0.248)
			(stroke
				(width 0.15)
				(type solid)
			)
			(layer "F.Fab")
		)
		(fp_line
			(start 0.504 -0.25)
			(end 0.504 0.248)
			(stroke
				(width 0.15)
				(type solid)
			)
			(layer "F.Fab")
		)
		(fp_line
			(start -0.494 0.248)
			(end -0.494 -0.25)
			(stroke
				(width 0.15)
				(type solid)
			)
			(layer "F.Fab")
		)
		(fp_line
			(start -0.494 -0.25)
			(end 0.504 -0.25)
			(stroke
				(width 0.15)
				(type solid)
			)
			(layer "F.Fab")
		)
		(fp_text user "Author: Antmicro"
			(at -0.939 3.399 180)
			(layer "F.Fab")
			(effects
				(font
					(size 0.7 0.7)
					(thickness 0.15)
				)
				(justify left bottom)
			)
		)
		(fp_text user "${REFERENCE}"
			(at -0.939 4.599 180)
			(layer "F.Fab")
			(effects
				(font
					(size 0.7 0.7)
					(thickness 0.15)
				)
				(justify left bottom)
			)
		)
		(fp_text user "License: Apache-2.0"
			(at -0.939 5.799 180)
			(layer "F.Fab")
			(effects
				(font
					(size 0.7 0.7)
					(thickness 0.15)
				)
				(justify left bottom)
			)
		)
		(pad "1" smd roundrect
			(at -0.48 0 180)
			(size 0.59 0.64)
			(layers "F.Cu" "F.Mask" "F.Paste")
			(roundrect_rratio 0.25)
			(net 666 "/SoM_IO2/DP0.TX2-")
			(pintype "passive")
		)
		(pad "2" smd roundrect
			(at 0.48 0 180)
			(size 0.59 0.64)
			(layers "F.Cu" "F.Mask" "F.Paste")
			(roundrect_rratio 0.25)
			(net 617 "/SoM_IO2/DP0.TX2_C-")
			(pintype "passive")
		)
	)
	(footprint "antmicro-footprints:SW_KMR211NGLFS_SMD"
		(layer "F.Cu")
		(at 207 55.52 180)
		(property "Reference" "S6"
			(at 2 -2.1 180)
			(layer "F.SilkS")
			(hide yes)
			(effects
				(font
					(size 0.7 0.7)
					(thickness 0.15)
				)
				(justify right top)
			)
		)
		(property "Value" "SW_KMR211NGLFS_SMD"
			(at 0 2.8 0)
			(layer "F.Fab")
			(effects
				(font
					(size 0.7 0.7)
					(thickness 0.15)
				)
				(justify right top)
			)
		)
		(property "Datasheet" "http://www.farnell.com/datasheets/2631211.pdf"
			(at 0 0 0)
			(layer "F.Fab")
			(hide yes)
			(effects
				(font
					(size 1.27 1.27)
					(thickness 0.15)
				)
			)
		)
		(property "Description" "Tactile Switch, KMR 2 Series, Top Actuated, Surface Mount, Oval Button, 120 gf, 50mA at 32VDC"
			(at 0 0 0)
			(layer "F.Fab")
			(hide yes)
			(effects
				(font
					(size 1.27 1.27)
					(thickness 0.15)
				)
			)
		)
		(property "MPN" "KMR211NGLFS"
			(at 0 0 180)
			(unlocked yes)
			(layer "F.Fab")
			(hide yes)
			(effects
				(font
					(size 1 1)
					(thickness 0.15)
				)
			)
		)
		(property "Manufacturer" "C&K"
			(at 0 0 180)
			(unlocked yes)
			(layer "F.Fab")
			(hide yes)
			(effects
				(font
					(size 1 1)
					(thickness 0.15)
				)
			)
		)
		(property "Author" "Antmicro"
			(at 0 0 180)
			(unlocked yes)
			(layer "F.Fab")
			(hide yes)
			(effects
				(font
					(size 1 1)
					(thickness 0.15)
				)
			)
		)
		(property "License" "Apache-2.0"
			(at 0 0 180)
			(unlocked yes)
			(layer "F.Fab")
			(hide yes)
			(effects
				(font
					(size 1 1)
					(thickness 0.15)
				)
			)
		)
		(sheetname "/SoM_Power/")
		(sheetfile "som_power.kicad_sch")
		(attr smd)
		(fp_line
			(start 2.101 1.601)
			(end 2.101 1.48)
			(stroke
				(width 0.15)
				(type solid)
			)
			(layer "F.SilkS")
		)
		(fp_line
			(start 2.101 1.601)
			(end -2.1 1.601)
			(stroke
				(width 0.15)
				(type solid)
			)
			(layer "F.SilkS")
		)
		(fp_line
			(start 2.101 -1.58)
			(end 2.101 -1.459)
			(stroke
				(width 0.15)
				(type solid)
			)
			(layer "F.SilkS")
		)
		(fp_line
			(start 2.101 -1.6)
			(end -2.1 -1.6)
			(stroke
				(width 0.15)
				(type solid)
			)
			(layer "F.SilkS")
		)
		(fp_line
			(start -2.1 1.601)
			(end -2.1 1.48)
			(stroke
				(width 0.15)
				(type solid)
			)
			(layer "F.SilkS")
		)
		(fp_line
			(start -2.1 -1.6)
			(end -2.1 -1.499)
			(stroke
				(width 0.15)
				(type solid)
			)
			(layer "F.SilkS")
		)
		(fp_poly
			(pts
				(xy 2.751 1.75) (xy 2.751 -1.749) (xy -2.748 -1.749) (xy -2.748 1.749999)
			)
			(stroke
				(width 0.05)
				(type solid)
			)
			(fill no)
			(layer "F.CrtYd")
		)
		(fp_line
			(start 2.101 1.601)
			(end 2.101 -1.6)
			(stroke
				(width 0.15)
				(type solid)
			)
			(layer "F.Fab")
		)
		(fp_line
			(start 2.101 -1.6)
			(end -2.1 -1.6)
			(stroke
				(width 0.15)
				(type solid)
			)
			(layer "F.Fab")
		)
		(fp_line
			(start 0.25 0.802)
			(end -0.248 0.802)
			(stroke
				(width 0.15)
				(type solid)
			)
			(layer "F.Fab")
		)
		(fp_line
			(start -0.248 -0.8)
			(end 0.25 -0.8)
			(stroke
				(width 0.15)
				(type solid)
			)
			(layer "F.Fab")
		)
		(fp_line
			(start -2.1 1.601)
			(end 2.101 1.601)
			(stroke
				(width 0.15)
				(type solid)
			)
			(layer "F.Fab")
		)
		(fp_line
			(start -2.1 -1.6)
			(end -2.1 1.601)
			(stroke
				(width 0.15)
				(type solid)
			)
			(layer "F.Fab")
		)
		(fp_arc
			(start 0.25 -0.8)
			(mid 1.051001 0.001)
			(end 0.25 0.802)
			(stroke
				(width 0.15)
				(type solid)
			)
			(layer "F.Fab")
		)
		(fp_arc
			(start -0.248 0.802)
			(mid -1.050001 0.001)
			(end -0.248 -0.8)
			(stroke
				(width 0.15)
				(type solid)
			)
			(layer "F.Fab")
		)
		(fp_text user "${REFERENCE}"
			(at -3 4.25 0)
			(layer "F.Fab")
			(effects
				(font
					(size 0.7 0.7)
					(thickness 0.15)
				)
				(justify right top)
			)
		)
		(fp_text user "License: Apache-2.0"
			(at -3 6.75 0)
			(layer "F.Fab")
			(effects
				(font
					(size 0.7 0.7)
					(thickness 0.15)
				)
				(justify right top)
			)
		)
		(fp_text user "Author: Antmicro"
			(at -3 5.5 0)
			(layer "F.Fab")
			(effects
				(font
					(size 0.7 0.7)
					(thickness 0.15)
				)
				(justify right top)
			)
		)
		(pad "1" smd rect
			(at -2.048 -0.8)
			(size 0.9 1)
			(layers "F.Cu" "F.Mask" "F.Paste")
			(net 495 "/SoM_Power/~{FORCE_RECOVERY}")
			(pinfunction "1")
			(pintype "passive")
		)
		(pad "2" smd rect
			(at 2.049999 -0.8)
			(size 0.9 1)
			(layers "F.Cu" "F.Mask" "F.Paste")
			(net 495 "/SoM_Power/~{FORCE_RECOVERY}")
			(pinfunction "2")
			(pintype "passive")
		)
		(pad "3" smd rect
			(at -2.048 0.802)
			(size 0.9 1)
			(layers "F.Cu" "F.Mask" "F.Paste")
			(net 1 "GND")
			(pinfunction "3")
			(pintype "passive")
		)
		(pad "4" smd rect
			(at 2.05 0.802001)
			(size 0.9 1)
			(layers "F.Cu" "F.Mask" "F.Paste")
			(net 1 "GND")
			(pinfunction "4")
			(pintype "passive")
		)
	)
	(footprint "antmicro-footprints:TP_SMD_0.75mm"
		(layer "F.Cu")
		(at 66.16 58.26 90)
		(property "Reference" "TP27"
			(at 1.56 -2.51 90)
			(layer "F.SilkS")
			(effects
				(font
					(size 0.7 0.7)
					(thickness 0.15)
				)
				(justify left bottom)
			)
		)
		(property "Value" "TP_0.75mm_SMD"
			(at 0 1.2 90)
			(layer "F.Fab")
			(effects
				(font
					(size 0.7 0.7)
					(thickness 0.15)
				)
				(justify left bottom)
			)
		)
		(property "Description" "SMT test point"
			(at 0 0 90)
			(layer "F.Fab")
			(hide yes)
			(effects
				(font
					(size 1.27 1.27)
					(thickness 0.15)
				)
			)
		)
		(property "MPN" ""
			(at 0 0 90)
			(unlocked yes)
			(layer "F.Fab")
			(hide yes)
			(effects
				(font
					(size 1 1)
					(thickness 0.15)
				)
			)
		)
		(property "Manufacturer" ""
			(at 0 0 90)
			(unlocked yes)
			(layer "F.Fab")
			(hide yes)
			(effects
				(font
					(size 1 1)
					(thickness 0.15)
				)
			)
		)
		(property "Author" "Antmicro"
			(at 0 0 90)
			(unlocked yes)
			(layer "F.Fab")
			(hide yes)
			(effects
				(font
					(size 1 1)
					(thickness 0.15)
				)
			)
		)
		(property "License" "Apache-2.0"
			(at 0 0 90)
			(unlocked yes)
			(layer "F.Fab")
			(hide yes)
			(effects
				(font
					(size 1 1)
					(thickness 0.15)
				)
			)
		)
		(sheetname "/CSI/")
		(sheetfile "csi.kicad_sch")
		(attr exclude_from_pos_files exclude_from_bom)
		(fp_circle
			(center 0 0)
			(end 0.475 0)
			(stroke
				(width 0.05)
				(type default)
			)
			(fill no)
			(layer "F.CrtYd")
		)
		(fp_text user "License: Apache-2.0"
			(at -0.4 5.101 90)
			(layer "F.Fab")
			(effects
				(font
					(size 0.7 0.7)
					(thickness 0.15)
				)
				(justify left bottom)
			)
		)
		(fp_text user "Author: Antmicro"
			(at -0.4 3.901 90)
			(layer "F.Fab")
			(effects
				(font
					(size 0.7 0.7)
					(thickness 0.15)
				)
				(justify left bottom)
			)
		)
		(fp_text user "${REFERENCE}"
			(at -0.4 2.7 90)
			(layer "F.Fab")
			(effects
				(font
					(size 0.7 0.7)
					(thickness 0.15)
				)
				(justify left bottom)
			)
		)
		(pad "1" smd circle
			(at 0 0 90)
			(size 0.75 0.75)
			(layers "F.Cu" "F.Mask")
			(net 1051 "/CSI/MUX_I2C_7_SDA")
			(pinfunction "1")
			(pintype "passive")
		)
	)
	(footprint "antmicro-footprints:C_0402_1005Metric"
		(layer "F.Cu")
		(at 178.2 67.42)
		(descr "Capacitor SMD 0402")
		(tags "capacitor SMD 0402")
		(property "Reference" "C281"
			(at -2.4 -0.62 0)
			(layer "F.SilkS")
			(effects
				(font
					(size 0.7 0.7)
					(thickness 0.15)
				)
				(justify left bottom)
			)
		)
		(property "Value" "C_100n_0402"
			(at -1.022927 2.155213 0)
			(layer "F.Fab")
			(effects
				(font
					(size 0.7 0.7)
					(thickness 0.15)
				)
				(justify left bottom)
			)
		)
		(property "Datasheet" "https://www.murata.com/products/productdetail?partno=GRM155R61H104KE14%23"
			(at 0 0 0)
			(layer "F.Fab")
			(hide yes)
			(effects
				(font
					(size 1.27 1.27)
					(thickness 0.15)
				)
			)
		)
		(property "Description" "SMD Multilayer Ceramic Capacitor, 0.1 µF, 50 V, 0402 [1005 Metric], ± 10%, X5R, GRM Series"
			(at 0 0 0)
			(layer "F.Fab")
			(hide yes)
			(effects
				(font
					(size 1.27 1.27)
					(thickness 0.15)
				)
			)
		)
		(property "Manufacturer" "Murata"
			(at 0 0 0)
			(unlocked yes)
			(layer "F.Fab")
			(hide yes)
			(effects
				(font
					(size 1 1)
					(thickness 0.15)
				)
			)
		)
		(property "MPN" "GRM155R61H104KE14D"
			(at 0 0 0)
			(unlocked yes)
			(layer "F.Fab")
			(hide yes)
			(effects
				(font
					(size 1 1)
					(thickness 0.15)
				)
			)
		)
		(property "Val" "100n"
			(at 0 0 0)
			(unlocked yes)
			(layer "F.Fab")
			(hide yes)
			(effects
				(font
					(size 1 1)
					(thickness 0.15)
				)
			)
		)
		(property "License" "Apache-2.0"
			(at 0 0 0)
			(unlocked yes)
			(layer "F.Fab")
			(hide yes)
			(effects
				(font
					(size 1 1)
					(thickness 0.15)
				)
			)
		)
		(property "Author" "Antmicro"
			(at 0 0 0)
			(unlocked yes)
			(layer "F.Fab")
			(hide yes)
			(effects
				(font
					(size 1 1)
					(thickness 0.15)
				)
			)
		)
		(property "Voltage" "50V"
			(at 0 0 0)
			(unlocked yes)
			(layer "F.Fab")
			(hide yes)
			(effects
				(font
					(size 1 1)
					(thickness 0.15)
				)
			)
		)
		(property "Dielectric" "X5R"
			(at 0 0 0)
			(unlocked yes)
			(layer "F.Fab")
			(hide yes)
			(effects
				(font
					(size 1 1)
					(thickness 0.15)
				)
			)
		)
		(component_classes
			(class "DCDC_20V")
		)
		(sheetname "/DCDC/")
		(sheetfile "dcdc.kicad_sch")
		(attr smd)
		(fp_rect
			(start -0.925 -0.47)
			(end 0.925 0.47)
			(stroke
				(width 0.05)
				(type default)
			)
			(fill no)
			(layer "F.CrtYd")
		)
		(fp_line
			(start -0.494 -0.25)
			(end 0.504 -0.25)
			(stroke
				(width 0.15)
				(type solid)
			)
			(layer "F.Fab")
		)
		(fp_line
			(start -0.494 0.248)
			(end -0.494 -0.25)
			(stroke
				(width 0.15)
				(type solid)
			)
			(layer "F.Fab")
		)
		(fp_line
			(start 0.504 -0.25)
			(end 0.504 0.248)
			(stroke
				(width 0.15)
				(type solid)
			)
			(layer "F.Fab")
		)
		(fp_line
			(start 0.504 0.248)
			(end -0.494 0.248)
			(stroke
				(width 0.15)
				(type solid)
			)
			(layer "F.Fab")
		)
		(fp_text user "Author: Antmicro"
			(at -0.939 3.399 0)
			(layer "F.Fab")
			(effects
				(font
					(size 0.7 0.7)
					(thickness 0.15)
				)
				(justify left bottom)
			)
		)
		(fp_text user "License: Apache-2.0"
			(at -0.939 5.799 0)
			(layer "F.Fab")
			(effects
				(font
					(size 0.7 0.7)
					(thickness 0.15)
				)
				(justify left bottom)
			)
		)
		(fp_text user "${REFERENCE}"
			(at -0.939 4.599 0)
			(layer "F.Fab")
			(effects
				(font
					(size 0.7 0.7)
					(thickness 0.15)
				)
				(justify left bottom)
			)
		)
		(pad "1" smd roundrect
			(at -0.48 0)
			(size 0.59 0.64)
			(layers "F.Cu" "F.Mask" "F.Paste")
			(roundrect_rratio 0.25)
			(net 1104 "/DCDC/20V_PHASE")
			(pintype "passive")
		)
		(pad "2" smd roundrect
			(at 0.48 0)
			(size 0.59 0.64)
			(layers "F.Cu" "F.Mask" "F.Paste")
			(roundrect_rratio 0.25)
			(net 1086 "/DCDC/20V_BOOT")
			(pintype "passive")
		)
	)
	(footprint "antmicro-footprints:R_0402_1005Metric"
		(layer "F.Cu")
		(at 183.809468 68.67 90)
		(descr "Resistor SMD 0402")
		(tags "resistor SMD 0402")
		(property "Reference" "R125"
			(at -1.4 2.61 90)
			(layer "F.SilkS")
			(effects
				(font
					(size 0.7 0.7)
					(thickness 0.15)
				)
				(justify left bottom)
			)
		)
		(property "Value" "R_10k_0402"
			(at -1.011843 1.772047 90)
			(layer "F.Fab")
			(effects
				(font
					(size 0.7 0.7)
					(thickness 0.15)
				)
				(justify left bottom)
			)
		)
		(property "Datasheet" "https://www.bourns.com/docs/product-datasheets/cr.pdf"
			(at 0 0 90)
			(layer "F.Fab")
			(hide yes)
			(effects
				(font
					(size 1.27 1.27)
					(thickness 0.15)
				)
			)
		)
		(property "Description" "SMD Chip Resistor, 10 kohm, ± 1%, 62.5 mW, 0402 [1005 Metric], Thick Film, General Purpose"
			(at 0 0 90)
			(layer "F.Fab")
			(hide yes)
			(effects
				(font
					(size 1.27 1.27)
					(thickness 0.15)
				)
			)
		)
		(property "MPN" "CR0402-FX-1002GLF"
			(at 0 0 90)
			(unlocked yes)
			(layer "F.Fab")
			(hide yes)
			(effects
				(font
					(size 1 1)
					(thickness 0.15)
				)
			)
		)
		(property "Manufacturer" "Bourns"
			(at 0 0 90)
			(unlocked yes)
			(layer "F.Fab")
			(hide yes)
			(effects
				(font
					(size 1 1)
					(thickness 0.15)
				)
			)
		)
		(property "License" "Apache-2.0"
			(at 0 0 90)
			(unlocked yes)
			(layer "F.Fab")
			(hide yes)
			(effects
				(font
					(size 1 1)
					(thickness 0.15)
				)
			)
		)
		(property "Author" "Antmicro"
			(at 0 0 90)
			(unlocked yes)
			(layer "F.Fab")
			(hide yes)
			(effects
				(font
					(size 1 1)
					(thickness 0.15)
				)
			)
		)
		(property "Val" "10k"
			(at 0 0 90)
			(unlocked yes)
			(layer "F.Fab")
			(hide yes)
			(effects
				(font
					(size 1 1)
					(thickness 0.15)
				)
			)
		)
		(property "Tolerance" "1%"
			(at 0 0 90)
			(unlocked yes)
			(layer "F.Fab")
			(hide yes)
			(effects
				(font
					(size 1 1)
					(thickness 0.15)
				)
			)
		)
		(component_classes
			(class "DCDC_20V")
		)
		(sheetname "/DCDC/")
		(sheetfile "dcdc.kicad_sch")
		(attr smd)
		(fp_rect
			(start -0.925 -0.47)
			(end 0.925 0.47)
			(stroke
				(width 0.05)
				(type default)
			)
			(fill no)
			(layer "F.CrtYd")
		)
		(fp_rect
			(start -0.5 -0.25)
			(end 0.5 0.25)
			(stroke
				(width 0.15)
				(type solid)
			)
			(fill no)
			(layer "F.Fab")
		)
		(fp_text user "Author: Antmicro"
			(at -0.95 4.169 90)
			(layer "F.Fab")
			(effects
				(font
					(size 0.7 0.7)
					(thickness 0.15)
				)
				(justify left bottom)
			)
		)
		(fp_text user "${REFERENCE}"
			(at -0.95 3.168 90)
			(layer "F.Fab")
			(effects
				(font
					(size 0.7 0.7)
					(thickness 0.15)
				)
				(justify left bottom)
			)
		)
		(fp_text user "License: Apache-2.0"
			(at -0.95 5.169 90)
			(layer "F.Fab")
			(effects
				(font
					(size 0.7 0.7)
					(thickness 0.15)
				)
				(justify left bottom)
			)
		)
		(pad "1" smd roundrect
			(at -0.48 0 90)
			(size 0.59 0.64)
			(layers "F.Cu" "F.Mask" "F.Paste")
			(roundrect_rratio 0.25)
			(net 1 "GND")
			(pintype "passive")
		)
		(pad "2" smd roundrect
			(at 0.48 0 90)
			(size 0.59 0.64)
			(layers "F.Cu" "F.Mask" "F.Paste")
			(roundrect_rratio 0.25)
			(net 1220 "/DCDC/20V_FB")
			(pintype "passive")
		)
	)
	(footprint "antmicro-footprints:C_0805_2012Metric"
		(layer "F.Cu")
		(at 72.6 131 -90)
		(descr "Capacitor SMD 0805")
		(tags "capacitor SMD 0805")
		(property "Reference" "C228"
			(at -3.8 -1.4 90)
			(layer "F.SilkS")
			(effects
				(font
					(size 0.7 0.7)
					(thickness 0.15)
				)
				(justify right top)
			)
		)
		(property "Value" "C_22u_25V_0805"
			(at -2.055717 1.963153 90)
			(layer "F.Fab")
			(effects
				(font
					(size 0.7 0.7)
					(thickness 0.15)
				)
				(justify right top)
			)
		)
		(property "Datasheet" "https://product.samsungsem.com/mlcc/CL21A226MAYNNN.do"
			(at 0 0 90)
			(layer "F.Fab")
			(hide yes)
			(effects
				(font
					(size 1.27 1.27)
					(thickness 0.15)
				)
			)
		)
		(property "Description" "SMT Multilayer Ceramic Capacitor, 22uF, +/-20%, 25V, X5R, 0805 [2012 Metric]"
			(at 0 0 90)
			(layer "F.Fab")
			(hide yes)
			(effects
				(font
					(size 1.27 1.27)
					(thickness 0.15)
				)
			)
		)
		(property "MPN" "CL21A226MAYNNNE"
			(at 0 0 270)
			(unlocked yes)
			(layer "F.Fab")
			(hide yes)
			(effects
				(font
					(size 1 1)
					(thickness 0.15)
				)
			)
		)
		(property "Val" "22u"
			(at 0 0 270)
			(unlocked yes)
			(layer "F.Fab")
			(hide yes)
			(effects
				(font
					(size 1 1)
					(thickness 0.15)
				)
			)
		)
		(property "Voltage" "25V"
			(at 0 0 270)
			(unlocked yes)
			(layer "F.Fab")
			(hide yes)
			(effects
				(font
					(size 1 1)
					(thickness 0.15)
				)
			)
		)
		(property "Dielectric" "X5R"
			(at 0 0 270)
			(unlocked yes)
			(layer "F.Fab")
			(hide yes)
			(effects
				(font
					(size 1 1)
					(thickness 0.15)
				)
			)
		)
		(property "Manufacturer" "Samsung Electro-Mechanics"
			(at 0 0 270)
			(unlocked yes)
			(layer "F.Fab")
			(hide yes)
			(effects
				(font
					(size 1 1)
					(thickness 0.15)
				)
			)
		)
		(property "License" "Apache-2.0"
			(at 0 0 270)
			(unlocked yes)
			(layer "F.Fab")
			(hide yes)
			(effects
				(font
					(size 1 1)
					(thickness 0.15)
				)
			)
		)
		(property "Author" "Antmicro"
			(at 0 0 270)
			(unlocked yes)
			(layer "F.Fab")
			(hide yes)
			(effects
				(font
					(size 1 1)
					(thickness 0.15)
				)
			)
		)
		(property "Public" "False"
			(at 0 0 270)
			(unlocked yes)
			(layer "F.Fab")
			(hide yes)
			(effects
				(font
					(size 1 1)
					(thickness 0.15)
				)
			)
		)
		(sheetname "/Expansion connector/")
		(sheetfile "expansion_connector.kicad_sch")
		(attr smd)
		(fp_line
			(start -0.3 0.7)
			(end 0.3 0.7)
			(stroke
				(width 0.15)
				(type solid)
			)
			(layer "F.SilkS")
		)
		(fp_line
			(start -0.3 -0.7)
			(end 0.3 -0.7)
			(stroke
				(width 0.15)
				(type solid)
			)
			(layer "F.SilkS")
		)
		(fp_poly
			(pts
				(xy 1.95 -0.9) (xy -1.95 -0.9) (xy -1.95 0.9) (xy 1.95 0.9)
			)
			(stroke
				(width 0.05)
				(type default)
			)
			(fill no)
			(layer "F.CrtYd")
		)
		(fp_poly
			(pts
				(xy -0.95 -0.675001) (xy 0.95 -0.675001) (xy 0.95 0.675001) (xy -0.95 0.675001)
			)
			(stroke
				(width 0.15)
				(type solid)
			)
			(fill no)
			(layer "F.Fab")
		)
		(fp_text user "${REFERENCE}"
			(at -1.899999 3.947 90)
			(layer "F.Fab")
			(effects
				(font
					(size 0.7 0.7)
					(thickness 0.15)
				)
				(justify right top)
			)
		)
		(fp_text user "License: Apache-2.0"
			(at -1.9 4.947 90)
			(layer "F.Fab")
			(effects
				(font
					(size 0.7 0.7)
					(thickness 0.15)
				)
				(justify right top)
			)
		)
		(fp_text user "Author: Antmicro"
			(at -1.9 5.947 90)
			(layer "F.Fab")
			(effects
				(font
					(size 0.7 0.7)
					(thickness 0.15)
				)
				(justify right top)
			)
		)
		(pad "1" smd roundrect
			(at -1.099999 0 270)
			(size 1.2 1.3)
			(layers "F.Cu" "F.Mask" "F.Paste")
			(roundrect_rratio 0.25)
			(net 1 "GND")
			(pintype "passive")
		)
		(pad "2" smd roundrect
			(at 1.099999 0 270)
			(size 1.2 1.3)
			(layers "F.Cu" "F.Mask" "F.Paste")
			(roundrect_rratio 0.25)
			(net 295 "/Expansion connector/+V_{ADJ}")
			(pintype "passive")
		)
	)
	(footprint "antmicro-footprints:C_0805_2012Metric"
		(layer "F.Cu")
		(at 167.7 73.32 -90)
		(descr "Capacitor SMD 0805")
		(tags "capacitor SMD 0805")
		(property "Reference" "C297"
			(at 1.78449 -1.468678 90)
			(layer "F.SilkS")
			(effects
				(font
					(size 0.7 0.7)
					(thickness 0.15)
				)
				(justify right top)
			)
		)
		(property "Value" "C_22u_25V_0805"
			(at -2.055717 1.963152 90)
			(layer "F.Fab")
			(effects
				(font
					(size 0.7 0.7)
					(thickness 0.15)
				)
				(justify right top)
			)
		)
		(property "Datasheet" "https://product.samsungsem.com/mlcc/CL21A226MAYNNN.do"
			(at 0 0 90)
			(layer "F.Fab")
			(hide yes)
			(effects
				(font
					(size 1.27 1.27)
					(thickness 0.15)
				)
			)
		)
		(property "Description" "SMT Multilayer Ceramic Capacitor, 22uF, +/-20%, 25V, X5R, 0805 [2012 Metric]"
			(at 0 0 90)
			(layer "F.Fab")
			(hide yes)
			(effects
				(font
					(size 1.27 1.27)
					(thickness 0.15)
				)
			)
		)
		(property "MPN" "CL21A226MAYNNNE"
			(at 0 0 270)
			(unlocked yes)
			(layer "F.Fab")
			(hide yes)
			(effects
				(font
					(size 1 1)
					(thickness 0.15)
				)
			)
		)
		(property "Manufacturer" "Samsung Electro-Mechanics"
			(at 0 0 270)
			(unlocked yes)
			(layer "F.Fab")
			(hide yes)
			(effects
				(font
					(size 1 1)
					(thickness 0.15)
				)
			)
		)
		(property "License" "Apache-2.0"
			(at 0 0 270)
			(unlocked yes)
			(layer "F.Fab")
			(hide yes)
			(effects
				(font
					(size 1 1)
					(thickness 0.15)
				)
			)
		)
		(property "Author" "Antmicro"
			(at 0 0 270)
			(unlocked yes)
			(layer "F.Fab")
			(hide yes)
			(effects
				(font
					(size 1 1)
					(thickness 0.15)
				)
			)
		)
		(property "Val" "22u"
			(at 0 0 270)
			(unlocked yes)
			(layer "F.Fab")
			(hide yes)
			(effects
				(font
					(size 1 1)
					(thickness 0.15)
				)
			)
		)
		(property "Voltage" "25V"
			(at 0 0 270)
			(unlocked yes)
			(layer "F.Fab")
			(hide yes)
			(effects
				(font
					(size 1 1)
					(thickness 0.15)
				)
			)
		)
		(property "Dielectric" "X5R"
			(at 0 0 270)
			(unlocked yes)
			(layer "F.Fab")
			(hide yes)
			(effects
				(font
					(size 1 1)
					(thickness 0.15)
				)
			)
		)
		(property "Public" "False"
			(at 0 0 270)
			(unlocked yes)
			(layer "F.Fab")
			(hide yes)
			(effects
				(font
					(size 1 1)
					(thickness 0.15)
				)
			)
		)
		(component_classes
			(class "DCDC_20V")
		)
		(sheetname "/DCDC/")
		(sheetfile "dcdc.kicad_sch")
		(attr smd)
		(fp_line
			(start -0.3 0.7)
			(end 0.3 0.7)
			(stroke
				(width 0.15)
				(type solid)
			)
			(layer "F.SilkS")
		)
		(fp_line
			(start -0.3 -0.7)
			(end 0.3 -0.7)
			(stroke
				(width 0.15)
				(type solid)
			)
			(layer "F.SilkS")
		)
		(fp_rect
			(start 1.95 -0.9)
			(end -1.95 0.9)
			(stroke
				(width 0.05)
				(type default)
			)
			(fill no)
			(layer "F.CrtYd")
		)
		(fp_rect
			(start -0.95 -0.675)
			(end 0.95 0.675)
			(stroke
				(width 0.15)
				(type solid)
			)
			(fill no)
			(layer "F.Fab")
		)
		(fp_text user "Author: Antmicro"
			(at -1.9 5.947 90)
			(layer "F.Fab")
			(effects
				(font
					(size 0.7 0.7)
					(thickness 0.15)
				)
				(justify right top)
			)
		)
		(fp_text user "${REFERENCE}"
			(at -1.9 3.947 90)
			(layer "F.Fab")
			(effects
				(font
					(size 0.7 0.7)
					(thickness 0.15)
				)
				(justify right top)
			)
		)
		(fp_text user "License: Apache-2.0"
			(at -1.9 4.947 90)
			(layer "F.Fab")
			(effects
				(font
					(size 0.7 0.7)
					(thickness 0.15)
				)
				(justify right top)
			)
		)
		(pad "1" smd roundrect
			(at -1.1 0 270)
			(size 1.2 1.3)
			(layers "F.Cu" "F.Mask" "F.Paste")
			(roundrect_rratio 0.25)
			(net 1 "GND")
			(pintype "passive")
		)
		(pad "2" smd roundrect
			(at 1.1 0 270)
			(size 1.2 1.3)
			(layers "F.Cu" "F.Mask" "F.Paste")
			(roundrect_rratio 0.25)
			(net 1105 "/DCDC/20V_OUT")
			(pintype "passive")
		)
	)
	(footprint "antmicro-footprints:R_0402_1005Metric"
		(layer "F.Cu")
		(at 171.919468 117.806 90)
		(descr "Resistor SMD 0402")
		(tags "resistor SMD 0402")
		(property "Reference" "R368"
			(at -0.822484 -5.162165 90)
			(layer "F.SilkS")
			(effects
				(font
					(size 0.7 0.7)
					(thickness 0.15)
				)
				(justify left bottom)
			)
		)
		(property "Value" "R_27R_0402"
			(at -1.011843 1.772047 90)
			(layer "F.Fab")
			(effects
				(font
					(size 0.7 0.7)
					(thickness 0.15)
				)
				(justify left bottom)
			)
		)
		(property "Datasheet" "https://www.bourns.com/docs/product-datasheets/cr.pdf"
			(at 0 0 90)
			(layer "F.Fab")
			(hide yes)
			(effects
				(font
					(size 1.27 1.27)
					(thickness 0.15)
				)
			)
		)
		(property "Description" "SMD Chip Resistor, 27 ohm, ± 1%, 63 mW, 0402 [1005 Metric], Thick Film, General Purpose"
			(at 0 0 90)
			(layer "F.Fab")
			(hide yes)
			(effects
				(font
					(size 1.27 1.27)
					(thickness 0.15)
				)
			)
		)
		(property "Manufacturer" "Bourns"
			(at 0 0 90)
			(unlocked yes)
			(layer "F.Fab")
			(hide yes)
			(effects
				(font
					(size 1 1)
					(thickness 0.15)
				)
			)
		)
		(property "MPN" "CR0402-FX-27R0GLF"
			(at 0 0 90)
			(unlocked yes)
			(layer "F.Fab")
			(hide yes)
			(effects
				(font
					(size 1 1)
					(thickness 0.15)
				)
			)
		)
		(property "Val" "27R"
			(at 0 0 90)
			(unlocked yes)
			(layer "F.Fab")
			(hide yes)
			(effects
				(font
					(size 1 1)
					(thickness 0.15)
				)
			)
		)
		(property "License" "Apache-2.0"
			(at 0 0 90)
			(unlocked yes)
			(layer "F.Fab")
			(hide yes)
			(effects
				(font
					(size 1 1)
					(thickness 0.15)
				)
			)
		)
		(property "Author" "Antmicro"
			(at 0 0 90)
			(unlocked yes)
			(layer "F.Fab")
			(hide yes)
			(effects
				(font
					(size 1 1)
					(thickness 0.15)
				)
			)
		)
		(property "Tolerance" "1%"
			(at 0 0 90)
			(unlocked yes)
			(layer "F.Fab")
			(hide yes)
			(effects
				(font
					(size 1 1)
					(thickness 0.15)
				)
			)
		)
		(sheetname "/DCDC/")
		(sheetfile "dcdc.kicad_sch")
		(attr smd)
		(fp_rect
			(start -0.925 -0.47)
			(end 0.925 0.47)
			(stroke
				(width 0.05)
				(type default)
			)
			(fill no)
			(layer "F.CrtYd")
		)
		(fp_rect
			(start -0.5 -0.25)
			(end 0.5 0.25)
			(stroke
				(width 0.15)
				(type solid)
			)
			(fill no)
			(layer "F.Fab")
		)
		(fp_text user "Author: Antmicro"
			(at -0.95 4.169 90)
			(layer "F.Fab")
			(effects
				(font
					(size 0.7 0.7)
					(thickness 0.15)
				)
				(justify left bottom)
			)
		)
		(fp_text user "License: Apache-2.0"
			(at -0.95 5.169 90)
			(layer "F.Fab")
			(effects
				(font
					(size 0.7 0.7)
					(thickness 0.15)
				)
				(justify left bottom)
			)
		)
		(fp_text user "${REFERENCE}"
			(at -0.95 3.168 90)
			(layer "F.Fab")
			(effects
				(font
					(size 0.7 0.7)
					(thickness 0.15)
				)
				(justify left bottom)
			)
		)
		(pad "1" smd roundrect
			(at -0.48 0 90)
			(size 0.59 0.64)
			(layers "F.Cu" "F.Mask" "F.Paste")
			(roundrect_rratio 0.25)
			(net 1161 "Net-(U50-IN-)")
			(pintype "passive")
		)
		(pad "2" smd roundrect
			(at 0.48 0 90)
			(size 0.59 0.64)
			(layers "F.Cu" "F.Mask" "F.Paste")
			(roundrect_rratio 0.25)
			(net 5 "+5V")
			(pintype "passive")
		)
	)
	(footprint "antmicro-footprints:R_0402_1005Metric"
		(layer "F.Cu")
		(at 167 145.6 90)
		(descr "Resistor SMD 0402")
		(tags "resistor SMD 0402")
		(property "Reference" "R28"
			(at 4.3 2.5 90)
			(layer "F.SilkS")
			(effects
				(font
					(size 0.7 0.7)
					(thickness 0.15)
				)
				(justify left bottom)
			)
		)
		(property "Value" "R_0R_0402"
			(at -1.011843 1.772047 90)
			(layer "F.Fab")
			(effects
				(font
					(size 0.7 0.7)
					(thickness 0.15)
				)
				(justify left bottom)
			)
		)
		(property "Datasheet" "https://industrial.panasonic.com/cdbs/www-data/pdf/RDA0000/AOA0000C301.pdf"
			(at 0 0 90)
			(layer "F.Fab")
			(hide yes)
			(effects
				(font
					(size 1.27 1.27)
					(thickness 0.15)
				)
			)
		)
		(property "Description" "SMD Chip Resistor, Jumper, 0 ohm, 100 mW, 0402 [1005 Metric], Thick Film, General Purpose"
			(at 0 0 90)
			(layer "F.Fab")
			(hide yes)
			(effects
				(font
					(size 1.27 1.27)
					(thickness 0.15)
				)
			)
		)
		(property "MPN" "ERJ2GE0R00X"
			(at 0 0 90)
			(unlocked yes)
			(layer "F.Fab")
			(hide yes)
			(effects
				(font
					(size 1 1)
					(thickness 0.15)
				)
			)
		)
		(property "Manufacturer" "Panasonic"
			(at 0 0 90)
			(unlocked yes)
			(layer "F.Fab")
			(hide yes)
			(effects
				(font
					(size 1 1)
					(thickness 0.15)
				)
			)
		)
		(property "License" "Apache-2.0"
			(at 0 0 90)
			(unlocked yes)
			(layer "F.Fab")
			(hide yes)
			(effects
				(font
					(size 1 1)
					(thickness 0.15)
				)
			)
		)
		(property "Author" "Antmicro"
			(at 0 0 90)
			(unlocked yes)
			(layer "F.Fab")
			(hide yes)
			(effects
				(font
					(size 1 1)
					(thickness 0.15)
				)
			)
		)
		(property "Val" "0R"
			(at 0 0 90)
			(unlocked yes)
			(layer "F.Fab")
			(hide yes)
			(effects
				(font
					(size 1 1)
					(thickness 0.15)
				)
			)
		)
		(property "Tolerance" "~"
			(at 0 0 90)
			(unlocked yes)
			(layer "F.Fab")
			(hide yes)
			(effects
				(font
					(size 1 1)
					(thickness 0.15)
				)
			)
		)
		(property "Current" "1A"
			(at 0 0 270)
			(unlocked yes)
			(layer "F.Fab")
			(hide yes)
			(effects
				(font
					(size 1 1)
					(thickness 0.15)
				)
			)
		)
		(sheetname "/Peripherals/")
		(sheetfile "peripherals.kicad_sch")
		(attr smd)
		(fp_rect
			(start -0.925 -0.47)
			(end 0.925 0.47)
			(stroke
				(width 0.05)
				(type default)
			)
			(fill no)
			(layer "F.CrtYd")
		)
		(fp_rect
			(start -0.5 -0.25)
			(end 0.5 0.25)
			(stroke
				(width 0.15)
				(type solid)
			)
			(fill no)
			(layer "F.Fab")
		)
		(fp_text user "License: Apache-2.0"
			(at -0.95 5.169 90)
			(layer "F.Fab")
			(effects
				(font
					(size 0.7 0.7)
					(thickness 0.15)
				)
				(justify left bottom)
			)
		)
		(fp_text user "Author: Antmicro"
			(at -0.95 4.169 90)
			(layer "F.Fab")
			(effects
				(font
					(size 0.7 0.7)
					(thickness 0.15)
				)
				(justify left bottom)
			)
		)
		(fp_text user "${REFERENCE}"
			(at -0.95 3.168 90)
			(layer "F.Fab")
			(effects
				(font
					(size 0.7 0.7)
					(thickness 0.15)
				)
				(justify left bottom)
			)
		)
		(pad "1" smd roundrect
			(at -0.48 0 90)
			(size 0.59 0.64)
			(layers "F.Cu" "F.Mask" "F.Paste")
			(roundrect_rratio 0.25)
			(net 5 "+5V")
			(pintype "passive")
		)
		(pad "2" smd roundrect
			(at 0.48 0 90)
			(size 0.59 0.64)
			(layers "F.Cu" "F.Mask" "F.Paste")
			(roundrect_rratio 0.25)
			(net 1043 "/Peripherals/FAN_VDD")
			(pintype "passive")
		)
	)
	(footprint "antmicro-footprints:C_0805_2012Metric"
		(layer "F.Cu")
		(at 172.71 142.39 90)
		(descr "Capacitor SMD 0805")
		(tags "capacitor SMD 0805")
		(property "Reference" "C29"
			(at 1.92 0.23 90)
			(layer "F.SilkS")
			(effects
				(font
					(size 0.7 0.7)
					(thickness 0.15)
				)
				(justify left bottom)
			)
		)
		(property "Value" "C_22u_25V_0805"
			(at -2.055717 1.963152 90)
			(layer "F.Fab")
			(effects
				(font
					(size 0.7 0.7)
					(thickness 0.15)
				)
				(justify left bottom)
			)
		)
		(property "Datasheet" "https://product.samsungsem.com/mlcc/CL21A226MAYNNN.do"
			(at 0 0 90)
			(layer "F.Fab")
			(hide yes)
			(effects
				(font
					(size 1.27 1.27)
					(thickness 0.15)
				)
			)
		)
		(property "Description" "SMT Multilayer Ceramic Capacitor, 22uF, +/-20%, 25V, X5R, 0805 [2012 Metric]"
			(at 0 0 90)
			(layer "F.Fab")
			(hide yes)
			(effects
				(font
					(size 1.27 1.27)
					(thickness 0.15)
				)
			)
		)
		(property "Manufacturer" "Samsung Electro-Mechanics"
			(at 0 0 90)
			(unlocked yes)
			(layer "F.Fab")
			(hide yes)
			(effects
				(font
					(size 1 1)
					(thickness 0.15)
				)
			)
		)
		(property "MPN" "CL21A226MAYNNNE"
			(at 0 0 90)
			(unlocked yes)
			(layer "F.Fab")
			(hide yes)
			(effects
				(font
					(size 1 1)
					(thickness 0.15)
				)
			)
		)
		(property "Val" "22u"
			(at 0 0 90)
			(unlocked yes)
			(layer "F.Fab")
			(hide yes)
			(effects
				(font
					(size 1 1)
					(thickness 0.15)
				)
			)
		)
		(property "License" "Apache-2.0"
			(at 0 0 90)
			(unlocked yes)
			(layer "F.Fab")
			(hide yes)
			(effects
				(font
					(size 1 1)
					(thickness 0.15)
				)
			)
		)
		(property "Author" "Antmicro"
			(at 0 0 90)
			(unlocked yes)
			(layer "F.Fab")
			(hide yes)
			(effects
				(font
					(size 1 1)
					(thickness 0.15)
				)
			)
		)
		(property "Voltage" "25V"
			(at 0 0 90)
			(unlocked yes)
			(layer "F.Fab")
			(hide yes)
			(effects
				(font
					(size 1 1)
					(thickness 0.15)
				)
			)
		)
		(property "Dielectric" "X5R"
			(at 0 0 90)
			(unlocked yes)
			(layer "F.Fab")
			(hide yes)
			(effects
				(font
					(size 1 1)
					(thickness 0.15)
				)
			)
		)
		(property "Public" "False"
			(at 0 0 90)
			(unlocked yes)
			(layer "F.Fab")
			(hide yes)
			(effects
				(font
					(size 1 1)
					(thickness 0.15)
				)
			)
		)
		(sheetname "/DCDC/")
		(sheetfile "dcdc.kicad_sch")
		(attr smd)
		(fp_line
			(start -0.3 -0.7)
			(end 0.3 -0.7)
			(stroke
				(width 0.15)
				(type solid)
			)
			(layer "F.SilkS")
		)
		(fp_line
			(start -0.3 0.7)
			(end 0.3 0.7)
			(stroke
				(width 0.15)
				(type solid)
			)
			(layer "F.SilkS")
		)
		(fp_rect
			(start 1.95 -0.9)
			(end -1.95 0.9)
			(stroke
				(width 0.05)
				(type default)
			)
			(fill no)
			(layer "F.CrtYd")
		)
		(fp_rect
			(start -0.95 -0.675)
			(end 0.95 0.675)
			(stroke
				(width 0.15)
				(type solid)
			)
			(fill no)
			(layer "F.Fab")
		)
		(fp_text user "License: Apache-2.0"
			(at -1.9 4.947 90)
			(layer "F.Fab")
			(effects
				(font
					(size 0.7 0.7)
					(thickness 0.15)
				)
				(justify left bottom)
			)
		)
		(fp_text user "${REFERENCE}"
			(at -1.9 3.947 90)
			(layer "F.Fab")
			(effects
				(font
					(size 0.7 0.7)
					(thickness 0.15)
				)
				(justify left bottom)
			)
		)
		(fp_text user "Author: Antmicro"
			(at -1.9 5.947 90)
			(layer "F.Fab")
			(effects
				(font
					(size 0.7 0.7)
					(thickness 0.15)
				)
				(justify left bottom)
			)
		)
		(pad "1" smd roundrect
			(at -1.1 0 90)
			(size 1.2 1.3)
			(layers "F.Cu" "F.Mask" "F.Paste")
			(roundrect_rratio 0.25)
			(net 1 "GND")
			(pintype "passive")
		)
		(pad "2" smd roundrect
			(at 1.1 0 90)
			(size 1.2 1.3)
			(layers "F.Cu" "F.Mask" "F.Paste")
			(roundrect_rratio 0.25)
			(net 13 "VCC")
			(pintype "passive")
		)
	)
	(footprint "antmicro-footprints:USB-C_Receptacle_Kycon_KUSBX-SL2-CS1N24-B-TR"
		(locked yes)
		(layer "F.Cu")
		(at 236.455532 102.21 90)
		(descr "USB-C (USB TYPE-C) USB 3.2 Gen 2 (USB 3.1 Gen 2, Superspeed + (USB 3.1)) Receptacle Connector 24 Position Through Hole, Right Angle")
		(tags "CONNECTOR, USB")
		(property "Reference" "J3"
			(at 3.21 -10.685532 180)
			(layer "F.SilkS")
			(effects
				(font
					(size 0.7 0.7)
					(thickness 0.15)
				)
				(justify left bottom)
			)
		)
		(property "Value" "USB-C_Kycon_KUSBX-SL2-CS1N24-B-TR"
			(at 0 7.5 90)
			(layer "F.Fab")
			(effects
				(font
					(size 0.7 0.7)
					(thickness 0.15)
				)
				(justify right top)
			)
		)
		(property "Datasheet" "https://www.kycon.com/Pub_Eng_Draw/KUSBX-SL2-CS1N24-B-TR.pdf"
			(at 0 0 90)
			(layer "F.Fab")
			(hide yes)
			(effects
				(font
					(size 1.27 1.27)
					(thickness 0.15)
				)
			)
		)
		(property "Description" "USB-C (USB TYPE-C) USB 3.2 Gen 2 (USB 3.1 Gen 2, Superspeed + (USB 3.1)) USB PD Receptacle Connector 24 Position Surface Mount"
			(at 0 0 90)
			(layer "F.Fab")
			(hide yes)
			(effects
				(font
					(size 1.27 1.27)
					(thickness 0.15)
				)
			)
		)
		(property "MPN" "KUSBX-SL2-CS1N24-B-TR"
			(at 0 0 90)
			(unlocked yes)
			(layer "F.Fab")
			(hide yes)
			(effects
				(font
					(size 1 1)
					(thickness 0.15)
				)
			)
		)
		(property "Manufacturer" "Kycon"
			(at 0 0 90)
			(unlocked yes)
			(layer "F.Fab")
			(hide yes)
			(effects
				(font
					(size 1 1)
					(thickness 0.15)
				)
			)
		)
		(property "License" "Apache-2.0"
			(at 0 0 90)
			(unlocked yes)
			(layer "F.Fab")
			(hide yes)
			(effects
				(font
					(size 1 1)
					(thickness 0.15)
				)
			)
		)
		(property "Author" "Antmicro"
			(at 0 0 90)
			(unlocked yes)
			(layer "F.Fab")
			(hide yes)
			(effects
				(font
					(size 1 1)
					(thickness 0.15)
				)
			)
		)
		(sheetname "/Recovery USB/")
		(sheetfile "recovery_usb.kicad_sch")
		(attr smd)
		(fp_line
			(start 1 -8.8)
			(end 1 -8.8)
			(stroke
				(width 0.15)
				(type solid)
			)
			(layer "F.SilkS")
		)
		(fp_line
			(start 1 -8.8)
			(end -1 -8.8)
			(stroke
				(width 0.15)
				(type solid)
			)
			(layer "F.SilkS")
		)
		(fp_line
			(start -1 -8.8)
			(end 1 -8.8)
			(stroke
				(width 0.15)
				(type solid)
			)
			(layer "F.SilkS")
		)
		(fp_line
			(start -1 -8.8)
			(end -1 -8.8)
			(stroke
				(width 0.15)
				(type solid)
			)
			(layer "F.SilkS")
		)
		(fp_rect
			(start -4 -9.4)
			(end 4 5.65)
			(stroke
				(width 0.05)
				(type solid)
			)
			(fill no)
			(layer "F.CrtYd")
		)
		(fp_line
			(start 2.25 -8.8)
			(end -2.25 -8.8)
			(stroke
				(width 0.15)
				(type solid)
			)
			(layer "F.Fab")
		)
		(fp_line
			(start -2.25 -8.8)
			(end -2.25 5.5)
			(stroke
				(width 0.15)
				(type solid)
			)
			(layer "F.Fab")
		)
		(fp_line
			(start 2.25 5.5)
			(end 2.25 -8.8)
			(stroke
				(width 0.15)
				(type solid)
			)
			(layer "F.Fab")
		)
		(fp_line
			(start -2.25 5.5)
			(end 2.25 5.5)
			(stroke
				(width 0.15)
				(type solid)
			)
			(layer "F.Fab")
		)
		(fp_text user "${REFERENCE}"
			(at -5.47 8.5 90)
			(layer "F.Fab")
			(effects
				(font
					(size 0.7 0.7)
					(thickness 0.15)
				)
				(justify left bottom)
			)
		)
		(fp_text user "License: Apache-2.0"
			(at -5.47 10.9 90)
			(layer "F.Fab")
			(effects
				(font
					(size 0.7 0.7)
					(thickness 0.15)
				)
				(justify left bottom)
			)
		)
		(fp_text user "Author: Antmicro"
			(at -5.47 9.7 90)
			(layer "F.Fab")
			(effects
				(font
					(size 0.7 0.7)
					(thickness 0.15)
				)
				(justify left bottom)
			)
		)
		(pad "" np_thru_hole circle
			(at 0 -7.6 90)
			(size 1.1 1.1)
			(drill 1.1)
			(layers "*.Cu" "*.Mask")
		)
		(pad "" np_thru_hole circle
			(at 0 0 90)
			(size 1 1)
			(drill 1)
			(layers "*.Cu" "*.Mask")
		)
		(pad "A1" smd rect
			(at 1.1375 -6.525 180)
			(size 0.25 1.625)
			(layers "F.Cu" "F.Mask" "F.Paste")
			(net 1 "GND")
			(pinfunction "GND")
			(pintype "power_in")
		)
		(pad "A2" smd rect
			(at 1.1375 -6.025 180)
			(size 0.25 1.625)
			(layers "F.Cu" "F.Mask" "F.Paste")
			(net 215 "/Recovery USB/USBC2_CONN_TX1_N")
			(pinfunction "TX_{1}+")
			(pintype "bidirectional")
		)
		(pad "A3" smd rect
			(at 1.1375 -5.525 180)
			(size 0.25 1.625)
			(layers "F.Cu" "F.Mask" "F.Paste")
			(net 245 "/Recovery USB/USBC2_CONN_TX1_P")
			(pinfunction "TX_{1}-")
			(pintype "bidirectional")
		)
		(pad "A4" smd rect
			(at 1.1375 -5.025 180)
			(size 0.25 1.625)
			(layers "F.Cu" "F.Mask" "F.Paste")
			(net 287 "/Recovery USB/USBC2_VBUS")
			(pinfunction "VBUS")
			(pintype "power_in")
		)
		(pad "A5" smd rect
			(at 1.1375 -4.525 180)
			(size 0.25 1.625)
			(layers "F.Cu" "F.Mask" "F.Paste")
			(net 806 "/Recovery USB/USBC2_CC1")
			(pinfunction "CC_{1}")
			(pintype "bidirectional")
		)
		(pad "A6" smd rect
			(at 1.1375 -4.025 180)
			(size 0.25 1.625)
			(layers "F.Cu" "F.Mask" "F.Paste")
			(net 766 "/Recovery USB/USB0.D+")
			(pinfunction "D_{A}+")
			(pintype "bidirectional")
		)
		(pad "A7" smd rect
			(at 1.1375 -3.525 180)
			(size 0.25 1.625)
			(layers "F.Cu" "F.Mask" "F.Paste")
			(net 698 "/Recovery USB/USB0.D-")
			(pinfunction "D_{A}-")
			(pintype "bidirectional")
		)
		(pad "A8" smd rect
			(at 1.1375 -3.025 180)
			(size 0.25 1.625)
			(layers "F.Cu" "F.Mask" "F.Paste")
			(net 803 "unconnected-(J3-SBU_{1}-PadA8)")
			(pinfunction "SBU_{1}")
			(pintype "bidirectional+no_connect")
		)
		(pad "A9" smd rect
			(at 1.1375 -2.525 180)
			(size 0.25 1.625)
			(layers "F.Cu" "F.Mask" "F.Paste")
			(net 287 "/Recovery USB/USBC2_VBUS")
			(pinfunction "VBUS")
			(pintype "passive")
		)
		(pad "A10" smd rect
			(at 1.1375 -2.025 180)
			(size 0.25 1.625)
			(layers "F.Cu" "F.Mask" "F.Paste")
			(net 804 "/Recovery USB/USBC2_RX2_P")
			(pinfunction "RX_{2}-")
			(pintype "bidirectional")
		)
		(pad "A11" smd rect
			(at 1.1375 -1.525 180)
			(size 0.25 1.625)
			(layers "F.Cu" "F.Mask" "F.Paste")
			(net 807 "/Recovery USB/USBC2_RX2_N")
			(pinfunction "RX_{2}+")
			(pintype "bidirectional")
		)
		(pad "A12" smd rect
			(at 1.1375 -1.025 180)
			(size 0.25 1.625)
			(layers "F.Cu" "F.Mask" "F.Paste")
			(net 1 "GND")
			(pinfunction "GND")
			(pintype "passive")
		)
		(pad "B1" smd rect
			(at -1.1375 -1.025 180)
			(size 0.25 1.625)
			(layers "F.Cu" "F.Mask" "F.Paste")
			(net 1 "GND")
			(pinfunction "GND")
			(pintype "passive")
		)
		(pad "B2" smd rect
			(at -1.1375 -1.525 180)
			(size 0.25 1.625)
			(layers "F.Cu" "F.Mask" "F.Paste")
			(net 270 "/Recovery USB/USBC2_CONN_TX2_P")
			(pinfunction "TX_{2}+")
			(pintype "bidirectional")
		)
		(pad "B3" smd rect
			(at -1.1375 -2.025 180)
			(size 0.25 1.625)
			(layers "F.Cu" "F.Mask" "F.Paste")
			(net 241 "/Recovery USB/USBC2_CONN_TX2_N")
			(pinfunction "TX_{2}-")
			(pintype "bidirectional")
		)
		(pad "B4" smd rect
			(at -1.1375 -2.525 180)
			(size 0.25 1.625)
			(layers "F.Cu" "F.Mask" "F.Paste")
			(net 287 "/Recovery USB/USBC2_VBUS")
			(pinfunction "VBUS")
			(pintype "passive")
		)
		(pad "B5" smd rect
			(at -1.1375 -3.025 180)
			(size 0.25 1.625)
			(layers "F.Cu" "F.Mask" "F.Paste")
			(net 801 "/Recovery USB/USBC2_CC2")
			(pinfunction "CC_{2}")
			(pintype "bidirectional")
		)
		(pad "B6" smd rect
			(at -1.1375 -3.525 180)
			(size 0.25 1.625)
			(layers "F.Cu" "F.Mask" "F.Paste")
			(net 766 "/Recovery USB/USB0.D+")
			(pinfunction "D_{B}+")
			(pintype "bidirectional")
		)
		(pad "B7" smd rect
			(at -1.1375 -4.025 180)
			(size 0.25 1.625)
			(layers "F.Cu" "F.Mask" "F.Paste")
			(net 698 "/Recovery USB/USB0.D-")
			(pinfunction "D_{B}-")
			(pintype "bidirectional")
		)
		(pad "B8" smd rect
			(at -1.1375 -4.525 180)
			(size 0.25 1.625)
			(layers "F.Cu" "F.Mask" "F.Paste")
			(net 805 "unconnected-(J3-SBU_{2}-PadB8)")
			(pinfunction "SBU_{2}")
			(pintype "bidirectional+no_connect")
		)
		(pad "B9" smd rect
			(at -1.1375 -5.025 180)
			(size 0.25 1.625)
			(layers "F.Cu" "F.Mask" "F.Paste")
			(net 287 "/Recovery USB/USBC2_VBUS")
			(pinfunction "VBUS")
			(pintype "passive")
		)
		(pad "B10" smd rect
			(at -1.1375 -5.525 180)
			(size 0.25 1.625)
			(layers "F.Cu" "F.Mask" "F.Paste")
			(net 800 "/Recovery USB/USBC2_RX1_N")
			(pinfunction "RX_{1}-")
			(pintype "bidirectional")
		)
		(pad "B11" smd rect
			(at -1.1375 -6.025 180)
			(size 0.25 1.625)
			(layers "F.Cu" "F.Mask" "F.Paste")
			(net 802 "/Recovery USB/USBC2_RX1_P")
			(pinfunction "RX_{1}+")
			(pintype "bidirectional")
		)
		(pad "B12" smd rect
			(at -1.1375 -6.525 180)
			(size 0.25 1.625)
			(layers "F.Cu" "F.Mask" "F.Paste")
			(net 1 "GND")
			(pinfunction "GND")
			(pintype "passive")
		)
		(pad "SH" thru_hole oval
			(at -3 -7.849 90)
			(size 1 2.05)
			(drill oval 0.6 1.65)
			(layers "*.Cu" "*.Mask")
			(remove_unused_layers no)
			(net 1 "GND")
			(pinfunction "SH")
			(pintype "passive")
		)
		(pad "SH" thru_hole oval
			(at -3 0.25 90)
			(size 1 2.05)
			(drill oval 0.6 1.65)
			(layers "*.Cu" "*.Mask")
			(remove_unused_layers no)
			(net 1 "GND")
			(pinfunction "SH")
			(pintype "passive")
		)
		(pad "SH" thru_hole oval
			(at 3 -7.849 90)
			(size 1 2.05)
			(drill oval 0.6 1.65)
			(layers "*.Cu" "*.Mask")
			(remove_unused_layers no)
			(net 1 "GND")
			(pinfunction "SH")
			(pintype "passive")
		)
		(pad "SH" thru_hole oval
			(at 3 0.25 90)
			(size 1 2.05)
			(drill oval 0.6 1.65)
			(layers "*.Cu" "*.Mask")
			(remove_unused_layers no)
			(net 1 "GND")
			(pinfunction "SH")
			(pintype "passive")
		)
	)
	(footprint "antmicro-footprints:Spacer_Drill4.45mm_H4mm_9774040960R"
		(locked yes)
		(layer "F.Cu")
		(at 155.930532 57.71 90)
		(property "Reference" "H7"
			(at 1.86 -3.45 90)
			(layer "F.SilkS")
			(effects
				(font
					(size 0.7 0.7)
					(thickness 0.15)
				)
				(justify left bottom)
			)
		)
		(property "Value" "Spacer_Drill4.45mm_H4mm_9774040960R"
			(at -3.95 5.05 90)
			(layer "F.Fab")
			(effects
				(font
					(size 0.7 0.7)
					(thickness 0.15)
				)
				(justify left bottom)
			)
		)
		(property "Datasheet" "https://www.we-online.com/components/products/datasheet/9774040960R.pdf"
			(at 0 0 90)
			(layer "F.Fab")
			(effects
				(font
					(size 0.7 0.7)
					(thickness 0.15)
				)
				(justify left bottom)
			)
		)
		(property "Description" "Spacer, SMT, Non Stop, Steel, Swage Round, 6 mm x 4 mm, 3.3 mm Internal, WA-SMST Series"
			(at 0 0 90)
			(layer "F.Fab")
			(effects
				(font
					(size 0.7 0.7)
					(thickness 0.15)
				)
				(justify left bottom)
			)
		)
		(property "Manufacturer" "Würth Elektronik"
			(at 0 0 90)
			(unlocked yes)
			(layer "F.Fab")
			(hide yes)
			(effects
				(font
					(size 1 1)
					(thickness 0.15)
				)
			)
		)
		(property "MPN" "9774040960R"
			(at 0 0 90)
			(unlocked yes)
			(layer "F.Fab")
			(hide yes)
			(effects
				(font
					(size 1 1)
					(thickness 0.15)
				)
			)
		)
		(property "Author" "Antmicro"
			(at 0 0 90)
			(unlocked yes)
			(layer "F.Fab")
			(hide yes)
			(effects
				(font
					(size 1 1)
					(thickness 0.15)
				)
			)
		)
		(property "License" "Apache-2.0"
			(at 0 0 90)
			(unlocked yes)
			(layer "F.Fab")
			(hide yes)
			(effects
				(font
					(size 1 1)
					(thickness 0.15)
				)
			)
		)
		(sheetname "/SoM_Power/")
		(sheetfile "som_power.kicad_sch")
		(attr smd)
		(fp_rect
			(start -3.95 -3.95)
			(end 3.95 3.95)
			(stroke
				(width 0.05)
				(type solid)
			)
			(fill no)
			(layer "F.CrtYd")
		)
		(fp_circle
			(center 0 0)
			(end 3.25 0)
			(stroke
				(width 0.05)
				(type solid)
			)
			(fill no)
			(layer "F.CrtYd")
		)
		(fp_circle
			(center 0 0)
			(end 2.564 0)
			(stroke
				(width 0.15)
				(type solid)
			)
			(fill no)
			(layer "F.Fab")
		)
		(fp_text user "Author: Antmicro"
			(at -3.95 8.65 90)
			(layer "F.Fab")
			(effects
				(font
					(size 0.7 0.7)
					(thickness 0.15)
				)
				(justify left bottom)
			)
		)
		(fp_text user "${REFERENCE}"
			(at -3.95 7.45 90)
			(layer "F.Fab")
			(effects
				(font
					(size 0.7 0.7)
					(thickness 0.15)
				)
				(justify left bottom)
			)
		)
		(fp_text user "License: Apache-2.0"
			(at -3.95 6.25 90)
			(layer "F.Fab")
			(effects
				(font
					(size 0.7 0.7)
					(thickness 0.15)
				)
				(justify left bottom)
			)
		)
		(pad "" smd custom
			(at -2.55 -0.55 212.5)
			(size 0.1 0.1)
			(layers "F.Paste")
			(options
				(clearance outline)
				(anchor circle)
			)
			(primitives
				(gr_arc
					(start 0 0)
					(mid 0.704278 1.28373)
					(end 0.608513 2.744826)
					(width 0.7)
				)
			)
		)
		(pad "" smd custom
			(at -0.55 2.55 302.5)
			(size 0.1 0.1)
			(layers "F.Paste")
			(options
				(clearance outline)
				(anchor circle)
			)
			(primitives
				(gr_arc
					(start 0 0)
					(mid 0.704278 1.28373)
					(end 0.608513 2.744826)
					(width 0.7)
				)
			)
		)
		(pad "" smd custom
			(at 0.55 -2.55 122.5)
			(size 0.1 0.1)
			(layers "F.Paste")
			(options
				(clearance outline)
				(anchor circle)
			)
			(primitives
				(gr_arc
					(start 0 0)
					(mid 0.704278 1.28373)
					(end 0.608513 2.744826)
					(width 0.7)
				)
			)
		)
		(pad "" smd custom
			(at 2.55 0.55 32.5)
			(size 0.1 0.1)
			(layers "F.Paste")
			(options
				(clearance outline)
				(anchor circle)
			)
			(primitives
				(gr_arc
					(start 0 0)
					(mid 0.704278 1.28373)
					(end 0.608513 2.744826)
					(width 0.7)
				)
			)
		)
		(pad "1" thru_hole circle
			(at 0 0 90)
			(size 7.4 7.4)
			(drill 4.45)
			(layers "*.Cu" "*.Mask")
			(remove_unused_layers no)
			(net 1 "GND")
			(pintype "passive")
		)
	)
	(footprint "antmicro-footprints:R_0402_1005Metric"
		(layer "F.Cu")
		(at 96.45 56.87)
		(descr "Resistor SMD 0402")
		(tags "resistor SMD 0402")
		(property "Reference" "R45"
			(at -3 0.33 0)
			(layer "F.SilkS")
			(effects
				(font
					(size 0.7 0.7)
					(thickness 0.15)
				)
				(justify left bottom)
			)
		)
		(property "Value" "R_3k92_0402"
			(at -1.011843 1.772047 0)
			(layer "F.Fab")
			(effects
				(font
					(size 0.7 0.7)
					(thickness 0.15)
				)
				(justify left bottom)
			)
		)
		(property "Datasheet" "https://www.bourns.com/docs/product-datasheets/cr.pdf"
			(at 0 0 0)
			(layer "F.Fab")
			(hide yes)
			(effects
				(font
					(size 1.27 1.27)
					(thickness 0.15)
				)
			)
		)
		(property "Description" "SMD Chip Resistor, 3.92 kohm, ± 1%, 100 mW, 0402 [1005 Metric], Thick Film, Precision"
			(at 0 0 0)
			(layer "F.Fab")
			(hide yes)
			(effects
				(font
					(size 1.27 1.27)
					(thickness 0.15)
				)
			)
		)
		(property "MPN" "CR0402-FX-3921GLF"
			(at 0 0 0)
			(unlocked yes)
			(layer "F.Fab")
			(hide yes)
			(effects
				(font
					(size 1 1)
					(thickness 0.15)
				)
			)
		)
		(property "Manufacturer" "Bourns"
			(at 0 0 0)
			(unlocked yes)
			(layer "F.Fab")
			(hide yes)
			(effects
				(font
					(size 1 1)
					(thickness 0.15)
				)
			)
		)
		(property "License" "Apache-2.0"
			(at 0 0 0)
			(unlocked yes)
			(layer "F.Fab")
			(hide yes)
			(effects
				(font
					(size 1 1)
					(thickness 0.15)
				)
			)
		)
		(property "Author" "Antmicro"
			(at 0 0 0)
			(unlocked yes)
			(layer "F.Fab")
			(hide yes)
			(effects
				(font
					(size 1 1)
					(thickness 0.15)
				)
			)
		)
		(property "Val" "3k92"
			(at 0 0 0)
			(unlocked yes)
			(layer "F.Fab")
			(hide yes)
			(effects
				(font
					(size 1 1)
					(thickness 0.15)
				)
			)
		)
		(property "Tolerance" "1%"
			(at 0 0 0)
			(unlocked yes)
			(layer "F.Fab")
			(hide yes)
			(effects
				(font
					(size 1 1)
					(thickness 0.15)
				)
			)
		)
		(sheetname "/SoM_Power/")
		(sheetfile "som_power.kicad_sch")
		(attr smd)
		(fp_rect
			(start -0.925 -0.47)
			(end 0.925 0.47)
			(stroke
				(width 0.05)
				(type default)
			)
			(fill no)
			(layer "F.CrtYd")
		)
		(fp_rect
			(start -0.5 -0.25)
			(end 0.5 0.25)
			(stroke
				(width 0.15)
				(type solid)
			)
			(fill no)
			(layer "F.Fab")
		)
		(fp_text user "${REFERENCE}"
			(at -0.95 3.168 0)
			(layer "F.Fab")
			(effects
				(font
					(size 0.7 0.7)
					(thickness 0.15)
				)
				(justify left bottom)
			)
		)
		(fp_text user "License: Apache-2.0"
			(at -0.95 5.169 0)
			(layer "F.Fab")
			(effects
				(font
					(size 0.7 0.7)
					(thickness 0.15)
				)
				(justify left bottom)
			)
		)
		(fp_text user "Author: Antmicro"
			(at -0.95 4.169 0)
			(layer "F.Fab")
			(effects
				(font
					(size 0.7 0.7)
					(thickness 0.15)
				)
				(justify left bottom)
			)
		)
		(pad "1" smd roundrect
			(at -0.48 0)
			(size 0.59 0.64)
			(layers "F.Cu" "F.Mask" "F.Paste")
			(roundrect_rratio 0.25)
			(net 1380 "Net-(U3-DIV)")
			(pintype "passive")
		)
		(pad "2" smd roundrect
			(at 0.48 0)
			(size 0.59 0.64)
			(layers "F.Cu" "F.Mask" "F.Paste")
			(roundrect_rratio 0.25)
			(net 4 "+3V3_AON")
			(pintype "passive")
		)
	)
	(footprint "antmicro-footprints:C_0402_1005Metric"
		(layer "F.Cu")
		(at 130.549999 59.47)
		(descr "Capacitor SMD 0402")
		(tags "capacitor SMD 0402")
		(property "Reference" "C377"
			(at 0.920001 0.01 0)
			(layer "F.SilkS")
			(effects
				(font
					(size 0.7 0.7)
					(thickness 0.15)
				)
				(justify left bottom)
			)
		)
		(property "Value" "C_100n_0402"
			(at -1.022927 2.155213 0)
			(layer "F.Fab")
			(effects
				(font
					(size 0.7 0.7)
					(thickness 0.15)
				)
				(justify left bottom)
			)
		)
		(property "Datasheet" "https://www.murata.com/products/productdetail?partno=GRM155R61H104KE14%23"
			(at 0 0 0)
			(layer "F.Fab")
			(hide yes)
			(effects
				(font
					(size 1.27 1.27)
					(thickness 0.15)
				)
			)
		)
		(property "Description" "SMD Multilayer Ceramic Capacitor, 0.1 µF, 50 V, 0402 [1005 Metric], ± 10%, X5R, GRM Series"
			(at 0 0 0)
			(layer "F.Fab")
			(hide yes)
			(effects
				(font
					(size 1.27 1.27)
					(thickness 0.15)
				)
			)
		)
		(property "Manufacturer" "Murata"
			(at 0 0 0)
			(unlocked yes)
			(layer "F.Fab")
			(hide yes)
			(effects
				(font
					(size 1 1)
					(thickness 0.15)
				)
			)
		)
		(property "MPN" "GRM155R61H104KE14D"
			(at 0 0 0)
			(unlocked yes)
			(layer "F.Fab")
			(hide yes)
			(effects
				(font
					(size 1 1)
					(thickness 0.15)
				)
			)
		)
		(property "Val" "100n"
			(at 0 0 0)
			(unlocked yes)
			(layer "F.Fab")
			(hide yes)
			(effects
				(font
					(size 1 1)
					(thickness 0.15)
				)
			)
		)
		(property "License" "Apache-2.0"
			(at 0 0 0)
			(unlocked yes)
			(layer "F.Fab")
			(hide yes)
			(effects
				(font
					(size 1 1)
					(thickness 0.15)
				)
			)
		)
		(property "Author" "Antmicro"
			(at 0 0 0)
			(unlocked yes)
			(layer "F.Fab")
			(hide yes)
			(effects
				(font
					(size 1 1)
					(thickness 0.15)
				)
			)
		)
		(property "Voltage" "50V"
			(at 0 0 0)
			(unlocked yes)
			(layer "F.Fab")
			(hide yes)
			(effects
				(font
					(size 1 1)
					(thickness 0.15)
				)
			)
		)
		(property "Dielectric" "X5R"
			(at 0 0 0)
			(unlocked yes)
			(layer "F.Fab")
			(hide yes)
			(effects
				(font
					(size 1 1)
					(thickness 0.15)
				)
			)
		)
		(sheetname "/DCDC/")
		(sheetfile "dcdc.kicad_sch")
		(attr smd)
		(fp_poly
			(pts
				(xy -0.925 -0.47) (xy 0.925 -0.47) (xy 0.925 0.47) (xy -0.925 0.47)
			)
			(stroke
				(width 0.05)
				(type default)
			)
			(fill no)
			(layer "F.CrtYd")
		)
		(fp_line
			(start -0.494 -0.25)
			(end 0.504 -0.25)
			(stroke
				(width 0.15)
				(type solid)
			)
			(layer "F.Fab")
		)
		(fp_line
			(start -0.494 0.248)
			(end -0.494 -0.25)
			(stroke
				(width 0.15)
				(type solid)
			)
			(layer "F.Fab")
		)
		(fp_line
			(start 0.504 -0.25)
			(end 0.504 0.248)
			(stroke
				(width 0.15)
				(type solid)
			)
			(layer "F.Fab")
		)
		(fp_line
			(start 0.504 0.248)
			(end -0.494 0.248)
			(stroke
				(width 0.15)
				(type solid)
			)
			(layer "F.Fab")
		)
		(fp_text user "${REFERENCE}"
			(at -0.939 4.599 0)
			(layer "F.Fab")
			(effects
				(font
					(size 0.7 0.7)
					(thickness 0.15)
				)
				(justify left bottom)
			)
		)
		(fp_text user "License: Apache-2.0"
			(at -0.939 5.799 0)
			(layer "F.Fab")
			(effects
				(font
					(size 0.7 0.7)
					(thickness 0.15)
				)
				(justify left bottom)
			)
		)
		(fp_text user "Author: Antmicro"
			(at -0.939 3.399 0)
			(layer "F.Fab")
			(effects
				(font
					(size 0.7 0.7)
					(thickness 0.15)
				)
				(justify left bottom)
			)
		)
		(pad "1" smd roundrect
			(at -0.48 0)
			(size 0.59 0.64)
			(layers "F.Cu" "F.Mask" "F.Paste")
			(roundrect_rratio 0.25)
			(net 1277 "/DCDC/5V_{AON}_PHASE")
			(pintype "passive")
		)
		(pad "2" smd roundrect
			(at 0.48 0)
			(size 0.59 0.64)
			(layers "F.Cu" "F.Mask" "F.Paste")
			(roundrect_rratio 0.25)
			(net 1276 "/DCDC/5V_{AON}_BOOT")
			(pintype "passive")
		)
	)
	(footprint "antmicro-footprints:MLP44-24L_4x4x0.75mm"
		(layer "F.Cu")
		(at 181 111)
		(property "Reference" "U12"
			(at 0.6 3.456 0)
			(layer "F.SilkS")
			(effects
				(font
					(size 0.7 0.7)
					(thickness 0.15)
				)
				(justify left bottom)
			)
		)
		(property "Value" "SIC437AED-T1-GE3"
			(at -2.7 3.6 0)
			(layer "F.Fab")
			(effects
				(font
					(size 0.7 0.7)
					(thickness 0.15)
				)
				(justify left bottom)
			)
		)
		(property "Datasheet" "https://www.vishay.com/docs/75921/sic437.pdf"
			(at 0 0 0)
			(layer "F.Fab")
			(hide yes)
			(effects
				(font
					(size 1.27 1.27)
					(thickness 0.15)
				)
			)
		)
		(property "Description" "DC/DC Buck Step Down Regulator Adjustable, 4.5-28V In, 0.6V to 20V/12A Out, 1MHz, PowerPAK MLP44-24"
			(at 0 0 0)
			(layer "F.Fab")
			(hide yes)
			(effects
				(font
					(size 1.27 1.27)
					(thickness 0.15)
				)
			)
		)
		(property "Manufacturer" "Vishay"
			(at 0 0 0)
			(unlocked yes)
			(layer "F.Fab")
			(hide yes)
			(effects
				(font
					(size 1 1)
					(thickness 0.15)
				)
			)
		)
		(property "MPN" "SIC437AED-T1-GE3"
			(at 0 0 0)
			(unlocked yes)
			(layer "F.Fab")
			(hide yes)
			(effects
				(font
					(size 1 1)
					(thickness 0.15)
				)
			)
		)
		(property "Author" "Antmicro"
			(at 0 0 0)
			(unlocked yes)
			(layer "F.Fab")
			(hide yes)
			(effects
				(font
					(size 1 1)
					(thickness 0.15)
				)
			)
		)
		(property "License" "Apache-2.0"
			(at 0 0 0)
			(unlocked yes)
			(layer "F.Fab")
			(hide yes)
			(effects
				(font
					(size 1 1)
					(thickness 0.15)
				)
			)
		)
		(sheetname "/DCDC/")
		(sheetfile "dcdc.kicad_sch")
		(attr smd)
		(net_tie_pad_groups "1,2,26" "3,4,27" "5,6,7,8,9")
		(fp_line
			(start -2.11 -1.38)
			(end -2.11 -2.1)
			(stroke
				(width 0.15)
				(type solid)
			)
			(layer "F.SilkS")
		)
		(fp_line
			(start -2.11 2.11)
			(end -2.11 1.39)
			(stroke
				(width 0.15)
				(type solid)
			)
			(layer "F.SilkS")
		)
		(fp_line
			(start -1.89 -2.1)
			(end -2.11 -2.1)
			(stroke
				(width 0.15)
				(type solid)
			)
			(layer "F.SilkS")
		)
		(fp_line
			(start -1.89 2.11)
			(end -2.11 2.11)
			(stroke
				(width 0.15)
				(type solid)
			)
			(layer "F.SilkS")
		)
		(fp_line
			(start 1.44 2.11)
			(end 2.11 2.11)
			(stroke
				(width 0.15)
				(type solid)
			)
			(layer "F.SilkS")
		)
		(fp_line
			(start 1.89 -2.11)
			(end 2.11 -2.11)
			(stroke
				(width 0.15)
				(type solid)
			)
			(layer "F.SilkS")
		)
		(fp_line
			(start 2.11 -2.11)
			(end 2.11 -1.69)
			(stroke
				(width 0.15)
				(type solid)
			)
			(layer "F.SilkS")
		)
		(fp_line
			(start 2.11 2.11)
			(end 2.11 1.84)
			(stroke
				(width 0.15)
				(type solid)
			)
			(layer "F.SilkS")
		)
		(fp_circle
			(center -2.25 -1.15)
			(end -2.2 -1.15)
			(stroke
				(width 0.15)
				(type solid)
			)
			(fill yes)
			(layer "F.SilkS")
		)
		(fp_line
			(start -2.55 -2.55)
			(end 2.55 -2.55)
			(stroke
				(width 0.05)
				(type solid)
			)
			(layer "F.CrtYd")
		)
		(fp_line
			(start -2.55 2.55)
			(end -2.55 -2.55)
			(stroke
				(width 0.05)
				(type solid)
			)
			(layer "F.CrtYd")
		)
		(fp_line
			(start 2.55 -2.55)
			(end 2.55 2.55)
			(stroke
				(width 0.05)
				(type solid)
			)
			(layer "F.CrtYd")
		)
		(fp_line
			(start 2.55 2.55)
			(end -2.55 2.55)
			(stroke
				(width 0.05)
				(type solid)
			)
			(layer "F.CrtYd")
		)
		(fp_line
			(start -2 -1)
			(end -2 2)
			(stroke
				(width 0.15)
				(type solid)
			)
			(layer "F.Fab")
		)
		(fp_line
			(start -2 2)
			(end 2 2)
			(stroke
				(width 0.15)
				(type solid)
			)
			(layer "F.Fab")
		)
		(fp_line
			(start -1 -2)
			(end -2 -1)
			(stroke
				(width 0.15)
				(type solid)
			)
			(layer "F.Fab")
		)
		(fp_line
			(start 2 -2)
			(end -1 -2)
			(stroke
				(width 0.15)
				(type solid)
			)
			(layer "F.Fab")
		)
		(fp_line
			(start 2 2)
			(end 2 -2)
			(stroke
				(width 0.15)
				(type solid)
			)
			(layer "F.Fab")
		)
		(fp_text user "License: Apache-2.0"
			(at -2.7 5.6 0)
			(layer "F.Fab")
			(effects
				(font
					(size 0.7 0.7)
					(thickness 0.15)
				)
				(justify left bottom)
			)
		)
		(fp_text user "${REFERENCE}"
			(at -2.7 6.8 0)
			(layer "F.Fab")
			(effects
				(font
					(size 0.7 0.7)
					(thickness 0.15)
				)
				(justify left bottom)
			)
		)
		(fp_text user "Author: Antmicro"
			(at -2.7 8 0)
			(layer "F.Fab")
			(effects
				(font
					(size 0.7 0.7)
					(thickness 0.15)
				)
				(justify left bottom)
			)
		)
		(pad "1" smd roundrect
			(at -1.94 -0.825 90)
			(size 0.3 0.725)
			(layers "F.Cu" "F.Mask" "F.Paste")
			(roundrect_rratio 0.25)
			(net 13 "VCC")
			(pinfunction "V_{IN}")
			(pintype "power_in")
		)
		(pad "2" smd roundrect
			(at -1.94 -0.375 90)
			(size 0.3 0.725)
			(layers "F.Cu" "F.Mask" "F.Paste")
			(roundrect_rratio 0.25)
			(net 13 "VCC")
			(pinfunction "V_{IN}")
			(pintype "passive")
		)
		(pad "3" smd roundrect
			(at -1.94 0.525 90)
			(size 0.3 0.725)
			(layers "F.Cu" "F.Mask" "F.Paste")
			(roundrect_rratio 0.25)
			(net 1 "GND")
			(pinfunction "P_{GND}")
			(pintype "passive")
		)
		(pad "4" smd roundrect
			(at -1.94 0.975 90)
			(size 0.3 0.725)
			(layers "F.Cu" "F.Mask" "F.Paste")
			(roundrect_rratio 0.25)
			(net 1 "GND")
			(pinfunction "P_{GND}")
			(pintype "passive")
		)
		(pad "5" smd custom
			(at -1.475 1.94)
			(size 0.3 0.3)
			(layers "F.Cu" "F.Mask" "F.Paste")
			(net 1181 "/DCDC/5V_SW")
			(pinfunction "SW")
			(pintype "passive")
			(options
				(clearance outline)
				(anchor circle)
			)
			(primitives
				(gr_poly
					(pts
						(xy -0.15 -0.2875) (xy -0.144291 -0.316201) (xy -0.128033 -0.340533) (xy -0.103701 -0.356791)
						(xy -0.075 -0.3625) (xy 0.075 -0.3625) (xy 0.103701 -0.356791) (xy 0.128033 -0.340533) (xy 0.144291 -0.316201)
						(xy 0.15 -0.2875) (xy 0.15 0.2875) (xy 0.144291 0.316201) (xy 0.128033 0.340533) (xy 0.103701 0.356791)
						(xy 0.075 0.3625) (xy -0.075 0.3625) (xy -0.103701 0.356791) (xy -0.128033 0.340533) (xy -0.144291 0.316201)
						(xy -0.15 0.2875)
					)
					(width 0)
					(fill yes)
				)
				(gr_poly
					(pts
						(xy -0.15 -0.3625) (xy 2.2 -0.3625) (xy 2.2 -0.0875) (xy -0.15 -0.0875)
					)
					(width 0)
					(fill yes)
				)
			)
		)
		(pad "6" smd roundrect
			(at -1.025 1.94)
			(size 0.3 0.725)
			(layers "F.Cu" "F.Mask" "F.Paste")
			(roundrect_rratio 0.25)
			(net 1181 "/DCDC/5V_SW")
			(pinfunction "SW")
			(pintype "passive")
		)
		(pad "7" smd roundrect
			(at -0.575 1.94)
			(size 0.3 0.725)
			(layers "F.Cu" "F.Mask" "F.Paste")
			(roundrect_rratio 0.25)
			(net 1181 "/DCDC/5V_SW")
			(pinfunction "SW")
			(pintype "passive")
		)
		(pad "8" smd roundrect
			(at 0.125 1.94)
			(size 0.3 0.725)
			(layers "F.Cu" "F.Mask" "F.Paste")
			(roundrect_rratio 0.25)
			(net 1181 "/DCDC/5V_SW")
			(pinfunction "SW")
			(pintype "passive")
		)
		(pad "9" smd roundrect
			(at 0.575 1.94)
			(size 0.3 0.725)
			(layers "F.Cu" "F.Mask" "F.Paste")
			(roundrect_rratio 0.25)
			(net 1181 "/DCDC/5V_SW")
			(pinfunction "SW")
			(pintype "passive")
		)
		(pad "10" smd roundrect
			(at 1.025 1.935)
			(size 0.3 0.725)
			(layers "F.Cu" "F.Mask" "F.Paste")
			(roundrect_rratio 0.25)
			(net 1054 "unconnected-(U12-GL-Pad10)_1")
			(pinfunction "GL")
			(pintype "passive+no_connect")
		)
		(pad "11" smd roundrect
			(at 1.94 1.425 90)
			(size 0.3 0.725)
			(layers "F.Cu" "F.Mask" "F.Paste")
			(roundrect_rratio 0.25)
			(net 1053 "unconnected-(U12-GL-Pad10)")
			(pinfunction "GL")
			(pintype "passive+no_connect")
		)
		(pad "12" smd roundrect
			(at 1.94 0.975 90)
			(size 0.3 0.725)
			(layers "F.Cu" "F.Mask" "F.Paste")
			(roundrect_rratio 0.25)
			(net 23 "/DCDC/5V_VDRV")
			(pinfunction "V_{DRV}")
			(pintype "passive")
		)
		(pad "13" smd roundrect
			(at 1.94 0.525 90)
			(size 0.3 0.725)
			(layers "F.Cu" "F.Mask" "F.Paste")
			(roundrect_rratio 0.25)
			(net 1 "GND")
			(pinfunction "P_{GND}")
			(pintype "power_in")
		)
		(pad "14" smd roundrect
			(at 1.94 0.075 90)
			(size 0.3 0.725)
			(layers "F.Cu" "F.Mask" "F.Paste")
			(roundrect_rratio 0.25)
			(net 1322 "unconnected-(U12-P_{GOOD}-Pad14)")
			(pinfunction "P_{GOOD}")
			(pintype "output+no_connect")
		)
		(pad "15" smd roundrect
			(at 1.94 -0.375 90)
			(size 0.3 0.725)
			(layers "F.Cu" "F.Mask" "F.Paste")
			(roundrect_rratio 0.25)
			(net 18 "/DCDC/5V_VDD")
			(pinfunction "V_{DD}")
			(pintype "passive")
		)
		(pad "16" smd roundrect
			(at 1.94 -0.825 90)
			(size 0.3 0.725)
			(layers "F.Cu" "F.Mask" "F.Paste")
			(roundrect_rratio 0.25)
			(net 1 "GND")
			(pinfunction "A_{GND}")
			(pintype "power_in")
		)
		(pad "17" smd roundrect
			(at 1.94 -1.275 90)
			(size 0.3 0.725)
			(layers "F.Cu" "F.Mask" "F.Paste")
			(roundrect_rratio 0.25)
			(net 1217 "/DCDC/5V_FB")
			(pinfunction "FB")
			(pintype "passive")
		)
		(pad "18" smd roundrect
			(at 1.475 -1.94)
			(size 0.3 0.725)
			(layers "F.Cu" "F.Mask" "F.Paste")
			(roundrect_rratio 0.25)
			(net 253 "/DCDC/5V_OUT")
			(pinfunction "V_{OUT}")
			(pintype "passive")
		)
		(pad "19" smd roundrect
			(at 1.025 -1.94)
			(size 0.3 0.725)
			(layers "F.Cu" "F.Mask" "F.Paste")
			(roundrect_rratio 0.25)
			(net 1293 "/DCDC/CARRIER_PWR_ON")
			(pinfunction "EN")
			(pintype "input")
		)
		(pad "20" smd roundrect
			(at 0.575 -1.94)
			(size 0.3 0.725)
			(layers "F.Cu" "F.Mask" "F.Paste")
			(roundrect_rratio 0.25)
			(net 1215 "/DCDC/5V_MODE2")
			(pinfunction "MODE2")
			(pintype "input")
		)
		(pad "21" smd roundrect
			(at 0.125 -1.94)
			(size 0.3 0.725)
			(layers "F.Cu" "F.Mask" "F.Paste")
			(roundrect_rratio 0.25)
			(net 1212 "/DCDC/5V_MODE1")
			(pinfunction "MODE1")
			(pintype "input")
		)
		(pad "22" smd roundrect
			(at -0.575 -1.94)
			(size 0.3 0.725)
			(layers "F.Cu" "F.Mask" "F.Paste")
			(roundrect_rratio 0.25)
			(net 13 "VCC")
			(pinfunction "V_{IN}")
			(pintype "passive")
		)
		(pad "23" smd roundrect
			(at -1.025 -1.94)
			(size 0.3 0.725)
			(layers "F.Cu" "F.Mask" "F.Paste")
			(roundrect_rratio 0.25)
			(net 25 "/DCDC/5V_BOOT")
			(pinfunction "BOOT")
			(pintype "passive")
		)
		(pad "24" smd roundrect
			(at -1.475 -1.94)
			(size 0.3 0.725)
			(layers "F.Cu" "F.Mask" "F.Paste")
			(roundrect_rratio 0.25)
			(net 26 "/DCDC/5V_PHASE")
			(pinfunction "PHASE")
			(pintype "passive")
		)
		(pad "25" smd rect
			(at 0.49 -0.75 180)
			(size 1.575 1.05)
			(layers "F.Cu" "F.Mask" "F.Paste")
			(net 1 "GND")
			(pinfunction "A_{GND}")
			(pintype "passive")
		)
		(pad "26" smd rect
			(at -1.175 -0.75 180)
			(size 1.15 1.05)
			(layers "F.Cu" "F.Mask" "F.Paste")
			(net 13 "VCC")
			(pinfunction "V_{IN}")
			(pintype "passive")
		)
		(pad "27" smd custom
			(at -0.75 0.775)
			(size 1 1)
			(layers "F.Cu" "F.Mask" "F.Paste")
			(net 1 "GND")
			(pinfunction "P_{GND}")
			(pintype "passive")
			(options
				(clearance outline)
				(anchor rect)
			)
			(primitives
				(gr_poly
					(pts
						(xy -1 0.5) (xy -1 -0.7) (xy 1.825 -0.7) (xy 1.825 -0.245) (xy 1.175 -0.245) (xy 1.175 0.5)
					)
					(width 0)
					(fill yes)
				)
			)
		)
		(pad "28" smd rect
			(at 0.985 0.99 180)
			(size 0.58 0.38)
			(layers "F.Cu" "F.Mask" "F.Paste")
			(net 1055 "unconnected-(U12-GL-Pad10)_2")
			(pinfunction "GL")
			(pintype "passive+no_connect")
		)
	)
	(footprint "antmicro-footprints:R_0402_1005Metric"
		(layer "F.Cu")
		(at 195.1 128.3 180)
		(descr "Resistor SMD 0402")
		(tags "resistor SMD 0402")
		(property "Reference" "R89"
			(at -1.1 -4.6 0)
			(layer "F.SilkS")
			(effects
				(font
					(size 0.7 0.7)
					(thickness 0.15)
				)
				(justify right top)
			)
		)
		(property "Value" "R_0R_0402"
			(at -1.011843 1.772047 0)
			(layer "F.Fab")
			(effects
				(font
					(size 0.7 0.7)
					(thickness 0.15)
				)
				(justify right top)
			)
		)
		(property "Datasheet" "https://industrial.panasonic.com/cdbs/www-data/pdf/RDA0000/AOA0000C301.pdf"
			(at 0 0 0)
			(layer "F.Fab")
			(hide yes)
			(effects
				(font
					(size 1.27 1.27)
					(thickness 0.15)
				)
			)
		)
		(property "Description" "SMD Chip Resistor, Jumper, 0 ohm, 100 mW, 0402 [1005 Metric], Thick Film, General Purpose"
			(at 0 0 0)
			(layer "F.Fab")
			(hide yes)
			(effects
				(font
					(size 1.27 1.27)
					(thickness 0.15)
				)
			)
		)
		(property "Manufacturer" "Panasonic"
			(at 0 0 180)
			(unlocked yes)
			(layer "F.Fab")
			(hide yes)
			(effects
				(font
					(size 1 1)
					(thickness 0.15)
				)
			)
		)
		(property "MPN" "ERJ2GE0R00X"
			(at 0 0 180)
			(unlocked yes)
			(layer "F.Fab")
			(hide yes)
			(effects
				(font
					(size 1 1)
					(thickness 0.15)
				)
			)
		)
		(property "Val" "0R"
			(at 0 0 180)
			(unlocked yes)
			(layer "F.Fab")
			(hide yes)
			(effects
				(font
					(size 1 1)
					(thickness 0.15)
				)
			)
		)
		(property "License" "Apache-2.0"
			(at 0 0 180)
			(unlocked yes)
			(layer "F.Fab")
			(hide yes)
			(effects
				(font
					(size 1 1)
					(thickness 0.15)
				)
			)
		)
		(property "Author" "Antmicro"
			(at 0 0 180)
			(unlocked yes)
			(layer "F.Fab")
			(hide yes)
			(effects
				(font
					(size 1 1)
					(thickness 0.15)
				)
			)
		)
		(property "Tolerance" "~"
			(at 0 0 180)
			(unlocked yes)
			(layer "F.Fab")
			(hide yes)
			(effects
				(font
					(size 1 1)
					(thickness 0.15)
				)
			)
		)
		(property "Current" "1A"
			(at 0 0 180)
			(unlocked yes)
			(layer "F.Fab")
			(hide yes)
			(effects
				(font
					(size 1 1)
					(thickness 0.15)
				)
			)
		)
		(sheetname "/USB Hub/")
		(sheetfile "usb_hub.kicad_sch")
		(attr smd exclude_from_pos_files exclude_from_bom dnp)
		(fp_rect
			(start -0.925 -0.47)
			(end 0.925 0.47)
			(stroke
				(width 0.05)
				(type default)
			)
			(fill no)
			(layer "F.CrtYd")
		)
		(fp_rect
			(start -0.5 -0.25)
			(end 0.5 0.25)
			(stroke
				(width 0.15)
				(type solid)
			)
			(fill no)
			(layer "F.Fab")
		)
		(fp_text user "${REFERENCE}"
			(at -0.95 3.168 0)
			(layer "F.Fab")
			(effects
				(font
					(size 0.7 0.7)
					(thickness 0.15)
				)
				(justify right top)
			)
		)
		(fp_text user "Author: Antmicro"
			(at -0.95 4.169 0)
			(layer "F.Fab")
			(effects
				(font
					(size 0.7 0.7)
					(thickness 0.15)
				)
				(justify right top)
			)
		)
		(fp_text user "License: Apache-2.0"
			(at -0.95 5.169 0)
			(layer "F.Fab")
			(effects
				(font
					(size 0.7 0.7)
					(thickness 0.15)
				)
				(justify right top)
			)
		)
		(pad "1" smd roundrect
			(at -0.48 0 180)
			(size 0.59 0.64)
			(layers "F.Cu" "F.Mask" "F.Paste")
			(roundrect_rratio 0.25)
			(net 927 "/USB Hub/HUB_SPI_CLK")
			(pintype "passive")
		)
		(pad "2" smd roundrect
			(at 0.48 0 180)
			(size 0.59 0.64)
			(layers "F.Cu" "F.Mask" "F.Paste")
			(roundrect_rratio 0.25)
			(net 928 "/USB Debug, PD/SPI_{HUB_DEBUG}.SCK")
			(pintype "passive")
		)
	)
	(footprint "antmicro-footprints:R_0402_1005Metric"
		(layer "F.Cu")
		(at 178.194468 86.455 180)
		(descr "Resistor SMD 0402")
		(tags "resistor SMD 0402")
		(property "Reference" "R26"
			(at -1.06 2.14 0)
			(layer "F.SilkS")
			(effects
				(font
					(size 0.7 0.7)
					(thickness 0.15)
				)
				(justify right top)
			)
		)
		(property "Value" "R_499k_0402"
			(at -1.011843 1.772047 0)
			(layer "F.Fab")
			(effects
				(font
					(size 0.7 0.7)
					(thickness 0.15)
				)
				(justify right top)
			)
		)
		(property "Datasheet" "https://www.mouser.com/datasheet/2/54/cr-1858361.pdf"
			(at 0 0 0)
			(layer "F.Fab")
			(hide yes)
			(effects
				(font
					(size 1.27 1.27)
					(thickness 0.15)
				)
			)
		)
		(property "Description" "SMD Chip Resistor, 499 kohm, ± 1%, 63 mW, 0402 [1005 Metric], Thick Film, General Purpose"
			(at 0 0 0)
			(layer "F.Fab")
			(hide yes)
			(effects
				(font
					(size 1.27 1.27)
					(thickness 0.15)
				)
			)
		)
		(property "MPN" "CR0402-FX-4993GLF"
			(at 0 0 180)
			(unlocked yes)
			(layer "F.Fab")
			(hide yes)
			(effects
				(font
					(size 1 1)
					(thickness 0.15)
				)
			)
		)
		(property "Manufacturer" "Bourns"
			(at 0 0 180)
			(unlocked yes)
			(layer "F.Fab")
			(hide yes)
			(effects
				(font
					(size 1 1)
					(thickness 0.15)
				)
			)
		)
		(property "License" "Apache-2.0"
			(at 0 0 180)
			(unlocked yes)
			(layer "F.Fab")
			(hide yes)
			(effects
				(font
					(size 1 1)
					(thickness 0.15)
				)
			)
		)
		(property "Author" "Antmicro"
			(at 0 0 180)
			(unlocked yes)
			(layer "F.Fab")
			(hide yes)
			(effects
				(font
					(size 1 1)
					(thickness 0.15)
				)
			)
		)
		(property "Val" "499k"
			(at 0 0 180)
			(unlocked yes)
			(layer "F.Fab")
			(hide yes)
			(effects
				(font
					(size 1 1)
					(thickness 0.15)
				)
			)
		)
		(property "Tolerance" "1%"
			(at 0 0 180)
			(unlocked yes)
			(layer "F.Fab")
			(hide yes)
			(effects
				(font
					(size 1 1)
					(thickness 0.15)
				)
			)
		)
		(component_classes
			(class "DCDC_SOM")
		)
		(sheetname "/DCDC/")
		(sheetfile "dcdc.kicad_sch")
		(attr smd exclude_from_pos_files exclude_from_bom dnp)
		(fp_rect
			(start -0.925 -0.47)
			(end 0.925 0.47)
			(stroke
				(width 0.05)
				(type default)
			)
			(fill no)
			(layer "F.CrtYd")
		)
		(fp_rect
			(start -0.5 -0.25)
			(end 0.5 0.25)
			(stroke
				(width 0.15)
				(type solid)
			)
			(fill no)
			(layer "F.Fab")
		)
		(fp_text user "${REFERENCE}"
			(at -0.95 3.168 0)
			(layer "F.Fab")
			(effects
				(font
					(size 0.7 0.7)
					(thickness 0.15)
				)
				(justify right top)
			)
		)
		(fp_text user "License: Apache-2.0"
			(at -0.95 5.169 0)
			(layer "F.Fab")
			(effects
				(font
					(size 0.7 0.7)
					(thickness 0.15)
				)
				(justify right top)
			)
		)
		(fp_text user "Author: Antmicro"
			(at -0.95 4.169 0)
			(layer "F.Fab")
			(effects
				(font
					(size 0.7 0.7)
					(thickness 0.15)
				)
				(justify right top)
			)
		)
		(pad "1" smd roundrect
			(at -0.48 0 180)
			(size 0.59 0.64)
			(layers "F.Cu" "F.Mask" "F.Paste")
			(roundrect_rratio 0.25)
			(net 1207 "/DCDC/16V_MODE1")
			(pintype "passive")
		)
		(pad "2" smd roundrect
			(at 0.48 0 180)
			(size 0.59 0.64)
			(layers "F.Cu" "F.Mask" "F.Paste")
			(roundrect_rratio 0.25)
			(net 896 "/DCDC/16V_VDD")
			(pintype "passive")
		)
	)
	(footprint "antmicro-footprints:C_0402_1005Metric"
		(layer "F.Cu")
		(at 204.75 87.970856 180)
		(descr "Capacitor SMD 0402")
		(tags "capacitor SMD 0402")
		(property "Reference" "C315"
			(at 5.15 -0.429144 180)
			(layer "F.SilkS")
			(effects
				(font
					(size 0.7 0.7)
					(thickness 0.15)
				)
				(justify left bottom)
			)
		)
		(property "Value" "C_100n_0402"
			(at -1.022927 2.155213 180)
			(layer "F.Fab")
			(effects
				(font
					(size 0.7 0.7)
					(thickness 0.15)
				)
				(justify left bottom)
			)
		)
		(property "Datasheet" "https://www.murata.com/products/productdetail?partno=GRM155R61H104KE14%23"
			(at 0 0 180)
			(layer "F.Fab")
			(hide yes)
			(effects
				(font
					(size 1.27 1.27)
					(thickness 0.15)
				)
			)
		)
		(property "Description" "SMD Multilayer Ceramic Capacitor, 0.1 µF, 50 V, 0402 [1005 Metric], ± 10%, X5R, GRM Series"
			(at 0 0 180)
			(layer "F.Fab")
			(hide yes)
			(effects
				(font
					(size 1.27 1.27)
					(thickness 0.15)
				)
			)
		)
		(property "Manufacturer" "Murata"
			(at 0 0 180)
			(unlocked yes)
			(layer "F.Fab")
			(hide yes)
			(effects
				(font
					(size 1 1)
					(thickness 0.15)
				)
			)
		)
		(property "MPN" "GRM155R61H104KE14D"
			(at 0 0 180)
			(unlocked yes)
			(layer "F.Fab")
			(hide yes)
			(effects
				(font
					(size 1 1)
					(thickness 0.15)
				)
			)
		)
		(property "Val" "100n"
			(at 0 0 180)
			(unlocked yes)
			(layer "F.Fab")
			(hide yes)
			(effects
				(font
					(size 1 1)
					(thickness 0.15)
				)
			)
		)
		(property "License" "Apache-2.0"
			(at 0 0 180)
			(unlocked yes)
			(layer "F.Fab")
			(hide yes)
			(effects
				(font
					(size 1 1)
					(thickness 0.15)
				)
			)
		)
		(property "Author" "Antmicro"
			(at 0 0 180)
			(unlocked yes)
			(layer "F.Fab")
			(hide yes)
			(effects
				(font
					(size 1 1)
					(thickness 0.15)
				)
			)
		)
		(property "Voltage" "50V"
			(at 0 0 180)
			(unlocked yes)
			(layer "F.Fab")
			(hide yes)
			(effects
				(font
					(size 1 1)
					(thickness 0.15)
				)
			)
		)
		(property "Dielectric" "X5R"
			(at 0 0 180)
			(unlocked yes)
			(layer "F.Fab")
			(hide yes)
			(effects
				(font
					(size 1 1)
					(thickness 0.15)
				)
			)
		)
		(sheetname "/SoM_IO2/")
		(sheetfile "som_io2.kicad_sch")
		(attr smd)
		(fp_rect
			(start -0.925 -0.47)
			(end 0.925 0.47)
			(stroke
				(width 0.05)
				(type default)
			)
			(fill no)
			(layer "F.CrtYd")
		)
		(fp_line
			(start 0.504 0.248)
			(end -0.494 0.248)
			(stroke
				(width 0.15)
				(type solid)
			)
			(layer "F.Fab")
		)
		(fp_line
			(start 0.504 -0.25)
			(end 0.504 0.248)
			(stroke
				(width 0.15)
				(type solid)
			)
			(layer "F.Fab")
		)
		(fp_line
			(start -0.494 0.248)
			(end -0.494 -0.25)
			(stroke
				(width 0.15)
				(type solid)
			)
			(layer "F.Fab")
		)
		(fp_line
			(start -0.494 -0.25)
			(end 0.504 -0.25)
			(stroke
				(width 0.15)
				(type solid)
			)
			(layer "F.Fab")
		)
		(fp_text user "${REFERENCE}"
			(at -0.939 4.599 180)
			(layer "F.Fab")
			(effects
				(font
					(size 0.7 0.7)
					(thickness 0.15)
				)
				(justify left bottom)
			)
		)
		(fp_text user "Author: Antmicro"
			(at -0.939 3.399 180)
			(layer "F.Fab")
			(effects
				(font
					(size 0.7 0.7)
					(thickness 0.15)
				)
				(justify left bottom)
			)
		)
		(fp_text user "License: Apache-2.0"
			(at -0.939 5.799 180)
			(layer "F.Fab")
			(effects
				(font
					(size 0.7 0.7)
					(thickness 0.15)
				)
				(justify left bottom)
			)
		)
		(pad "1" smd roundrect
			(at -0.48 0 180)
			(size 0.59 0.64)
			(layers "F.Cu" "F.Mask" "F.Paste")
			(roundrect_rratio 0.25)
			(net 663 "/SoM_IO2/DP0.TX0-")
			(pintype "passive")
		)
		(pad "2" smd roundrect
			(at 0.48 0 180)
			(size 0.59 0.64)
			(layers "F.Cu" "F.Mask" "F.Paste")
			(roundrect_rratio 0.25)
			(net 575 "/SoM_IO2/DP0.TX0_C-")
			(pintype "passive")
		)
	)
	(footprint "antmicro-footprints:R_0402_1005Metric"
		(layer "F.Cu")
		(at 219.77 74.699951 180)
		(descr "Resistor SMD 0402")
		(tags "resistor SMD 0402")
		(property "Reference" "R120"
			(at 1.33 -2.685049 180)
			(layer "F.SilkS")
			(effects
				(font
					(size 0.7 0.7)
					(thickness 0.15)
				)
				(justify left bottom)
			)
		)
		(property "Value" "R_200R_0402"
			(at -1.011843 1.772047 180)
			(layer "F.Fab")
			(effects
				(font
					(size 0.7 0.7)
					(thickness 0.15)
				)
				(justify left bottom)
			)
		)
		(property "Datasheet" "https://www.bourns.com/docs/product-datasheets/cr.pdf"
			(at 0 0 180)
			(layer "F.Fab")
			(hide yes)
			(effects
				(font
					(size 1.27 1.27)
					(thickness 0.15)
				)
			)
		)
		(property "Description" "SMD Chip Resistor, 200 ohm, ± 1%, 62.5 mW, 0402 [1005 Metric], Thick Film, General Purpose"
			(at 0 0 180)
			(layer "F.Fab")
			(hide yes)
			(effects
				(font
					(size 1.27 1.27)
					(thickness 0.15)
				)
			)
		)
		(property "Manufacturer" "Bourns"
			(at 0 0 180)
			(unlocked yes)
			(layer "F.Fab")
			(hide yes)
			(effects
				(font
					(size 1 1)
					(thickness 0.15)
				)
			)
		)
		(property "MPN" "CR0402-FX-2000GLF"
			(at 0 0 180)
			(unlocked yes)
			(layer "F.Fab")
			(hide yes)
			(effects
				(font
					(size 1 1)
					(thickness 0.15)
				)
			)
		)
		(property "Val" "200R"
			(at 0 0 180)
			(unlocked yes)
			(layer "F.Fab")
			(hide yes)
			(effects
				(font
					(size 1 1)
					(thickness 0.15)
				)
			)
		)
		(property "License" "Apache-2.0"
			(at 0 0 180)
			(unlocked yes)
			(layer "F.Fab")
			(hide yes)
			(effects
				(font
					(size 1 1)
					(thickness 0.15)
				)
			)
		)
		(property "Author" "Antmicro"
			(at 0 0 180)
			(unlocked yes)
			(layer "F.Fab")
			(hide yes)
			(effects
				(font
					(size 1 1)
					(thickness 0.15)
				)
			)
		)
		(property "Tolerance" "1%"
			(at 0 0 180)
			(unlocked yes)
			(layer "F.Fab")
			(hide yes)
			(effects
				(font
					(size 1 1)
					(thickness 0.15)
				)
			)
		)
		(sheetname "/USB Debug, PD/")
		(sheetfile "usb_debug_pd.kicad_sch")
		(attr smd)
		(fp_rect
			(start -0.925 -0.47)
			(end 0.925 0.47)
			(stroke
				(width 0.05)
				(type default)
			)
			(fill no)
			(layer "F.CrtYd")
		)
		(fp_rect
			(start -0.5 -0.25)
			(end 0.5 0.25)
			(stroke
				(width 0.15)
				(type solid)
			)
			(fill no)
			(layer "F.Fab")
		)
		(fp_text user "Author: Antmicro"
			(at -0.95 4.169 180)
			(layer "F.Fab")
			(effects
				(font
					(size 0.7 0.7)
					(thickness 0.15)
				)
				(justify left bottom)
			)
		)
		(fp_text user "License: Apache-2.0"
			(at -0.95 5.169 180)
			(layer "F.Fab")
			(effects
				(font
					(size 0.7 0.7)
					(thickness 0.15)
				)
				(justify left bottom)
			)
		)
		(fp_text user "${REFERENCE}"
			(at -0.95 3.168 180)
			(layer "F.Fab")
			(effects
				(font
					(size 0.7 0.7)
					(thickness 0.15)
				)
				(justify left bottom)
			)
		)
		(pad "1" smd roundrect
			(at -0.48 0 180)
			(size 0.59 0.64)
			(layers "F.Cu" "F.Mask" "F.Paste")
			(roundrect_rratio 0.25)
			(net 538 "Net-(D21-A)")
			(pintype "passive")
		)
		(pad "2" smd roundrect
			(at 0.48 0 180)
			(size 0.59 0.64)
			(layers "F.Cu" "F.Mask" "F.Paste")
			(roundrect_rratio 0.25)
			(net 334 "/USB Debug, PD/FTDI_3V3")
			(pintype "passive")
		)
	)
	(footprint "antmicro-footprints:C_0402_1005Metric"
		(layer "F.Cu")
		(at 179.469468 139.93)
		(descr "Capacitor SMD 0402")
		(tags "capacitor SMD 0402")
		(property "Reference" "C221"
			(at -3.569468 0.17 0)
			(layer "F.SilkS")
			(effects
				(font
					(size 0.7 0.7)
					(thickness 0.15)
				)
				(justify left bottom)
			)
		)
		(property "Value" "C_100n_0402"
			(at -1.022927 2.155213 0)
			(layer "F.Fab")
			(effects
				(font
					(size 0.7 0.7)
					(thickness 0.15)
				)
				(justify left bottom)
			)
		)
		(property "Datasheet" "https://www.murata.com/products/productdetail?partno=GRM155R61H104KE14%23"
			(at 0 0 0)
			(layer "F.Fab")
			(hide yes)
			(effects
				(font
					(size 1.27 1.27)
					(thickness 0.15)
				)
			)
		)
		(property "Description" "SMD Multilayer Ceramic Capacitor, 0.1 µF, 50 V, 0402 [1005 Metric], ± 10%, X5R, GRM Series"
			(at 0 0 0)
			(layer "F.Fab")
			(hide yes)
			(effects
				(font
					(size 1.27 1.27)
					(thickness 0.15)
				)
			)
		)
		(property "Manufacturer" "Murata"
			(at 0 0 0)
			(unlocked yes)
			(layer "F.Fab")
			(hide yes)
			(effects
				(font
					(size 1 1)
					(thickness 0.15)
				)
			)
		)
		(property "MPN" "GRM155R61H104KE14D"
			(at 0 0 0)
			(unlocked yes)
			(layer "F.Fab")
			(hide yes)
			(effects
				(font
					(size 1 1)
					(thickness 0.15)
				)
			)
		)
		(property "Val" "100n"
			(at 0 0 0)
			(unlocked yes)
			(layer "F.Fab")
			(hide yes)
			(effects
				(font
					(size 1 1)
					(thickness 0.15)
				)
			)
		)
		(property "License" "Apache-2.0"
			(at 0 0 0)
			(unlocked yes)
			(layer "F.Fab")
			(hide yes)
			(effects
				(font
					(size 1 1)
					(thickness 0.15)
				)
			)
		)
		(property "Author" "Antmicro"
			(at 0 0 0)
			(unlocked yes)
			(layer "F.Fab")
			(hide yes)
			(effects
				(font
					(size 1 1)
					(thickness 0.15)
				)
			)
		)
		(property "Voltage" "50V"
			(at 0 0 0)
			(unlocked yes)
			(layer "F.Fab")
			(hide yes)
			(effects
				(font
					(size 1 1)
					(thickness 0.15)
				)
			)
		)
		(property "Dielectric" "X5R"
			(at 0 0 0)
			(unlocked yes)
			(layer "F.Fab")
			(hide yes)
			(effects
				(font
					(size 1 1)
					(thickness 0.15)
				)
			)
		)
		(sheetname "/DCDC/")
		(sheetfile "dcdc.kicad_sch")
		(attr smd)
		(fp_rect
			(start -0.925 -0.47)
			(end 0.925 0.47)
			(stroke
				(width 0.05)
				(type default)
			)
			(fill no)
			(layer "F.CrtYd")
		)
		(fp_line
			(start -0.494 -0.25)
			(end 0.504 -0.25)
			(stroke
				(width 0.15)
				(type solid)
			)
			(layer "F.Fab")
		)
		(fp_line
			(start -0.494 0.248)
			(end -0.494 -0.25)
			(stroke
				(width 0.15)
				(type solid)
			)
			(layer "F.Fab")
		)
		(fp_line
			(start 0.504 -0.25)
			(end 0.504 0.248)
			(stroke
				(width 0.15)
				(type solid)
			)
			(layer "F.Fab")
		)
		(fp_line
			(start 0.504 0.248)
			(end -0.494 0.248)
			(stroke
				(width 0.15)
				(type solid)
			)
			(layer "F.Fab")
		)
		(fp_text user "License: Apache-2.0"
			(at -0.939 5.799 0)
			(layer "F.Fab")
			(effects
				(font
					(size 0.7 0.7)
					(thickness 0.15)
				)
				(justify left bottom)
			)
		)
		(fp_text user "${REFERENCE}"
			(at -0.939 4.599 0)
			(layer "F.Fab")
			(effects
				(font
					(size 0.7 0.7)
					(thickness 0.15)
				)
				(justify left bottom)
			)
		)
		(fp_text user "Author: Antmicro"
			(at -0.939 3.399 0)
			(layer "F.Fab")
			(effects
				(font
					(size 0.7 0.7)
					(thickness 0.15)
				)
				(justify left bottom)
			)
		)
		(pad "1" smd roundrect
			(at -0.48 0)
			(size 0.59 0.64)
			(layers "F.Cu" "F.Mask" "F.Paste")
			(roundrect_rratio 0.25)
			(net 879 "/DCDC/12V_PHASE")
			(pintype "passive")
		)
		(pad "2" smd roundrect
			(at 0.48 0)
			(size 0.59 0.64)
			(layers "F.Cu" "F.Mask" "F.Paste")
			(roundrect_rratio 0.25)
			(net 585 "/DCDC/12V_BOOT")
			(pintype "passive")
		)
	)
	(footprint "antmicro-footprints:TP_SMD_0.75mm"
		(layer "F.Cu")
		(at 68.85 58.25 90)
		(property "Reference" "TP25"
			(at -0.15 0.9 180)
			(layer "F.SilkS")
			(effects
				(font
					(size 0.7 0.7)
					(thickness 0.15)
				)
				(justify left bottom)
			)
		)
		(property "Value" "TP_0.75mm_SMD"
			(at 0 1.2 90)
			(layer "F.Fab")
			(effects
				(font
					(size 0.7 0.7)
					(thickness 0.15)
				)
				(justify left bottom)
			)
		)
		(property "Description" "SMT test point"
			(at 0 0 90)
			(layer "F.Fab")
			(hide yes)
			(effects
				(font
					(size 1.27 1.27)
					(thickness 0.15)
				)
			)
		)
		(property "MPN" ""
			(at 0 0 90)
			(unlocked yes)
			(layer "F.Fab")
			(hide yes)
			(effects
				(font
					(size 1 1)
					(thickness 0.15)
				)
			)
		)
		(property "Manufacturer" ""
			(at 0 0 90)
			(unlocked yes)
			(layer "F.Fab")
			(hide yes)
			(effects
				(font
					(size 1 1)
					(thickness 0.15)
				)
			)
		)
		(property "Author" "Antmicro"
			(at 0 0 90)
			(unlocked yes)
			(layer "F.Fab")
			(hide yes)
			(effects
				(font
					(size 1 1)
					(thickness 0.15)
				)
			)
		)
		(property "License" "Apache-2.0"
			(at 0 0 90)
			(unlocked yes)
			(layer "F.Fab")
			(hide yes)
			(effects
				(font
					(size 1 1)
					(thickness 0.15)
				)
			)
		)
		(sheetname "/CSI/")
		(sheetfile "csi.kicad_sch")
		(attr exclude_from_pos_files exclude_from_bom)
		(fp_circle
			(center 0 0)
			(end 0.475 0)
			(stroke
				(width 0.05)
				(type default)
			)
			(fill no)
			(layer "F.CrtYd")
		)
		(fp_text user "${REFERENCE}"
			(at -0.4 2.7 90)
			(layer "F.Fab")
			(effects
				(font
					(size 0.7 0.7)
					(thickness 0.15)
				)
				(justify left bottom)
			)
		)
		(fp_text user "Author: Antmicro"
			(at -0.4 3.901 90)
			(layer "F.Fab")
			(effects
				(font
					(size 0.7 0.7)
					(thickness 0.15)
				)
				(justify left bottom)
			)
		)
		(fp_text user "License: Apache-2.0"
			(at -0.4 5.101 90)
			(layer "F.Fab")
			(effects
				(font
					(size 0.7 0.7)
					(thickness 0.15)
				)
				(justify left bottom)
			)
		)
		(pad "1" smd circle
			(at 0 0 90)
			(size 0.75 0.75)
			(layers "F.Cu" "F.Mask")
			(net 1049 "/CSI/MUX_I2C_6_SDA")
			(pinfunction "1")
			(pintype "passive")
		)
	)
	(footprint "antmicro-footprints:LED_0603_1608Metric_G"
		(layer "F.Cu")
		(at 235.540532 134.323 180)
		(descr "LED SMD 0603 Green")
		(tags "LED SMD 0603 Green")
		(property "Reference" "D49"
			(at -0.459468 -0.799999 0)
			(layer "F.SilkS")
			(effects
				(font
					(size 0.7 0.7)
					(thickness 0.15)
				)
				(justify right top)
			)
		)
		(property "Value" "LED_G_0603_LTST-C190GKT"
			(at -0.001 1.599 0)
			(layer "F.Fab")
			(effects
				(font
					(size 0.7 0.7)
					(thickness 0.15)
				)
				(justify right top)
			)
		)
		(property "Datasheet" "https://media.digikey.com/pdf/Data%20Sheets/Lite-On%20PDFs/LTST-C190GKT.pdf"
			(at 0 0 0)
			(layer "F.Fab")
			(hide yes)
			(effects
				(font
					(size 1.27 1.27)
					(thickness 0.15)
				)
			)
		)
		(property "Description" "LED, Green, SMD, 0603, 20 mA, 2.1 V, 569 nm"
			(at 0 0 0)
			(layer "F.Fab")
			(hide yes)
			(effects
				(font
					(size 1.27 1.27)
					(thickness 0.15)
				)
			)
		)
		(property "MPN" "LTST-C190GKT"
			(at 0 0 180)
			(unlocked yes)
			(layer "F.Fab")
			(hide yes)
			(effects
				(font
					(size 1 1)
					(thickness 0.15)
				)
			)
		)
		(property "Manufacturer" "Lite-On"
			(at 0 0 180)
			(unlocked yes)
			(layer "F.Fab")
			(hide yes)
			(effects
				(font
					(size 1 1)
					(thickness 0.15)
				)
			)
		)
		(property "Author" "Antmicro"
			(at 0 0 180)
			(unlocked yes)
			(layer "F.Fab")
			(hide yes)
			(effects
				(font
					(size 1 1)
					(thickness 0.15)
				)
			)
		)
		(property "License" "Apache-2.0"
			(at 0 0 180)
			(unlocked yes)
			(layer "F.Fab")
			(hide yes)
			(effects
				(font
					(size 1 1)
					(thickness 0.15)
				)
			)
		)
		(property "Color" "Green"
			(at 0 0 180)
			(unlocked yes)
			(layer "F.Fab")
			(hide yes)
			(effects
				(font
					(size 1 1)
					(thickness 0.15)
				)
			)
		)
		(sheetname "/USB Hub/")
		(sheetfile "usb_hub.kicad_sch")
		(attr smd)
		(fp_line
			(start 0.22 0.35)
			(end -0.22 0.35)
			(stroke
				(width 0.15)
				(type solid)
			)
			(layer "F.SilkS")
		)
		(fp_line
			(start 0.22 -0.35)
			(end -0.22 -0.35)
			(stroke
				(width 0.15)
				(type solid)
			)
			(layer "F.SilkS")
		)
		(fp_line
			(start 0.105328 0.201008)
			(end 0.105329 -0.198992)
			(stroke
				(width 0.1)
				(type solid)
			)
			(layer "F.SilkS")
		)
		(fp_line
			(start 0.105328 0.201008)
			(end -0.094672 0.001008)
			(stroke
				(width 0.1)
				(type solid)
			)
			(layer "F.SilkS")
		)
		(fp_line
			(start 0.105328 0.001008)
			(end 0.240001 0.001)
			(stroke
				(width 0.1)
				(type solid)
			)
			(layer "F.SilkS")
		)
		(fp_line
			(start -0.094672 0.201008)
			(end -0.094672 -0.198992)
			(stroke
				(width 0.1)
				(type solid)
			)
			(layer "F.SilkS")
		)
		(fp_line
			(start -0.094672 0.001008)
			(end 0.105329 -0.198992)
			(stroke
				(width 0.1)
				(type solid)
			)
			(layer "F.SilkS")
		)
		(fp_line
			(start -0.094672 0.001008)
			(end -0.24 0.001008)
			(stroke
				(width 0.1)
				(type solid)
			)
			(layer "F.SilkS")
		)
		(fp_line
			(start -1.18 -0.319)
			(end -1.18 0.321)
			(stroke
				(width 0.15)
				(type solid)
			)
			(layer "F.SilkS")
		)
		(fp_poly
			(pts
				(xy 1.25 0.65) (xy -1.25 0.65) (xy -1.25 -0.65) (xy 1.25 -0.65)
			)
			(stroke
				(width 0.05)
				(type solid)
			)
			(fill no)
			(layer "F.CrtYd")
		)
		(fp_line
			(start 0.599 0)
			(end 0.200999 0)
			(stroke
				(width 0.15)
				(type solid)
			)
			(layer "F.Fab")
		)
		(fp_line
			(start 0.201 0.2)
			(end 0.200999 0)
			(stroke
				(width 0.15)
				(type solid)
			)
			(layer "F.Fab")
		)
		(fp_line
			(start 0.201 -0.202)
			(end -0.101 0)
			(stroke
				(width 0.15)
				(type solid)
			)
			(layer "F.Fab")
		)
		(fp_line
			(start 0.200999 0)
			(end 0.201 -0.202)
			(stroke
				(width 0.15)
				(type solid)
			)
			(layer "F.Fab")
		)
		(fp_line
			(start -0.101 0)
			(end 0.201 0.2)
			(stroke
				(width 0.15)
				(type solid)
			)
			(layer "F.Fab")
		)
		(fp_line
			(start -0.199 0.2)
			(end -0.199 0.1)
			(stroke
				(width 0.15)
				(type solid)
			)
			(layer "F.Fab")
		)
		(fp_line
			(start -0.199 0)
			(end -0.597 0)
			(stroke
				(width 0.15)
				(type solid)
			)
			(layer "F.Fab")
		)
		(fp_line
			(start -0.199 -0.202)
			(end -0.199 0.1)
			(stroke
				(width 0.15)
				(type solid)
			)
			(layer "F.Fab")
		)
		(fp_poly
			(pts
				(xy 0.848 0.4) (xy -0.85 0.4) (xy -0.85 -0.402) (xy 0.848 -0.401999)
			)
			(stroke
				(width 0.15)
				(type solid)
			)
			(fill no)
			(layer "F.Fab")
		)
		(fp_text user "${REFERENCE}"
			(at -1.4224 5.999 0)
			(layer "F.Fab")
			(effects
				(font
					(size 0.7 0.7)
					(thickness 0.15)
				)
				(justify right top)
			)
		)
		(fp_text user "License: Apache-2.0"
			(at -1.4224 3.599 0)
			(layer "F.Fab")
			(effects
				(font
					(size 0.7 0.7)
					(thickness 0.15)
				)
				(justify right top)
			)
		)
		(fp_text user "Author: Antmicro"
			(at -1.4224 4.799 0)
			(layer "F.Fab")
			(effects
				(font
					(size 0.7 0.7)
					(thickness 0.15)
				)
				(justify right top)
			)
		)
		(pad "1" smd roundrect
			(at -0.7 0)
			(size 0.8 1)
			(layers "F.Cu" "F.Mask" "F.Paste")
			(roundrect_rratio 0.2)
			(net 1 "GND")
			(pinfunction "C")
			(pintype "passive")
		)
		(pad "2" smd roundrect
			(at 0.7 0)
			(size 0.8 1)
			(layers "F.Cu" "F.Mask" "F.Paste")
			(roundrect_rratio 0.2)
			(net 1390 "Net-(D49-A)")
			(pinfunction "A")
			(pintype "passive")
		)
	)
	(footprint "antmicro-footprints:R_0402_1005Metric"
		(layer "F.Cu")
		(at 232.540532 134.323 180)
		(descr "Resistor SMD 0402")
		(tags "resistor SMD 0402")
		(property "Reference" "R260"
			(at -1.122484 -0.772697 0)
			(layer "F.SilkS")
			(effects
				(font
					(size 0.7 0.7)
					(thickness 0.15)
				)
				(justify right top)
			)
		)
		(property "Value" "R_470R_0402"
			(at -1.011843 1.772046 0)
			(layer "F.Fab")
			(effects
				(font
					(size 0.7 0.7)
					(thickness 0.15)
				)
				(justify right top)
			)
		)
		(property "Datasheet" "https://www.bourns.com/docs/product-datasheets/cr.pdf"
			(at 0 0 0)
			(layer "F.Fab")
			(hide yes)
			(effects
				(font
					(size 1.27 1.27)
					(thickness 0.15)
				)
			)
		)
		(property "Description" "SMD Chip Resistor, 470 ohm, ± 1%, 62.5 mW, 0402 [1005 Metric], Thick Film, General Purpose"
			(at 0 0 0)
			(layer "F.Fab")
			(hide yes)
			(effects
				(font
					(size 1.27 1.27)
					(thickness 0.15)
				)
			)
		)
		(property "Manufacturer" "Bourns"
			(at 0 0 180)
			(unlocked yes)
			(layer "F.Fab")
			(hide yes)
			(effects
				(font
					(size 1 1)
					(thickness 0.15)
				)
			)
		)
		(property "MPN" "CR0402-FX-4700GLF"
			(at 0 0 180)
			(unlocked yes)
			(layer "F.Fab")
			(hide yes)
			(effects
				(font
					(size 1 1)
					(thickness 0.15)
				)
			)
		)
		(property "Val" "470R"
			(at 0 0 180)
			(unlocked yes)
			(layer "F.Fab")
			(hide yes)
			(effects
				(font
					(size 1 1)
					(thickness 0.15)
				)
			)
		)
		(property "License" "Apache-2.0"
			(at 0 0 180)
			(unlocked yes)
			(layer "F.Fab")
			(hide yes)
			(effects
				(font
					(size 1 1)
					(thickness 0.15)
				)
			)
		)
		(property "Author" "Antmicro"
			(at 0 0 180)
			(unlocked yes)
			(layer "F.Fab")
			(hide yes)
			(effects
				(font
					(size 1 1)
					(thickness 0.15)
				)
			)
		)
		(property "Tolerance" "1%"
			(at 0 0 180)
			(unlocked yes)
			(layer "F.Fab")
			(hide yes)
			(effects
				(font
					(size 1 1)
					(thickness 0.15)
				)
			)
		)
		(sheetname "/USB Hub/")
		(sheetfile "usb_hub.kicad_sch")
		(attr smd)
		(fp_poly
			(pts
				(xy -0.925 -0.47) (xy 0.925 -0.47) (xy 0.925 0.47) (xy -0.925 0.47)
			)
			(stroke
				(width 0.05)
				(type default)
			)
			(fill no)
			(layer "F.CrtYd")
		)
		(fp_poly
			(pts
				(xy -0.5 -0.25) (xy 0.5 -0.25) (xy 0.5 0.25) (xy -0.5 0.25)
			)
			(stroke
				(width 0.15)
				(type solid)
			)
			(fill no)
			(layer "F.Fab")
		)
		(fp_text user "License: Apache-2.0"
			(at -0.949999 5.169 0)
			(layer "F.Fab")
			(effects
				(font
					(size 0.7 0.7)
					(thickness 0.15)
				)
				(justify right top)
			)
		)
		(fp_text user "${REFERENCE}"
			(at -0.95 3.168 0)
			(layer "F.Fab")
			(effects
				(font
					(size 0.7 0.7)
					(thickness 0.15)
				)
				(justify right top)
			)
		)
		(fp_text user "Author: Antmicro"
			(at -0.95 4.169 0)
			(layer "F.Fab")
			(effects
				(font
					(size 0.7 0.7)
					(thickness 0.15)
				)
				(justify right top)
			)
		)
		(pad "1" smd roundrect
			(at -0.48 0 180)
			(size 0.59 0.64)
			(layers "F.Cu" "F.Mask" "F.Paste")
			(roundrect_rratio 0.25)
			(net 1390 "Net-(D49-A)")
			(pintype "passive")
		)
		(pad "2" smd roundrect
			(at 0.48 0 180)
			(size 0.59 0.64)
			(layers "F.Cu" "F.Mask" "F.Paste")
			(roundrect_rratio 0.25)
			(net 115 "/USB Hub/USBC4_VBUS")
			(pintype "passive")
		)
	)
	(footprint "antmicro-footprints:C_0402_1005Metric"
		(layer "F.Cu")
		(at 206 79.205)
		(descr "Capacitor SMD 0402")
		(tags "capacitor SMD 0402")
		(property "Reference" "C119"
			(at 0.921064 0.365 0)
			(layer "F.SilkS")
			(effects
				(font
					(size 0.7 0.7)
					(thickness 0.15)
				)
				(justify left bottom)
			)
		)
		(property "Value" "C_100n_0402"
			(at -1.022927 2.155213 0)
			(layer "F.Fab")
			(effects
				(font
					(size 0.7 0.7)
					(thickness 0.15)
				)
				(justify left bottom)
			)
		)
		(property "Datasheet" "https://www.murata.com/products/productdetail?partno=GRM155R61H104KE14%23"
			(at 0 0 0)
			(layer "F.Fab")
			(hide yes)
			(effects
				(font
					(size 1.27 1.27)
					(thickness 0.15)
				)
			)
		)
		(property "Description" "SMD Multilayer Ceramic Capacitor, 0.1 µF, 50 V, 0402 [1005 Metric], ± 10%, X5R, GRM Series"
			(at 0 0 0)
			(layer "F.Fab")
			(hide yes)
			(effects
				(font
					(size 1.27 1.27)
					(thickness 0.15)
				)
			)
		)
		(property "Manufacturer" "Murata"
			(at 0 0 0)
			(unlocked yes)
			(layer "F.Fab")
			(hide yes)
			(effects
				(font
					(size 1 1)
					(thickness 0.15)
				)
			)
		)
		(property "MPN" "GRM155R61H104KE14D"
			(at 0 0 0)
			(unlocked yes)
			(layer "F.Fab")
			(hide yes)
			(effects
				(font
					(size 1 1)
					(thickness 0.15)
				)
			)
		)
		(property "Val" "100n"
			(at 0 0 0)
			(unlocked yes)
			(layer "F.Fab")
			(hide yes)
			(effects
				(font
					(size 1 1)
					(thickness 0.15)
				)
			)
		)
		(property "License" "Apache-2.0"
			(at 0 0 0)
			(unlocked yes)
			(layer "F.Fab")
			(hide yes)
			(effects
				(font
					(size 1 1)
					(thickness 0.15)
				)
			)
		)
		(property "Author" "Antmicro"
			(at 0 0 0)
			(unlocked yes)
			(layer "F.Fab")
			(hide yes)
			(effects
				(font
					(size 1 1)
					(thickness 0.15)
				)
			)
		)
		(property "Voltage" "50V"
			(at 0 0 0)
			(unlocked yes)
			(layer "F.Fab")
			(hide yes)
			(effects
				(font
					(size 1 1)
					(thickness 0.15)
				)
			)
		)
		(property "Dielectric" "X5R"
			(at 0 0 0)
			(unlocked yes)
			(layer "F.Fab")
			(hide yes)
			(effects
				(font
					(size 1 1)
					(thickness 0.15)
				)
			)
		)
		(sheetname "/USB Debug, PD/")
		(sheetfile "usb_debug_pd.kicad_sch")
		(attr smd)
		(fp_rect
			(start -0.925 -0.47)
			(end 0.925 0.47)
			(stroke
				(width 0.05)
				(type default)
			)
			(fill no)
			(layer "F.CrtYd")
		)
		(fp_line
			(start -0.494 -0.25)
			(end 0.504 -0.25)
			(stroke
				(width 0.15)
				(type solid)
			)
			(layer "F.Fab")
		)
		(fp_line
			(start -0.494 0.248)
			(end -0.494 -0.25)
			(stroke
				(width 0.15)
				(type solid)
			)
			(layer "F.Fab")
		)
		(fp_line
			(start 0.504 -0.25)
			(end 0.504 0.248)
			(stroke
				(width 0.15)
				(type solid)
			)
			(layer "F.Fab")
		)
		(fp_line
			(start 0.504 0.248)
			(end -0.494 0.248)
			(stroke
				(width 0.15)
				(type solid)
			)
			(layer "F.Fab")
		)
		(fp_text user "Author: Antmicro"
			(at -0.939 3.399 0)
			(layer "F.Fab")
			(effects
				(font
					(size 0.7 0.7)
					(thickness 0.15)
				)
				(justify left bottom)
			)
		)
		(fp_text user "${REFERENCE}"
			(at -0.939 4.599 0)
			(layer "F.Fab")
			(effects
				(font
					(size 0.7 0.7)
					(thickness 0.15)
				)
				(justify left bottom)
			)
		)
		(fp_text user "License: Apache-2.0"
			(at -0.939 5.799 0)
			(layer "F.Fab")
			(effects
				(font
					(size 0.7 0.7)
					(thickness 0.15)
				)
				(justify left bottom)
			)
		)
		(pad "1" smd roundrect
			(at -0.48 0)
			(size 0.59 0.64)
			(layers "F.Cu" "F.Mask" "F.Paste")
			(roundrect_rratio 0.25)
			(net 2 "+3V3")
			(pintype "passive")
		)
		(pad "2" smd roundrect
			(at 0.48 0)
			(size 0.59 0.64)
			(layers "F.Cu" "F.Mask" "F.Paste")
			(roundrect_rratio 0.25)
			(net 1 "GND")
			(pintype "passive")
		)
	)
	(footprint "antmicro-footprints:R_0402_1005Metric"
		(layer "F.Cu")
		(at 142.59 131.32 90)
		(descr "Resistor SMD 0402")
		(tags "resistor SMD 0402")
		(property "Reference" "R363"
			(at -0.98 1.51 90)
			(layer "F.SilkS")
			(effects
				(font
					(size 0.7 0.7)
					(thickness 0.15)
				)
				(justify left bottom)
			)
		)
		(property "Value" "R_100k_0402"
			(at -1.011843 1.772047 90)
			(layer "F.Fab")
			(effects
				(font
					(size 0.7 0.7)
					(thickness 0.15)
				)
				(justify left bottom)
			)
		)
		(property "Datasheet" "https://www.bourns.com/docs/product-datasheets/cr.pdf"
			(at 0 0 90)
			(layer "F.Fab")
			(hide yes)
			(effects
				(font
					(size 1.27 1.27)
					(thickness 0.15)
				)
			)
		)
		(property "Description" "SMD Chip Resistor, 100 kohm, ± 1%, 62.5 mW, 0402 [1005 Metric], Thick Film, General Purpose"
			(at 0 0 90)
			(layer "F.Fab")
			(hide yes)
			(effects
				(font
					(size 1.27 1.27)
					(thickness 0.15)
				)
			)
		)
		(property "MPN" "CR0402-FX-1003GLF"
			(at 0 0 90)
			(unlocked yes)
			(layer "F.Fab")
			(hide yes)
			(effects
				(font
					(size 1 1)
					(thickness 0.15)
				)
			)
		)
		(property "Manufacturer" "Bourns"
			(at 0 0 90)
			(unlocked yes)
			(layer "F.Fab")
			(hide yes)
			(effects
				(font
					(size 1 1)
					(thickness 0.15)
				)
			)
		)
		(property "License" "Apache-2.0"
			(at 0 0 90)
			(unlocked yes)
			(layer "F.Fab")
			(hide yes)
			(effects
				(font
					(size 1 1)
					(thickness 0.15)
				)
			)
		)
		(property "Author" "Antmicro"
			(at 0 0 90)
			(unlocked yes)
			(layer "F.Fab")
			(hide yes)
			(effects
				(font
					(size 1 1)
					(thickness 0.15)
				)
			)
		)
		(property "Val" "100k"
			(at 0 0 90)
			(unlocked yes)
			(layer "F.Fab")
			(hide yes)
			(effects
				(font
					(size 1 1)
					(thickness 0.15)
				)
			)
		)
		(property "Tolerance" "1%"
			(at 0 0 90)
			(unlocked yes)
			(layer "F.Fab")
			(hide yes)
			(effects
				(font
					(size 1 1)
					(thickness 0.15)
				)
			)
		)
		(sheetname "/SoM_Power/")
		(sheetfile "som_power.kicad_sch")
		(attr smd)
		(fp_rect
			(start -0.925 -0.47)
			(end 0.925 0.47)
			(stroke
				(width 0.05)
				(type default)
			)
			(fill no)
			(layer "F.CrtYd")
		)
		(fp_rect
			(start -0.5 -0.25)
			(end 0.5 0.25)
			(stroke
				(width 0.15)
				(type solid)
			)
			(fill no)
			(layer "F.Fab")
		)
		(fp_text user "License: Apache-2.0"
			(at -0.95 5.169 90)
			(layer "F.Fab")
			(effects
				(font
					(size 0.7 0.7)
					(thickness 0.15)
				)
				(justify left bottom)
			)
		)
		(fp_text user "${REFERENCE}"
			(at -0.95 3.168 90)
			(layer "F.Fab")
			(effects
				(font
					(size 0.7 0.7)
					(thickness 0.15)
				)
				(justify left bottom)
			)
		)
		(fp_text user "Author: Antmicro"
			(at -0.95 4.169 90)
			(layer "F.Fab")
			(effects
				(font
					(size 0.7 0.7)
					(thickness 0.15)
				)
				(justify left bottom)
			)
		)
		(pad "1" smd roundrect
			(at -0.48 0 90)
			(size 0.59 0.64)
			(layers "F.Cu" "F.Mask" "F.Paste")
			(roundrect_rratio 0.25)
			(net 883 "Net-(Q10-G)")
			(pintype "passive")
		)
		(pad "2" smd roundrect
			(at 0.48 0 90)
			(size 0.59 0.64)
			(layers "F.Cu" "F.Mask" "F.Paste")
			(roundrect_rratio 0.25)
			(net 4 "+3V3_AON")
			(pintype "passive")
		)
	)
	(footprint "antmicro-footprints:C_0402_1005Metric"
		(layer "F.Cu")
		(at 139.4 104.8 -90)
		(descr "Capacitor SMD 0402")
		(tags "capacitor SMD 0402")
		(property "Reference" "C313"
			(at -3.8 0.4 90)
			(layer "F.SilkS")
			(effects
				(font
					(size 0.7 0.7)
					(thickness 0.15)
				)
				(justify right top)
			)
		)
		(property "Value" "C_100n_0402"
			(at -1.022927 2.155213 90)
			(layer "F.Fab")
			(effects
				(font
					(size 0.7 0.7)
					(thickness 0.15)
				)
				(justify right top)
			)
		)
		(property "Datasheet" "https://www.murata.com/products/productdetail?partno=GRM155R61H104KE14%23"
			(at 0 0 90)
			(layer "F.Fab")
			(hide yes)
			(effects
				(font
					(size 1.27 1.27)
					(thickness 0.15)
				)
			)
		)
		(property "Description" "SMD Multilayer Ceramic Capacitor, 0.1 µF, 50 V, 0402 [1005 Metric], ± 10%, X5R, GRM Series"
			(at 0 0 90)
			(layer "F.Fab")
			(hide yes)
			(effects
				(font
					(size 1.27 1.27)
					(thickness 0.15)
				)
			)
		)
		(property "Manufacturer" "Murata"
			(at 0 0 270)
			(unlocked yes)
			(layer "F.Fab")
			(hide yes)
			(effects
				(font
					(size 1 1)
					(thickness 0.15)
				)
			)
		)
		(property "MPN" "GRM155R61H104KE14D"
			(at 0 0 270)
			(unlocked yes)
			(layer "F.Fab")
			(hide yes)
			(effects
				(font
					(size 1 1)
					(thickness 0.15)
				)
			)
		)
		(property "Val" "100n"
			(at 0 0 270)
			(unlocked yes)
			(layer "F.Fab")
			(hide yes)
			(effects
				(font
					(size 1 1)
					(thickness 0.15)
				)
			)
		)
		(property "License" "Apache-2.0"
			(at 0 0 270)
			(unlocked yes)
			(layer "F.Fab")
			(hide yes)
			(effects
				(font
					(size 1 1)
					(thickness 0.15)
				)
			)
		)
		(property "Author" "Antmicro"
			(at 0 0 270)
			(unlocked yes)
			(layer "F.Fab")
			(hide yes)
			(effects
				(font
					(size 1 1)
					(thickness 0.15)
				)
			)
		)
		(property "Voltage" "50V"
			(at 0 0 270)
			(unlocked yes)
			(layer "F.Fab")
			(hide yes)
			(effects
				(font
					(size 1 1)
					(thickness 0.15)
				)
			)
		)
		(property "Dielectric" "X5R"
			(at 0 0 270)
			(unlocked yes)
			(layer "F.Fab")
			(hide yes)
			(effects
				(font
					(size 1 1)
					(thickness 0.15)
				)
			)
		)
		(sheetname "/Peripherals/")
		(sheetfile "peripherals.kicad_sch")
		(attr smd)
		(fp_rect
			(start -0.925 -0.47)
			(end 0.925 0.47)
			(stroke
				(width 0.05)
				(type default)
			)
			(fill no)
			(layer "F.CrtYd")
		)
		(fp_line
			(start -0.494 0.248)
			(end -0.494 -0.25)
			(stroke
				(width 0.15)
				(type solid)
			)
			(layer "F.Fab")
		)
		(fp_line
			(start 0.504 0.248)
			(end -0.494 0.248)
			(stroke
				(width 0.15)
				(type solid)
			)
			(layer "F.Fab")
		)
		(fp_line
			(start -0.494 -0.25)
			(end 0.504 -0.25)
			(stroke
				(width 0.15)
				(type solid)
			)
			(layer "F.Fab")
		)
		(fp_line
			(start 0.504 -0.25)
			(end 0.504 0.248)
			(stroke
				(width 0.15)
				(type solid)
			)
			(layer "F.Fab")
		)
		(fp_text user "License: Apache-2.0"
			(at -0.939 5.799 90)
			(layer "F.Fab")
			(effects
				(font
					(size 0.7 0.7)
					(thickness 0.15)
				)
				(justify right top)
			)
		)
		(fp_text user "Author: Antmicro"
			(at -0.939 3.399 90)
			(layer "F.Fab")
			(effects
				(font
					(size 0.7 0.7)
					(thickness 0.15)
				)
				(justify right top)
			)
		)
		(fp_text user "${REFERENCE}"
			(at -0.939 4.599 90)
			(layer "F.Fab")
			(effects
				(font
					(size 0.7 0.7)
					(thickness 0.15)
				)
				(justify right top)
			)
		)
		(pad "1" smd roundrect
			(at -0.48 0 270)
			(size 0.59 0.64)
			(layers "F.Cu" "F.Mask" "F.Paste")
			(roundrect_rratio 0.25)
			(net 1 "GND")
			(pintype "passive")
		)
		(pad "2" smd roundrect
			(at 0.48 0 270)
			(size 0.59 0.64)
			(layers "F.Cu" "F.Mask" "F.Paste")
			(roundrect_rratio 0.25)
			(net 2 "+3V3")
			(pintype "passive")
		)
	)
	(footprint "antmicro-footprints:R_0402_1005Metric"
		(layer "F.Cu")
		(at 142.06 58.8 -90)
		(descr "Resistor SMD 0402")
		(tags "resistor SMD 0402")
		(property "Reference" "R417"
			(at 1.01 0.27 90)
			(layer "F.SilkS")
			(effects
				(font
					(size 0.7 0.7)
					(thickness 0.15)
				)
				(justify right top)
			)
		)
		(property "Value" "R_10k_0402"
			(at -1.011843 1.772046 90)
			(layer "F.Fab")
			(effects
				(font
					(size 0.7 0.7)
					(thickness 0.15)
				)
				(justify right top)
			)
		)
		(property "Datasheet" "https://www.bourns.com/docs/product-datasheets/cr.pdf"
			(at 0 0 90)
			(layer "F.Fab")
			(hide yes)
			(effects
				(font
					(size 1.27 1.27)
					(thickness 0.15)
				)
			)
		)
		(property "Description" "SMD Chip Resistor, 10 kohm, ± 1%, 62.5 mW, 0402 [1005 Metric], Thick Film, General Purpose"
			(at 0 0 90)
			(layer "F.Fab")
			(hide yes)
			(effects
				(font
					(size 1.27 1.27)
					(thickness 0.15)
				)
			)
		)
		(property "MPN" "CR0402-FX-1002GLF"
			(at 0 0 270)
			(unlocked yes)
			(layer "F.Fab")
			(hide yes)
			(effects
				(font
					(size 1 1)
					(thickness 0.15)
				)
			)
		)
		(property "Manufacturer" "Bourns"
			(at 0 0 270)
			(unlocked yes)
			(layer "F.Fab")
			(hide yes)
			(effects
				(font
					(size 1 1)
					(thickness 0.15)
				)
			)
		)
		(property "License" "Apache-2.0"
			(at 0 0 270)
			(unlocked yes)
			(layer "F.Fab")
			(hide yes)
			(effects
				(font
					(size 1 1)
					(thickness 0.15)
				)
			)
		)
		(property "Author" "Antmicro"
			(at 0 0 270)
			(unlocked yes)
			(layer "F.Fab")
			(hide yes)
			(effects
				(font
					(size 1 1)
					(thickness 0.15)
				)
			)
		)
		(property "Val" "10k"
			(at 0 0 270)
			(unlocked yes)
			(layer "F.Fab")
			(hide yes)
			(effects
				(font
					(size 1 1)
					(thickness 0.15)
				)
			)
		)
		(property "Tolerance" "1%"
			(at 0 0 270)
			(unlocked yes)
			(layer "F.Fab")
			(hide yes)
			(effects
				(font
					(size 1 1)
					(thickness 0.15)
				)
			)
		)
		(sheetname "/Power/")
		(sheetfile "power.kicad_sch")
		(attr smd)
		(fp_poly
			(pts
				(xy -0.925 -0.47) (xy 0.925 -0.47) (xy 0.925 0.47) (xy -0.925 0.47)
			)
			(stroke
				(width 0.05)
				(type default)
			)
			(fill no)
			(layer "F.CrtYd")
		)
		(fp_poly
			(pts
				(xy -0.5 -0.25) (xy 0.5 -0.25) (xy 0.5 0.25) (xy -0.5 0.25)
			)
			(stroke
				(width 0.15)
				(type solid)
			)
			(fill no)
			(layer "F.Fab")
		)
		(fp_text user "License: Apache-2.0"
			(at -0.949999 5.169 90)
			(layer "F.Fab")
			(effects
				(font
					(size 0.7 0.7)
					(thickness 0.15)
				)
				(justify right top)
			)
		)
		(fp_text user "Author: Antmicro"
			(at -0.95 4.169 90)
			(layer "F.Fab")
			(effects
				(font
					(size 0.7 0.7)
					(thickness 0.15)
				)
				(justify right top)
			)
		)
		(fp_text user "${REFERENCE}"
			(at -0.95 3.168 90)
			(layer "F.Fab")
			(effects
				(font
					(size 0.7 0.7)
					(thickness 0.15)
				)
				(justify right top)
			)
		)
		(pad "1" smd roundrect
			(at -0.48 0 270)
			(size 0.59 0.64)
			(layers "F.Cu" "F.Mask" "F.Paste")
			(roundrect_rratio 0.25)
			(net 1 "GND")
			(pintype "passive")
		)
		(pad "2" smd roundrect
			(at 0.48 0 270)
			(size 0.59 0.64)
			(layers "F.Cu" "F.Mask" "F.Paste")
			(roundrect_rratio 0.25)
			(net 1396 "Net-(U79-ADJ)")
			(pintype "passive")
		)
	)
	(footprint "antmicro-footprints:TDFN-6-1EP_3x3mm_P0.95mm"
		(layer "F.Cu")
		(at 210.4 64.9 -90)
		(property "Reference" "U9"
			(at -2.09 0.75 0)
			(layer "F.SilkS")
			(effects
				(font
					(size 0.7 0.7)
					(thickness 0.15)
				)
				(justify left bottom)
			)
		)
		(property "Value" "MAX16013"
			(at -2 4.1 270)
			(layer "F.Fab")
			(effects
				(font
					(size 0.7 0.7)
					(thickness 0.15)
				)
				(justify left bottom)
			)
		)
		(property "Datasheet" "https://www.analog.com/media/en/technical-documentation/data-sheets/max16010-max16014.pdf"
			(at 0 0 270)
			(layer "F.Fab")
			(effects
				(font
					(size 0.7 0.7)
					(thickness 0.15)
				)
				(justify left bottom)
			)
		)
		(property "Description" "Over voltage, reverse voltage protection"
			(at 0 0 270)
			(layer "F.Fab")
			(effects
				(font
					(size 0.7 0.7)
					(thickness 0.15)
				)
				(justify left bottom)
			)
		)
		(property "Manufacturer" "Analog Devices"
			(at 0 0 270)
			(unlocked yes)
			(layer "F.Fab")
			(hide yes)
			(effects
				(font
					(size 1 1)
					(thickness 0.15)
				)
			)
		)
		(property "MPN" "MAX16013TT-T"
			(at 0 0 270)
			(unlocked yes)
			(layer "F.Fab")
			(hide yes)
			(effects
				(font
					(size 1 1)
					(thickness 0.15)
				)
			)
		)
		(property "Author" "Antmicro"
			(at 0 0 270)
			(unlocked yes)
			(layer "F.Fab")
			(hide yes)
			(effects
				(font
					(size 1 1)
					(thickness 0.15)
				)
			)
		)
		(property "License" "Apache-2.0"
			(at 0 0 270)
			(unlocked yes)
			(layer "F.Fab")
			(hide yes)
			(effects
				(font
					(size 1 1)
					(thickness 0.15)
				)
			)
		)
		(sheetname "/Power/")
		(sheetfile "power.kicad_sch")
		(attr smd)
		(fp_line
			(start -1.55 1.55)
			(end 1.55 1.55)
			(stroke
				(width 0.15)
				(type solid)
			)
			(layer "F.SilkS")
		)
		(fp_line
			(start -1.55 -1.55)
			(end 1.55 -1.55)
			(stroke
				(width 0.15)
				(type solid)
			)
			(layer "F.SilkS")
		)
		(fp_circle
			(center -1.85 -1.4)
			(end -1.8 -1.4)
			(stroke
				(width 0.15)
				(type solid)
			)
			(fill yes)
			(layer "F.SilkS")
		)
		(fp_poly
			(pts
				(xy -0.47 -0.73) (xy 0.47 -0.73) (xy 0.47 0.73) (xy -0.47 0.73)
			)
			(stroke
				(width 0.01)
				(type solid)
			)
			(fill yes)
			(layer "F.Paste")
		)
		(fp_rect
			(start -2.12 -1.75)
			(end 2.12 1.75)
			(stroke
				(width 0.05)
				(type solid)
			)
			(fill no)
			(layer "F.CrtYd")
		)
		(fp_line
			(start -1.55 1.55)
			(end 1.55 1.55)
			(stroke
				(width 0.15)
				(type solid)
			)
			(layer "F.Fab")
		)
		(fp_line
			(start -1.55 -1.55)
			(end -1.55 1.55)
			(stroke
				(width 0.15)
				(type solid)
			)
			(layer "F.Fab")
		)
		(fp_line
			(start -1.55 -1.55)
			(end 1.55 -1.55)
			(stroke
				(width 0.15)
				(type solid)
			)
			(layer "F.Fab")
		)
		(fp_line
			(start 1.55 -1.55)
			(end 1.55 1.55)
			(stroke
				(width 0.15)
				(type solid)
			)
			(layer "F.Fab")
		)
		(fp_text user "License: Apache-2.0"
			(at -2 6.5 270)
			(layer "F.Fab")
			(effects
				(font
					(size 0.7 0.7)
					(thickness 0.15)
				)
				(justify left bottom)
			)
		)
		(fp_text user "${REFERENCE}"
			(at -1.9 2.9 270)
			(layer "F.Fab")
			(effects
				(font
					(size 0.7 0.7)
					(thickness 0.15)
				)
				(justify left bottom)
			)
		)
		(fp_text user "Author: Antmicro"
			(at -2 5.3 270)
			(layer "F.Fab")
			(effects
				(font
					(size 0.7 0.7)
					(thickness 0.15)
				)
				(justify left bottom)
			)
		)
		(pad "1" smd roundrect
			(at -1.485 -0.95 270)
			(size 0.76 0.42)
			(layers "F.Cu" "F.Mask" "F.Paste")
			(roundrect_rratio 0.125)
			(net 1383 "VCC_NO_OVP")
			(pinfunction "VCC")
			(pintype "power_in")
			(solder_mask_margin 0)
		)
		(pad "2" smd roundrect
			(at -1.485 0 270)
			(size 0.76 0.42)
			(layers "F.Cu" "F.Mask" "F.Paste")
			(roundrect_rratio 0.125)
			(net 1 "GND")
			(pinfunction "GND")
			(pintype "power_in")
		)
		(pad "3" smd roundrect
			(at -1.485 0.95 270)
			(size 0.76 0.42)
			(layers "F.Cu" "F.Mask" "F.Paste")
			(roundrect_rratio 0.125)
			(net 1385 "Net-(Q41-G)")
			(pinfunction "GATE2")
			(pintype "output")
		)
		(pad "4" smd roundrect
			(at 1.485 0.95 270)
			(size 0.76 0.42)
			(layers "F.Cu" "F.Mask" "F.Paste")
			(roundrect_rratio 0.125)
			(net 1386 "Net-(U9-SET)")
			(pinfunction "SET")
			(pintype "input")
		)
		(pad "5" smd roundrect
			(at 1.485 0 270)
			(size 0.76 0.42)
			(layers "F.Cu" "F.Mask" "F.Paste")
			(roundrect_rratio 0.125)
			(net 1383 "VCC_NO_OVP")
			(pinfunction "EN")
			(pintype "input")
		)
		(pad "6" smd roundrect
			(at 1.485 -0.95 270)
			(size 0.76 0.42)
			(layers "F.Cu" "F.Mask" "F.Paste")
			(roundrect_rratio 0.125)
			(net 1384 "Net-(Q32-G)")
			(pinfunction "GATE1")
			(pintype "output")
		)
		(pad "7" smd rect
			(at 0 0 270)
			(size 1.5 2.3)
			(layers "F.Cu" "F.Mask")
			(net 1 "GND")
			(pinfunction "GND")
			(pintype "power_in")
		)
	)
	(footprint "antmicro-footprints:USON-10_2.5x1mm_P0.5mm"
		(layer "F.Cu")
		(at 221.402132 96.162)
		(descr "USON-10 2.5x1mm_ Pitch 0.5mm")
		(tags "USON-10 2.5x1mm Pitch 0.5mm")
		(property "Reference" "U36"
			(at 1.9 1.12 90)
			(layer "F.SilkS")
			(effects
				(font
					(size 0.7 0.7)
					(thickness 0.15)
				)
				(justify left bottom)
			)
		)
		(property "Value" "TPD4E05U06QDQARQ1"
			(at 0.018 2.499 0)
			(layer "F.Fab")
			(effects
				(font
					(size 0.7 0.7)
					(thickness 0.15)
				)
				(justify left bottom)
			)
		)
		(property "Datasheet" "https://www.ti.com/lit/ds/symlink/tpd4e05u06-q1.pdf?HQS=dis-mous-null-mousermode-dsf-pf-null-wwe&ts=1663591265741&ref_url=https%253A%252F%252Fwww.mouser.com%252F"
			(at 0 0 0)
			(layer "F.Fab")
			(hide yes)
			(effects
				(font
					(size 1.27 1.27)
					(thickness 0.15)
				)
			)
		)
		(property "Description" "TVS diode array, 12 kV, USON-10, 5.5 V, 0.5 pF"
			(at 0 0 0)
			(layer "F.Fab")
			(hide yes)
			(effects
				(font
					(size 1.27 1.27)
					(thickness 0.15)
				)
			)
		)
		(property "Manufacturer" "Texas Instruments"
			(at 0 0 0)
			(unlocked yes)
			(layer "F.Fab")
			(hide yes)
			(effects
				(font
					(size 1 1)
					(thickness 0.15)
				)
			)
		)
		(property "MPN" "TPD4E05U06QDQARQ1"
			(at 0 0 0)
			(unlocked yes)
			(layer "F.Fab")
			(hide yes)
			(effects
				(font
					(size 1 1)
					(thickness 0.15)
				)
			)
		)
		(property "Author" "Antmicro"
			(at 0 0 0)
			(unlocked yes)
			(layer "F.Fab")
			(hide yes)
			(effects
				(font
					(size 1 1)
					(thickness 0.15)
				)
			)
		)
		(property "License" "Apache-2.0"
			(at 0 0 0)
			(unlocked yes)
			(layer "F.Fab")
			(hide yes)
			(effects
				(font
					(size 1 1)
					(thickness 0.15)
				)
			)
		)
		(sheetname "/USB DP Alt mode/")
		(sheetfile "usb_dp.kicad_sch")
		(attr smd)
		(fp_line
			(start 0.498 -1.401)
			(end -0.5 -1.401)
			(stroke
				(width 0.15)
				(type solid)
			)
			(layer "F.SilkS")
		)
		(fp_line
			(start 0.498 1.398)
			(end -0.5 1.398)
			(stroke
				(width 0.15)
				(type solid)
			)
			(layer "F.SilkS")
		)
		(fp_circle
			(center -0.68 -1.27)
			(end -0.63 -1.27)
			(stroke
				(width 0.15)
				(type solid)
			)
			(fill yes)
			(layer "F.SilkS")
		)
		(fp_rect
			(start -0.8 -1.5)
			(end 0.8 1.499)
			(stroke
				(width 0.05)
				(type solid)
			)
			(fill no)
			(layer "F.CrtYd")
		)
		(fp_line
			(start -0.5 -1)
			(end -0.5 1.249)
			(stroke
				(width 0.15)
				(type solid)
			)
			(layer "F.Fab")
		)
		(fp_line
			(start -0.5 1.249)
			(end 0.498 1.249)
			(stroke
				(width 0.15)
				(type solid)
			)
			(layer "F.Fab")
		)
		(fp_line
			(start -0.25 -1.25)
			(end -0.5 -1)
			(stroke
				(width 0.15)
				(type solid)
			)
			(layer "F.Fab")
		)
		(fp_line
			(start 0.498 -1.25)
			(end -0.25 -1.25)
			(stroke
				(width 0.15)
				(type solid)
			)
			(layer "F.Fab")
		)
		(fp_line
			(start 0.498 -1.25)
			(end 0.498 1.249)
			(stroke
				(width 0.15)
				(type solid)
			)
			(layer "F.Fab")
		)
		(fp_text user "${REFERENCE}"
			(at -0.802 4.498 0)
			(layer "F.Fab")
			(effects
				(font
					(size 0.7 0.7)
					(thickness 0.15)
				)
				(justify left bottom)
			)
		)
		(fp_text user "Author: Antmicro"
			(at -0.802 5.7 0)
			(layer "F.Fab")
			(effects
				(font
					(size 0.7 0.7)
					(thickness 0.15)
				)
				(justify left bottom)
			)
		)
		(fp_text user "License: Apache-2.0"
			(at -0.802 6.9 0)
			(layer "F.Fab")
			(effects
				(font
					(size 0.7 0.7)
					(thickness 0.15)
				)
				(justify left bottom)
			)
		)
		(pad "1" smd roundrect
			(at -0.387 -1 270)
			(size 0.25 0.55)
			(layers "F.Cu" "F.Mask" "F.Paste")
			(roundrect_rratio 0.25)
			(net 821 "/USB DP Alt mode/USBC1_SBU_N")
			(pintype "passive")
		)
		(pad "2" smd roundrect
			(at -0.387 -0.5 270)
			(size 0.25 0.55)
			(layers "F.Cu" "F.Mask" "F.Paste")
			(roundrect_rratio 0.25)
			(net 815 "/USB DP Alt mode/USBC1_SBU_P")
			(pintype "passive")
		)
		(pad "3" smd roundrect
			(at -0.387 0 270)
			(size 0.4 0.55)
			(layers "F.Cu" "F.Mask" "F.Paste")
			(roundrect_rratio 0.25)
			(net 1 "GND")
			(pintype "power_in")
		)
		(pad "4" smd roundrect
			(at -0.387 0.498 270)
			(size 0.25 0.55)
			(layers "F.Cu" "F.Mask" "F.Paste")
			(roundrect_rratio 0.25)
			(net 1116 "unconnected-(U36-Pad4)")
			(pintype "passive+no_connect")
		)
		(pad "5" smd roundrect
			(at -0.387 0.998 270)
			(size 0.25 0.55)
			(layers "F.Cu" "F.Mask" "F.Paste")
			(roundrect_rratio 0.25)
			(net 1117 "unconnected-(U36-Pad5)")
			(pintype "passive+no_connect")
		)
		(pad "6" smd roundrect
			(at 0.385 0.998 270)
			(size 0.25 0.55)
			(layers "F.Cu" "F.Mask" "F.Paste")
			(roundrect_rratio 0.25)
			(net 1119 "unconnected-(U36-Pad5)_1")
			(pintype "passive+no_connect")
		)
		(pad "7" smd roundrect
			(at 0.385 0.498 270)
			(size 0.25 0.55)
			(layers "F.Cu" "F.Mask" "F.Paste")
			(roundrect_rratio 0.25)
			(net 1118 "unconnected-(U36-Pad4)_1")
			(pintype "passive+no_connect")
		)
		(pad "8" smd roundrect
			(at 0.385 0 270)
			(size 0.4 0.55)
			(layers "F.Cu" "F.Mask" "F.Paste")
			(roundrect_rratio 0.25)
			(net 1 "GND")
			(pintype "passive")
		)
		(pad "9" smd roundrect
			(at 0.385 -0.5 270)
			(size 0.25 0.55)
			(layers "F.Cu" "F.Mask" "F.Paste")
			(roundrect_rratio 0.25)
			(net 815 "/USB DP Alt mode/USBC1_SBU_P")
			(pintype "passive")
		)
		(pad "10" smd roundrect
			(at 0.385 -1 270)
			(size 0.25 0.55)
			(layers "F.Cu" "F.Mask" "F.Paste")
			(roundrect_rratio 0.25)
			(net 821 "/USB DP Alt mode/USBC1_SBU_N")
			(pintype "passive")
		)
	)
	(footprint "antmicro-footprints:C_0805_2012Metric"
		(layer "F.Cu")
		(at 175 99.81 90)
		(descr "Capacitor SMD 0805")
		(tags "capacitor SMD 0805")
		(property "Reference" "C248"
			(at -4.565 0.4 90)
			(layer "F.SilkS")
			(effects
				(font
					(size 0.7 0.7)
					(thickness 0.15)
				)
				(justify left bottom)
			)
		)
		(property "Value" "C_22u_25V_0805"
			(at -2.055717 1.963152 90)
			(layer "F.Fab")
			(effects
				(font
					(size 0.7 0.7)
					(thickness 0.15)
				)
				(justify left bottom)
			)
		)
		(property "Datasheet" "https://product.samsungsem.com/mlcc/CL21A226MAYNNN.do"
			(at 0 0 90)
			(layer "F.Fab")
			(hide yes)
			(effects
				(font
					(size 1.27 1.27)
					(thickness 0.15)
				)
			)
		)
		(property "Description" "SMT Multilayer Ceramic Capacitor, 22uF, +/-20%, 25V, X5R, 0805 [2012 Metric]"
			(at 0 0 90)
			(layer "F.Fab")
			(hide yes)
			(effects
				(font
					(size 1.27 1.27)
					(thickness 0.15)
				)
			)
		)
		(property "MPN" "CL21A226MAYNNNE"
			(at 0 0 90)
			(unlocked yes)
			(layer "F.Fab")
			(hide yes)
			(effects
				(font
					(size 1 1)
					(thickness 0.15)
				)
			)
		)
		(property "Manufacturer" "Samsung Electro-Mechanics"
			(at 0 0 90)
			(unlocked yes)
			(layer "F.Fab")
			(hide yes)
			(effects
				(font
					(size 1 1)
					(thickness 0.15)
				)
			)
		)
		(property "License" "Apache-2.0"
			(at 0 0 90)
			(unlocked yes)
			(layer "F.Fab")
			(hide yes)
			(effects
				(font
					(size 1 1)
					(thickness 0.15)
				)
			)
		)
		(property "Author" "Antmicro"
			(at 0 0 90)
			(unlocked yes)
			(layer "F.Fab")
			(hide yes)
			(effects
				(font
					(size 1 1)
					(thickness 0.15)
				)
			)
		)
		(property "Val" "22u"
			(at 0 0 90)
			(unlocked yes)
			(layer "F.Fab")
			(hide yes)
			(effects
				(font
					(size 1 1)
					(thickness 0.15)
				)
			)
		)
		(property "Voltage" "25V"
			(at 0 0 90)
			(unlocked yes)
			(layer "F.Fab")
			(hide yes)
			(effects
				(font
					(size 1 1)
					(thickness 0.15)
				)
			)
		)
		(property "Dielectric" "X5R"
			(at 0 0 90)
			(unlocked yes)
			(layer "F.Fab")
			(hide yes)
			(effects
				(font
					(size 1 1)
					(thickness 0.15)
				)
			)
		)
		(property "Public" "False"
			(at 0 0 90)
			(unlocked yes)
			(layer "F.Fab")
			(hide yes)
			(effects
				(font
					(size 1 1)
					(thickness 0.15)
				)
			)
		)
		(component_classes
			(class "DCDC_SOM")
		)
		(sheetname "/DCDC/")
		(sheetfile "dcdc.kicad_sch")
		(attr smd)
		(fp_line
			(start -0.3 -0.7)
			(end 0.3 -0.7)
			(stroke
				(width 0.15)
				(type solid)
			)
			(layer "F.SilkS")
		)
		(fp_line
			(start -0.3 0.7)
			(end 0.3 0.7)
			(stroke
				(width 0.15)
				(type solid)
			)
			(layer "F.SilkS")
		)
		(fp_rect
			(start 1.95 -0.9)
			(end -1.95 0.9)
			(stroke
				(width 0.05)
				(type default)
			)
			(fill no)
			(layer "F.CrtYd")
		)
		(fp_rect
			(start -0.95 -0.675)
			(end 0.95 0.675)
			(stroke
				(width 0.15)
				(type solid)
			)
			(fill no)
			(layer "F.Fab")
		)
		(fp_text user "License: Apache-2.0"
			(at -1.9 4.947 90)
			(layer "F.Fab")
			(effects
				(font
					(size 0.7 0.7)
					(thickness 0.15)
				)
				(justify left bottom)
			)
		)
		(fp_text user "Author: Antmicro"
			(at -1.9 5.947 90)
			(layer "F.Fab")
			(effects
				(font
					(size 0.7 0.7)
					(thickness 0.15)
				)
				(justify left bottom)
			)
		)
		(fp_text user "${REFERENCE}"
			(at -1.9 3.947 90)
			(layer "F.Fab")
			(effects
				(font
					(size 0.7 0.7)
					(thickness 0.15)
				)
				(justify left bottom)
			)
		)
		(pad "1" smd roundrect
			(at -1.1 0 90)
			(size 1.2 1.3)
			(layers "F.Cu" "F.Mask" "F.Paste")
			(roundrect_rratio 0.25)
			(net 1 "GND")
			(pintype "passive")
		)
		(pad "2" smd roundrect
			(at 1.1 0 90)
			(size 1.2 1.3)
			(layers "F.Cu" "F.Mask" "F.Paste")
			(roundrect_rratio 0.25)
			(net 903 "/DCDC/16V_OUT")
			(pintype "passive")
		)
	)
	(footprint "antmicro-footprints:R_0402_1005Metric"
		(layer "F.Cu")
		(at 87.35 145.65 180)
		(descr "Resistor SMD 0402")
		(tags "resistor SMD 0402")
		(property "Reference" "R11"
			(at -1.15 1.35 0)
			(layer "F.SilkS")
			(effects
				(font
					(size 0.7 0.7)
					(thickness 0.15)
				)
				(justify right top)
			)
		)
		(property "Value" "R_100k_0402"
			(at -1.011843 1.772046 0)
			(layer "F.Fab")
			(effects
				(font
					(size 0.7 0.7)
					(thickness 0.15)
				)
				(justify right top)
			)
		)
		(property "Datasheet" "https://www.bourns.com/docs/product-datasheets/cr.pdf"
			(at 0 0 0)
			(layer "F.Fab")
			(hide yes)
			(effects
				(font
					(size 1.27 1.27)
					(thickness 0.15)
				)
			)
		)
		(property "Description" "SMD Chip Resistor, 100 kohm, ± 1%, 62.5 mW, 0402 [1005 Metric], Thick Film, General Purpose"
			(at 0 0 0)
			(layer "F.Fab")
			(hide yes)
			(effects
				(font
					(size 1.27 1.27)
					(thickness 0.15)
				)
			)
		)
		(property "MPN" "CR0402-FX-1003GLF"
			(at 0 0 180)
			(unlocked yes)
			(layer "F.Fab")
			(hide yes)
			(effects
				(font
					(size 1 1)
					(thickness 0.15)
				)
			)
		)
		(property "Manufacturer" "Bourns"
			(at 0 0 180)
			(unlocked yes)
			(layer "F.Fab")
			(hide yes)
			(effects
				(font
					(size 1 1)
					(thickness 0.15)
				)
			)
		)
		(property "License" "Apache-2.0"
			(at 0 0 180)
			(unlocked yes)
			(layer "F.Fab")
			(hide yes)
			(effects
				(font
					(size 1 1)
					(thickness 0.15)
				)
			)
		)
		(property "Author" "Antmicro"
			(at 0 0 180)
			(unlocked yes)
			(layer "F.Fab")
			(hide yes)
			(effects
				(font
					(size 1 1)
					(thickness 0.15)
				)
			)
		)
		(property "Val" "100k"
			(at 0 0 180)
			(unlocked yes)
			(layer "F.Fab")
			(hide yes)
			(effects
				(font
					(size 1 1)
					(thickness 0.15)
				)
			)
		)
		(property "Tolerance" "1%"
			(at 0 0 180)
			(unlocked yes)
			(layer "F.Fab")
			(hide yes)
			(effects
				(font
					(size 1 1)
					(thickness 0.15)
				)
			)
		)
		(sheetname "/SoM_IO2/")
		(sheetfile "som_io2.kicad_sch")
		(attr smd)
		(fp_poly
			(pts
				(xy -0.925 -0.47) (xy -0.925 0.47) (xy 0.925 0.47) (xy 0.925 -0.47)
			)
			(stroke
				(width 0.05)
				(type default)
			)
			(fill no)
			(layer "F.CrtYd")
		)
		(fp_poly
			(pts
				(xy -0.5 -0.25) (xy -0.5 0.25) (xy 0.5 0.25) (xy 0.5 -0.25)
			)
			(stroke
				(width 0.15)
				(type solid)
			)
			(fill no)
			(layer "F.Fab")
		)
		(fp_text user "${REFERENCE}"
			(at -0.95 3.168 0)
			(layer "F.Fab")
			(effects
				(font
					(size 0.7 0.7)
					(thickness 0.15)
				)
				(justify right top)
			)
		)
		(fp_text user "License: Apache-2.0"
			(at -0.949999 5.169 0)
			(layer "F.Fab")
			(effects
				(font
					(size 0.7 0.7)
					(thickness 0.15)
				)
				(justify right top)
			)
		)
		(fp_text user "Author: Antmicro"
			(at -0.95 4.169 0)
			(layer "F.Fab")
			(effects
				(font
					(size 0.7 0.7)
					(thickness 0.15)
				)
				(justify right top)
			)
		)
		(pad "1" smd roundrect
			(at -0.48 0 180)
			(size 0.59 0.64)
			(layers "F.Cu" "F.Mask" "F.Paste")
			(roundrect_rratio 0.25)
			(net 2 "+3V3")
			(pintype "passive")
		)
		(pad "2" smd roundrect
			(at 0.48 0 180)
			(size 0.59 0.64)
			(layers "F.Cu" "F.Mask" "F.Paste")
			(roundrect_rratio 0.25)
			(net 893 "Net-(Y1-EN)")
			(pintype "passive")
		)
	)
	(footprint "antmicro-footprints:C_0402_1005Metric"
		(layer "F.Cu")
		(at 193.126 148.1 180)
		(descr "Capacitor SMD 0402")
		(tags "capacitor SMD 0402")
		(property "Reference" "C58"
			(at 3.1 -0.5 180)
			(layer "F.SilkS")
			(effects
				(font
					(size 0.7 0.7)
					(thickness 0.15)
				)
				(justify left bottom)
			)
		)
		(property "Value" "C_100n_0402"
			(at -1.022927 2.155213 180)
			(layer "F.Fab")
			(effects
				(font
					(size 0.7 0.7)
					(thickness 0.15)
				)
				(justify left bottom)
			)
		)
		(property "Datasheet" "https://www.murata.com/products/productdetail?partno=GRM155R61H104KE14%23"
			(at 0 0 180)
			(layer "F.Fab")
			(hide yes)
			(effects
				(font
					(size 1.27 1.27)
					(thickness 0.15)
				)
			)
		)
		(property "Description" "SMD Multilayer Ceramic Capacitor, 0.1 µF, 50 V, 0402 [1005 Metric], ± 10%, X5R, GRM Series"
			(at 0 0 180)
			(layer "F.Fab")
			(hide yes)
			(effects
				(font
					(size 1.27 1.27)
					(thickness 0.15)
				)
			)
		)
		(property "Manufacturer" "Murata"
			(at 0 0 180)
			(unlocked yes)
			(layer "F.Fab")
			(hide yes)
			(effects
				(font
					(size 1 1)
					(thickness 0.15)
				)
			)
		)
		(property "MPN" "GRM155R61H104KE14D"
			(at 0 0 180)
			(unlocked yes)
			(layer "F.Fab")
			(hide yes)
			(effects
				(font
					(size 1 1)
					(thickness 0.15)
				)
			)
		)
		(property "Val" "100n"
			(at 0 0 180)
			(unlocked yes)
			(layer "F.Fab")
			(hide yes)
			(effects
				(font
					(size 1 1)
					(thickness 0.15)
				)
			)
		)
		(property "License" "Apache-2.0"
			(at 0 0 180)
			(unlocked yes)
			(layer "F.Fab")
			(hide yes)
			(effects
				(font
					(size 1 1)
					(thickness 0.15)
				)
			)
		)
		(property "Author" "Antmicro"
			(at 0 0 180)
			(unlocked yes)
			(layer "F.Fab")
			(hide yes)
			(effects
				(font
					(size 1 1)
					(thickness 0.15)
				)
			)
		)
		(property "Voltage" "50V"
			(at 0 0 180)
			(unlocked yes)
			(layer "F.Fab")
			(hide yes)
			(effects
				(font
					(size 1 1)
					(thickness 0.15)
				)
			)
		)
		(property "Dielectric" "X5R"
			(at 0 0 180)
			(unlocked yes)
			(layer "F.Fab")
			(hide yes)
			(effects
				(font
					(size 1 1)
					(thickness 0.15)
				)
			)
		)
		(property "Public" "False"
			(at 0 0 180)
			(unlocked yes)
			(layer "F.Fab")
			(hide yes)
			(effects
				(font
					(size 1 1)
					(thickness 0.15)
				)
			)
		)
		(sheetname "/SFP/")
		(sheetfile "sfp.kicad_sch")
		(attr smd)
		(fp_rect
			(start -0.925 -0.47)
			(end 0.925 0.47)
			(stroke
				(width 0.05)
				(type default)
			)
			(fill no)
			(layer "F.CrtYd")
		)
		(fp_line
			(start 0.504 0.248)
			(end -0.494 0.248)
			(stroke
				(width 0.15)
				(type solid)
			)
			(layer "F.Fab")
		)
		(fp_line
			(start 0.504 -0.25)
			(end 0.504 0.248)
			(stroke
				(width 0.15)
				(type solid)
			)
			(layer "F.Fab")
		)
		(fp_line
			(start -0.494 0.248)
			(end -0.494 -0.25)
			(stroke
				(width 0.15)
				(type solid)
			)
			(layer "F.Fab")
		)
		(fp_line
			(start -0.494 -0.25)
			(end 0.504 -0.25)
			(stroke
				(width 0.15)
				(type solid)
			)
			(layer "F.Fab")
		)
		(fp_text user "License: Apache-2.0"
			(at -0.939 5.799 180)
			(layer "F.Fab")
			(effects
				(font
					(size 0.7 0.7)
					(thickness 0.15)
				)
				(justify left bottom)
			)
		)
		(fp_text user "Author: Antmicro"
			(at -0.939 3.399 180)
			(layer "F.Fab")
			(effects
				(font
					(size 0.7 0.7)
					(thickness 0.15)
				)
				(justify left bottom)
			)
		)
		(fp_text user "${REFERENCE}"
			(at -0.939 4.599 180)
			(layer "F.Fab")
			(effects
				(font
					(size 0.7 0.7)
					(thickness 0.15)
				)
				(justify left bottom)
			)
		)
		(pad "1" smd roundrect
			(at -0.48 0 180)
			(size 0.59 0.64)
			(layers "F.Cu" "F.Mask" "F.Paste")
			(roundrect_rratio 0.25)
			(net 22 "/SFP/SFI_CONN_TX_N")
			(pintype "passive")
		)
		(pad "2" smd roundrect
			(at 0.48 0 180)
			(size 0.59 0.64)
			(layers "F.Cu" "F.Mask" "F.Paste")
			(roundrect_rratio 0.25)
			(net 132 "/SFP/SFI.TX-")
			(pintype "passive")
		)
	)
	(footprint "antmicro-footprints:R_0402_1005Metric"
		(layer "F.Cu")
		(at 181.513471 124.197356 -90)
		(descr "Resistor SMD 0402")
		(tags "resistor SMD 0402")
		(property "Reference" "R43"
			(at -6.297356 -3.086529 90)
			(layer "F.SilkS")
			(effects
				(font
					(size 0.7 0.7)
					(thickness 0.15)
				)
				(justify right top)
			)
		)
		(property "Value" "R_200k_0402"
			(at -1.011843 1.772047 90)
			(layer "F.Fab")
			(effects
				(font
					(size 0.7 0.7)
					(thickness 0.15)
				)
				(justify right top)
			)
		)
		(property "Datasheet" "https://www.bourns.com/docs/product-datasheets/cr.pdf"
			(at 0 0 90)
			(layer "F.Fab")
			(hide yes)
			(effects
				(font
					(size 1.27 1.27)
					(thickness 0.15)
				)
			)
		)
		(property "Description" "SMD Chip Resistor, 200 kohm, ± 1%, 62.5 mW, 0402 [1005 Metric], Thick Film, General Purpose"
			(at 0 0 90)
			(layer "F.Fab")
			(hide yes)
			(effects
				(font
					(size 1.27 1.27)
					(thickness 0.15)
				)
			)
		)
		(property "MPN" "CR0402-FX-2003GLF"
			(at 0 0 270)
			(unlocked yes)
			(layer "F.Fab")
			(hide yes)
			(effects
				(font
					(size 1 1)
					(thickness 0.15)
				)
			)
		)
		(property "Manufacturer" "Bourns"
			(at 0 0 270)
			(unlocked yes)
			(layer "F.Fab")
			(hide yes)
			(effects
				(font
					(size 1 1)
					(thickness 0.15)
				)
			)
		)
		(property "License" "Apache-2.0"
			(at 0 0 270)
			(unlocked yes)
			(layer "F.Fab")
			(hide yes)
			(effects
				(font
					(size 1 1)
					(thickness 0.15)
				)
			)
		)
		(property "Author" "Antmicro"
			(at 0 0 270)
			(unlocked yes)
			(layer "F.Fab")
			(hide yes)
			(effects
				(font
					(size 1 1)
					(thickness 0.15)
				)
			)
		)
		(property "Val" "200k"
			(at 0 0 270)
			(unlocked yes)
			(layer "F.Fab")
			(hide yes)
			(effects
				(font
					(size 1 1)
					(thickness 0.15)
				)
			)
		)
		(property "Tolerance" "1%"
			(at 0 0 270)
			(unlocked yes)
			(layer "F.Fab")
			(hide yes)
			(effects
				(font
					(size 1 1)
					(thickness 0.15)
				)
			)
		)
		(sheetname "/DCDC/")
		(sheetfile "dcdc.kicad_sch")
		(attr smd)
		(fp_rect
			(start -0.925 -0.47)
			(end 0.925 0.47)
			(stroke
				(width 0.05)
				(type default)
			)
			(fill no)
			(layer "F.CrtYd")
		)
		(fp_rect
			(start -0.5 -0.25)
			(end 0.5 0.25)
			(stroke
				(width 0.15)
				(type solid)
			)
			(fill no)
			(layer "F.Fab")
		)
		(fp_text user "License: Apache-2.0"
			(at -0.95 5.169 90)
			(layer "F.Fab")
			(effects
				(font
					(size 0.7 0.7)
					(thickness 0.15)
				)
				(justify right top)
			)
		)
		(fp_text user "Author: Antmicro"
			(at -0.95 4.169 90)
			(layer "F.Fab")
			(effects
				(font
					(size 0.7 0.7)
					(thickness 0.15)
				)
				(justify right top)
			)
		)
		(fp_text user "${REFERENCE}"
			(at -0.95 3.168 90)
			(layer "F.Fab")
			(effects
				(font
					(size 0.7 0.7)
					(thickness 0.15)
				)
				(justify right top)
			)
		)
		(pad "1" smd roundrect
			(at -0.48 0 270)
			(size 0.59 0.64)
			(layers "F.Cu" "F.Mask" "F.Paste")
			(roundrect_rratio 0.25)
			(net 1 "GND")
			(pintype "passive")
		)
		(pad "2" smd roundrect
			(at 0.48 0 270)
			(size 0.59 0.64)
			(layers "F.Cu" "F.Mask" "F.Paste")
			(roundrect_rratio 0.25)
			(net 1216 "/DCDC/3V3_MODE2")
			(pintype "passive")
		)
	)
	(footprint "antmicro-footprints:C_0402_1005Metric"
		(layer "F.Cu")
		(at 89.55 146.411499 -90)
		(descr "Capacitor SMD 0402")
		(tags "capacitor SMD 0402")
		(property "Reference" "C11"
			(at -3.05 0.33 90)
			(layer "F.SilkS")
			(effects
				(font
					(size 0.7 0.7)
					(thickness 0.15)
				)
				(justify right top)
			)
		)
		(property "Value" "C_100n_0402"
			(at -1.022927 2.155213 90)
			(layer "F.Fab")
			(effects
				(font
					(size 0.7 0.7)
					(thickness 0.15)
				)
				(justify right top)
			)
		)
		(property "Datasheet" "https://www.murata.com/products/productdetail?partno=GRM155R61H104KE14%23"
			(at 0 0 90)
			(layer "F.Fab")
			(hide yes)
			(effects
				(font
					(size 1.27 1.27)
					(thickness 0.15)
				)
			)
		)
		(property "Description" "SMD Multilayer Ceramic Capacitor, 0.1 µF, 50 V, 0402 [1005 Metric], ± 10%, X5R, GRM Series"
			(at 0 0 90)
			(layer "F.Fab")
			(hide yes)
			(effects
				(font
					(size 1.27 1.27)
					(thickness 0.15)
				)
			)
		)
		(property "MPN" "GRM155R61H104KE14D"
			(at 0 0 270)
			(unlocked yes)
			(layer "F.Fab")
			(hide yes)
			(effects
				(font
					(size 1 1)
					(thickness 0.15)
				)
			)
		)
		(property "Manufacturer" "Murata"
			(at 0 0 270)
			(unlocked yes)
			(layer "F.Fab")
			(hide yes)
			(effects
				(font
					(size 1 1)
					(thickness 0.15)
				)
			)
		)
		(property "License" "Apache-2.0"
			(at 0 0 270)
			(unlocked yes)
			(layer "F.Fab")
			(hide yes)
			(effects
				(font
					(size 1 1)
					(thickness 0.15)
				)
			)
		)
		(property "Author" "Antmicro"
			(at 0 0 270)
			(unlocked yes)
			(layer "F.Fab")
			(hide yes)
			(effects
				(font
					(size 1 1)
					(thickness 0.15)
				)
			)
		)
		(property "Val" "100n"
			(at 0 0 270)
			(unlocked yes)
			(layer "F.Fab")
			(hide yes)
			(effects
				(font
					(size 1 1)
					(thickness 0.15)
				)
			)
		)
		(property "Voltage" "50V"
			(at 0 0 270)
			(unlocked yes)
			(layer "F.Fab")
			(hide yes)
			(effects
				(font
					(size 1 1)
					(thickness 0.15)
				)
			)
		)
		(property "Dielectric" "X5R"
			(at 0 0 270)
			(unlocked yes)
			(layer "F.Fab")
			(hide yes)
			(effects
				(font
					(size 1 1)
					(thickness 0.15)
				)
			)
		)
		(sheetname "/SoM_IO2/")
		(sheetfile "som_io2.kicad_sch")
		(attr smd)
		(fp_poly
			(pts
				(xy -0.925 -0.47) (xy -0.925 0.47) (xy 0.925 0.47) (xy 0.925 -0.47)
			)
			(stroke
				(width 0.05)
				(type default)
			)
			(fill no)
			(layer "F.CrtYd")
		)
		(fp_line
			(start -0.494 0.248)
			(end -0.494 -0.25)
			(stroke
				(width 0.15)
				(type solid)
			)
			(layer "F.Fab")
		)
		(fp_line
			(start 0.504 0.248)
			(end -0.494 0.248)
			(stroke
				(width 0.15)
				(type solid)
			)
			(layer "F.Fab")
		)
		(fp_line
			(start -0.494 -0.25)
			(end 0.504 -0.25)
			(stroke
				(width 0.15)
				(type solid)
			)
			(layer "F.Fab")
		)
		(fp_line
			(start 0.504 -0.25)
			(end 0.504 0.248)
			(stroke
				(width 0.15)
				(type solid)
			)
			(layer "F.Fab")
		)
		(fp_text user "Author: Antmicro"
			(at -0.939 3.399 90)
			(layer "F.Fab")
			(effects
				(font
					(size 0.7 0.7)
					(thickness 0.15)
				)
				(justify right top)
			)
		)
		(fp_text user "${REFERENCE}"
			(at -0.939 4.599 90)
			(layer "F.Fab")
			(effects
				(font
					(size 0.7 0.7)
					(thickness 0.15)
				)
				(justify right top)
			)
		)
		(fp_text user "License: Apache-2.0"
			(at -0.939 5.799 90)
			(layer "F.Fab")
			(effects
				(font
					(size 0.7 0.7)
					(thickness 0.15)
				)
				(justify right top)
			)
		)
		(pad "1" smd roundrect
			(at -0.48 0 270)
			(size 0.59 0.64)
			(layers "F.Cu" "F.Mask" "F.Paste")
			(roundrect_rratio 0.25)
			(net 1 "GND")
			(pintype "passive")
		)
		(pad "2" smd roundrect
			(at 0.48 0 270)
			(size 0.59 0.64)
			(layers "F.Cu" "F.Mask" "F.Paste")
			(roundrect_rratio 0.25)
			(net 2 "+3V3")
			(pintype "passive")
		)
	)
	(footprint "antmicro-footprints:SOT-523"
		(layer "F.Cu")
		(at 83.51 59.75 -90)
		(property "Reference" "Q17"
			(at 1.25 -1.69 180)
			(layer "F.SilkS")
			(effects
				(font
					(size 0.7 0.7)
					(thickness 0.15)
				)
				(justify right top)
			)
		)
		(property "Value" "DMG1012T-7"
			(at 0.1 1.824 90)
			(layer "F.Fab")
			(effects
				(font
					(size 0.7 0.7)
					(thickness 0.15)
				)
				(justify right top)
			)
		)
		(property "Datasheet" "https://www.diodes.com/assets/Datasheets/ds31783.pdf"
			(at 0 0 90)
			(layer "F.Fab")
			(hide yes)
			(effects
				(font
					(size 1.27 1.27)
					(thickness 0.15)
				)
			)
		)
		(property "Description" "Power MOSFET, N Channel, 20 V, 630 mA, 0.3 ohm, SOT-523, Surface Mount"
			(at 0 0 90)
			(layer "F.Fab")
			(hide yes)
			(effects
				(font
					(size 1.27 1.27)
					(thickness 0.15)
				)
			)
		)
		(property "MPN" "DMG1012T-7"
			(at 0 0 270)
			(unlocked yes)
			(layer "F.Fab")
			(hide yes)
			(effects
				(font
					(size 1 1)
					(thickness 0.15)
				)
			)
		)
		(property "Manufacturer" "Diodes Incorporated"
			(at 0 0 270)
			(unlocked yes)
			(layer "F.Fab")
			(hide yes)
			(effects
				(font
					(size 1 1)
					(thickness 0.15)
				)
			)
		)
		(property "Author" "Antmicro"
			(at 0 0 270)
			(unlocked yes)
			(layer "F.Fab")
			(hide yes)
			(effects
				(font
					(size 1 1)
					(thickness 0.15)
				)
			)
		)
		(property "License" "Apache-2.0"
			(at 0 0 270)
			(unlocked yes)
			(layer "F.Fab")
			(hide yes)
			(effects
				(font
					(size 1 1)
					(thickness 0.15)
				)
			)
		)
		(sheetname "/SoM_Power/")
		(sheetfile "som_power.kicad_sch")
		(attr smd)
		(fp_line
			(start -0.927 -0.051)
			(end -0.927 -0.351)
			(stroke
				(width 0.15)
				(type solid)
			)
			(layer "F.SilkS")
		)
		(fp_line
			(start -0.927 -0.351)
			(end -0.725 -0.551)
			(stroke
				(width 0.15)
				(type solid)
			)
			(layer "F.SilkS")
		)
		(fp_line
			(start -0.725 -0.551)
			(end -0.277 -0.551)
			(stroke
				(width 0.15)
				(type solid)
			)
			(layer "F.SilkS")
		)
		(fp_line
			(start -0.277 -0.551)
			(end -0.277 -0.75)
			(stroke
				(width 0.15)
				(type solid)
			)
			(layer "F.SilkS")
		)
		(fp_circle
			(center -0.9652 0.9652)
			(end -0.9152 0.9652)
			(stroke
				(width 0.15)
				(type solid)
			)
			(fill yes)
			(layer "F.SilkS")
		)
		(fp_line
			(start -1.12 1.15)
			(end 1.1 1.15)
			(stroke
				(width 0.05)
				(type solid)
			)
			(layer "F.CrtYd")
		)
		(fp_line
			(start -1.12 -1.16)
			(end -1.12 1.15)
			(stroke
				(width 0.05)
				(type solid)
			)
			(layer "F.CrtYd")
		)
		(fp_line
			(start -1.12 -1.16)
			(end 1.1 -1.16)
			(stroke
				(width 0.05)
				(type solid)
			)
			(layer "F.CrtYd")
		)
		(fp_line
			(start 1.1 -1.16)
			(end 1.1 1.15)
			(stroke
				(width 0.05)
				(type solid)
			)
			(layer "F.CrtYd")
		)
		(fp_line
			(start 0.8 0.424)
			(end -0.802 0.424)
			(stroke
				(width 0.15)
				(type solid)
			)
			(layer "F.Fab")
		)
		(fp_line
			(start -0.802 -0.276)
			(end -0.802 0.424)
			(stroke
				(width 0.15)
				(type solid)
			)
			(layer "F.Fab")
		)
		(fp_line
			(start -0.652 -0.425)
			(end -0.802 -0.276)
			(stroke
				(width 0.15)
				(type solid)
			)
			(layer "F.Fab")
		)
		(fp_line
			(start 0.8 -0.425)
			(end 0.8 0.424)
			(stroke
				(width 0.15)
				(type solid)
			)
			(layer "F.Fab")
		)
		(fp_line
			(start 0.8 -0.425)
			(end -0.652 -0.425)
			(stroke
				(width 0.15)
				(type solid)
			)
			(layer "F.Fab")
		)
		(fp_circle
			(center -0.9652 0.9652)
			(end -0.9144 0.9652)
			(stroke
				(width 0.15)
				(type solid)
			)
			(fill no)
			(layer "F.Fab")
		)
		(fp_text user "${REFERENCE}"
			(at -1.12 3.824 90)
			(layer "F.Fab")
			(effects
				(font
					(size 0.7 0.7)
					(thickness 0.15)
				)
				(justify right top)
			)
		)
		(fp_text user "License: Apache-2.0"
			(at -1.12 5.024 90)
			(layer "F.Fab")
			(effects
				(font
					(size 0.7 0.7)
					(thickness 0.15)
				)
				(justify right top)
			)
		)
		(fp_text user "Author: Antmicro"
			(at -1.12 6.224 90)
			(layer "F.Fab")
			(effects
				(font
					(size 0.7 0.7)
					(thickness 0.15)
				)
				(justify right top)
			)
		)
		(pad "1" smd rect
			(at -0.5 0.65 270)
			(size 0.4 0.51)
			(layers "F.Cu" "F.Mask" "F.Paste")
			(net 11 "+1V8")
			(pinfunction "G")
			(pintype "input")
		)
		(pad "2" smd rect
			(at 0.498 0.65 270)
			(size 0.4 0.51)
			(layers "F.Cu" "F.Mask" "F.Paste")
			(net 605 "/SoM_Power/~{MODULE_SHDN}")
			(pinfunction "S")
			(pintype "passive")
		)
		(pad "3" smd rect
			(at 0 -0.652 270)
			(size 0.4 0.51)
			(layers "F.Cu" "F.Mask" "F.Paste")
			(net 887 "Net-(Q17-D)")
			(pinfunction "D")
			(pintype "passive")
		)
	)
	(footprint "antmicro-footprints:SOT-23-8"
		(layer "F.Cu")
		(at 161.322234 81.952234 -90)
		(descr "http://www.ti.com/lit/ds/symlink/ina219.pdf")
		(property "Reference" "U66"
			(at -1.65 2.76 90)
			(layer "F.SilkS")
			(effects
				(font
					(size 0.7 0.7)
					(thickness 0.15)
				)
				(justify right top)
			)
		)
		(property "Value" "INA219AIDCNR"
			(at -2.925 2.8 90)
			(layer "F.Fab")
			(effects
				(font
					(size 0.7 0.7)
					(thickness 0.15)
				)
				(justify right top)
			)
		)
		(property "Datasheet" "https://www.ti.com/lit/ds/symlink/ina219.pdf?ts=1713856455637&ref_url=https%253A%252F%252Fwww.mouser.es%252F"
			(at 0 0 90)
			(layer "F.Fab")
			(hide yes)
			(effects
				(font
					(size 1.27 1.27)
					(thickness 0.15)
				)
			)
		)
		(property "Description" "Zerø-Drift, Bidirectional Current/Power Monitor With I2C Interface"
			(at 0 0 90)
			(layer "F.Fab")
			(hide yes)
			(effects
				(font
					(size 1.27 1.27)
					(thickness 0.15)
				)
			)
		)
		(property "Manufacturer" "Texas Instruments"
			(at 0 0 270)
			(unlocked yes)
			(layer "F.Fab")
			(hide yes)
			(effects
				(font
					(size 1 1)
					(thickness 0.15)
				)
			)
		)
		(property "MPN" "INA219AIDCNR"
			(at 0 0 270)
			(unlocked yes)
			(layer "F.Fab")
			(hide yes)
			(effects
				(font
					(size 1 1)
					(thickness 0.15)
				)
			)
		)
		(property "Author" "Antmicro"
			(at 0 0 270)
			(unlocked yes)
			(layer "F.Fab")
			(hide yes)
			(effects
				(font
					(size 1 1)
					(thickness 0.15)
				)
			)
		)
		(property "License" "Apache-2.0"
			(at 0 0 270)
			(unlocked yes)
			(layer "F.Fab")
			(hide yes)
			(effects
				(font
					(size 1 1)
					(thickness 0.15)
				)
			)
		)
		(component_classes
			(class "DCDC_20V")
		)
		(sheetname "/DCDC/")
		(sheetfile "dcdc.kicad_sch")
		(attr smd)
		(fp_line
			(start -0.987 1.6)
			(end -0.987 1.324)
			(stroke
				(width 0.15)
				(type solid)
			)
			(layer "F.SilkS")
		)
		(fp_line
			(start -0.613 1.6)
			(end -0.987 1.6)
			(stroke
				(width 0.15)
				(type solid)
			)
			(layer "F.SilkS")
		)
		(fp_line
			(start 1 1.6)
			(end 0.6 1.6)
			(stroke
				(width 0.15)
				(type solid)
			)
			(layer "F.SilkS")
		)
		(fp_line
			(start 1 1.3)
			(end 1 1.6)
			(stroke
				(width 0.15)
				(type solid)
			)
			(layer "F.SilkS")
		)
		(fp_line
			(start -1 -1.3)
			(end -1 -1.6)
			(stroke
				(width 0.15)
				(type solid)
			)
			(layer "F.SilkS")
		)
		(fp_line
			(start 1 -1.3)
			(end 1 -1.6)
			(stroke
				(width 0.15)
				(type solid)
			)
			(layer "F.SilkS")
		)
		(fp_line
			(start -1 -1.6)
			(end -0.6 -1.6)
			(stroke
				(width 0.15)
				(type solid)
			)
			(layer "F.SilkS")
		)
		(fp_line
			(start 1 -1.6)
			(end 0.625 -1.6)
			(stroke
				(width 0.15)
				(type solid)
			)
			(layer "F.SilkS")
		)
		(fp_circle
			(center -1.3 -1.4)
			(end -1.25 -1.4)
			(stroke
				(width 0.15)
				(type solid)
			)
			(fill yes)
			(layer "F.SilkS")
		)
		(fp_rect
			(start -1.9 -1.75)
			(end 1.898 1.75)
			(stroke
				(width 0.05)
				(type solid)
			)
			(fill no)
			(layer "F.CrtYd")
		)
		(fp_line
			(start -1.4 -1.25)
			(end -1.2 -1.45)
			(stroke
				(width 0.15)
				(type solid)
			)
			(layer "F.Fab")
		)
		(fp_rect
			(start -1.401 -1.45)
			(end 1.398 1.449)
			(stroke
				(width 0.15)
				(type solid)
			)
			(fill no)
			(layer "F.Fab")
		)
		(fp_text user "Author: Antmicro"
			(at -2.925 7.2 90)
			(layer "F.Fab")
			(effects
				(font
					(size 0.7 0.7)
					(thickness 0.15)
				)
				(justify right top)
			)
		)
		(fp_text user "${REFERENCE}"
			(at -2.925 4.8 90)
			(layer "F.Fab")
			(effects
				(font
					(size 0.7 0.7)
					(thickness 0.15)
				)
				(justify right top)
			)
		)
		(fp_text user "License: Apache-2.0"
			(at -2.925 6 90)
			(layer "F.Fab")
			(effects
				(font
					(size 0.7 0.7)
					(thickness 0.15)
				)
				(justify right top)
			)
		)
		(pad "1" smd roundrect
			(at -1.3 -0.975 180)
			(size 0.45 1.1)
			(layers "F.Cu" "F.Mask" "F.Paste")
			(roundrect_rratio 0.25)
			(net 1284 "Net-(U66-IN+)")
			(pinfunction "IN+")
			(pintype "passive")
		)
		(pad "2" smd roundrect
			(at -1.3 -0.325 180)
			(size 0.45 1.1)
			(layers "F.Cu" "F.Mask" "F.Paste")
			(roundrect_rratio 0.25)
			(net 1221 "Net-(U66-IN-)")
			(pinfunction "IN-")
			(pintype "passive")
		)
		(pad "3" smd roundrect
			(at -1.3 0.325 180)
			(size 0.45 1.1)
			(layers "F.Cu" "F.Mask" "F.Paste")
			(roundrect_rratio 0.25)
			(net 1 "GND")
			(pinfunction "GND")
			(pintype "power_in")
		)
		(pad "4" smd roundrect
			(at -1.3 0.975 180)
			(size 0.45 1.1)
			(layers "F.Cu" "F.Mask" "F.Paste")
			(roundrect_rratio 0.25)
			(net 4 "+3V3_AON")
			(pinfunction "V_{S}")
			(pintype "power_in")
		)
		(pad "5" smd roundrect
			(at 1.3 0.975 180)
			(size 0.45 1.1)
			(layers "F.Cu" "F.Mask" "F.Paste")
			(roundrect_rratio 0.25)
			(net 853 "/I2C_{SYS}.SCL")
			(pinfunction "SCL")
			(pintype "open_collector")
		)
		(pad "6" smd roundrect
			(at 1.3 0.325 180)
			(size 0.45 1.1)
			(layers "F.Cu" "F.Mask" "F.Paste")
			(roundrect_rratio 0.25)
			(net 850 "/I2C_{SYS}.SDA")
			(pinfunction "SDA")
			(pintype "open_collector")
		)
		(pad "7" smd roundrect
			(at 1.3 -0.325 180)
			(size 0.45 1.1)
			(layers "F.Cu" "F.Mask" "F.Paste")
			(roundrect_rratio 0.25)
			(net 853 "/I2C_{SYS}.SCL")
			(pinfunction "A0")
			(pintype "passive")
		)
		(pad "8" smd roundrect
			(at 1.3 -0.975 180)
			(size 0.45 1.1)
			(layers "F.Cu" "F.Mask" "F.Paste")
			(roundrect_rratio 0.25)
			(net 1 "GND")
			(pinfunction "A1")
			(pintype "passive")
		)
	)
	(footprint "antmicro-footprints:Spacer_Drill4.45mm_H4mm_9774040960R"
		(locked yes)
		(layer "F.Cu")
		(at 76.930532 57.71 90)
		(property "Reference" "H6"
			(at -0.89 4.969468 90)
			(layer "F.SilkS")
			(effects
				(font
					(size 0.7 0.7)
					(thickness 0.15)
				)
				(justify left bottom)
			)
		)
		(property "Value" "Spacer_Drill4.45mm_H4mm_9774040960R"
			(at -3.95 5.05 90)
			(layer "F.Fab")
			(effects
				(font
					(size 0.7 0.7)
					(thickness 0.15)
				)
				(justify left bottom)
			)
		)
		(property "Datasheet" "https://www.we-online.com/components/products/datasheet/9774040960R.pdf"
			(at 0 0 90)
			(layer "F.Fab")
			(effects
				(font
					(size 0.7 0.7)
					(thickness 0.15)
				)
				(justify left bottom)
			)
		)
		(property "Description" "Spacer, SMT, Non Stop, Steel, Swage Round, 6 mm x 4 mm, 3.3 mm Internal, WA-SMST Series"
			(at 0 0 90)
			(layer "F.Fab")
			(effects
				(font
					(size 0.7 0.7)
					(thickness 0.15)
				)
				(justify left bottom)
			)
		)
		(property "Manufacturer" "Würth Elektronik"
			(at 0 0 90)
			(unlocked yes)
			(layer "F.Fab")
			(hide yes)
			(effects
				(font
					(size 1 1)
					(thickness 0.15)
				)
			)
		)
		(property "MPN" "9774040960R"
			(at 0 0 90)
			(unlocked yes)
			(layer "F.Fab")
			(hide yes)
			(effects
				(font
					(size 1 1)
					(thickness 0.15)
				)
			)
		)
		(property "Author" "Antmicro"
			(at 0 0 90)
			(unlocked yes)
			(layer "F.Fab")
			(hide yes)
			(effects
				(font
					(size 1 1)
					(thickness 0.15)
				)
			)
		)
		(property "License" "Apache-2.0"
			(at 0 0 90)
			(unlocked yes)
			(layer "F.Fab")
			(hide yes)
			(effects
				(font
					(size 1 1)
					(thickness 0.15)
				)
			)
		)
		(sheetname "/SoM_Power/")
		(sheetfile "som_power.kicad_sch")
		(attr smd)
		(fp_rect
			(start -3.95 -3.95)
			(end 3.95 3.95)
			(stroke
				(width 0.05)
				(type solid)
			)
			(fill no)
			(layer "F.CrtYd")
		)
		(fp_circle
			(center 0 0)
			(end 3.25 0)
			(stroke
				(width 0.05)
				(type solid)
			)
			(fill no)
			(layer "F.CrtYd")
		)
		(fp_circle
			(center 0 0)
			(end 2.564 0)
			(stroke
				(width 0.15)
				(type solid)
			)
			(fill no)
			(layer "F.Fab")
		)
		(fp_text user "${REFERENCE}"
			(at -3.95 7.45 90)
			(layer "F.Fab")
			(effects
				(font
					(size 0.7 0.7)
					(thickness 0.15)
				)
				(justify left bottom)
			)
		)
		(fp_text user "Author: Antmicro"
			(at -3.95 8.65 90)
			(layer "F.Fab")
			(effects
				(font
					(size 0.7 0.7)
					(thickness 0.15)
				)
				(justify left bottom)
			)
		)
		(fp_text user "License: Apache-2.0"
			(at -3.95 6.25 90)
			(layer "F.Fab")
			(effects
				(font
					(size 0.7 0.7)
					(thickness 0.15)
				)
				(justify left bottom)
			)
		)
		(pad "" smd custom
			(at -2.55 -0.55 212.5)
			(size 0.1 0.1)
			(layers "F.Paste")
			(options
				(clearance outline)
				(anchor circle)
			)
			(primitives
				(gr_arc
					(start 0 0)
					(mid 0.704278 1.28373)
					(end 0.608513 2.744826)
					(width 0.7)
				)
			)
		)
		(pad "" smd custom
			(at -0.55 2.55 302.5)
			(size 0.1 0.1)
			(layers "F.Paste")
			(options
				(clearance outline)
				(anchor circle)
			)
			(primitives
				(gr_arc
					(start 0 0)
					(mid 0.704278 1.28373)
					(end 0.608513 2.744826)
					(width 0.7)
				)
			)
		)
		(pad "" smd custom
			(at 0.55 -2.55 122.5)
			(size 0.1 0.1)
			(layers "F.Paste")
			(options
				(clearance outline)
				(anchor circle)
			)
			(primitives
				(gr_arc
					(start 0 0)
					(mid 0.704278 1.28373)
					(end 0.608513 2.744826)
					(width 0.7)
				)
			)
		)
		(pad "" smd custom
			(at 2.55 0.55 32.5)
			(size 0.1 0.1)
			(layers "F.Paste")
			(options
				(clearance outline)
				(anchor circle)
			)
			(primitives
				(gr_arc
					(start 0 0)
					(mid 0.704278 1.28373)
					(end 0.608513 2.744826)
					(width 0.7)
				)
			)
		)
		(pad "1" thru_hole circle
			(at 0 0 90)
			(size 7.4 7.4)
			(drill 4.45)
			(layers "*.Cu" "*.Mask")
			(remove_unused_layers no)
			(net 1 "GND")
			(pintype "passive")
		)
	)
	(footprint "antmicro-footprints:R_0402_1005Metric"
		(layer "F.Cu")
		(at 195.1 127.3)
		(descr "Resistor SMD 0402")
		(tags "resistor SMD 0402")
		(property "Reference" "R81"
			(at -1.1 5.5 0)
			(layer "F.SilkS")
			(effects
				(font
					(size 0.7 0.7)
					(thickness 0.15)
				)
				(justify left bottom)
			)
		)
		(property "Value" "R_10k_0402"
			(at -1.011843 1.772047 0)
			(layer "F.Fab")
			(effects
				(font
					(size 0.7 0.7)
					(thickness 0.15)
				)
				(justify left bottom)
			)
		)
		(property "Datasheet" "https://www.bourns.com/docs/product-datasheets/cr.pdf"
			(at 0 0 0)
			(layer "F.Fab")
			(hide yes)
			(effects
				(font
					(size 1.27 1.27)
					(thickness 0.15)
				)
			)
		)
		(property "Description" "SMD Chip Resistor, 10 kohm, ± 1%, 62.5 mW, 0402 [1005 Metric], Thick Film, General Purpose"
			(at 0 0 0)
			(layer "F.Fab")
			(hide yes)
			(effects
				(font
					(size 1.27 1.27)
					(thickness 0.15)
				)
			)
		)
		(property "MPN" "CR0402-FX-1002GLF"
			(at 0 0 0)
			(unlocked yes)
			(layer "F.Fab")
			(hide yes)
			(effects
				(font
					(size 1 1)
					(thickness 0.15)
				)
			)
		)
		(property "Manufacturer" "Bourns"
			(at 0 0 0)
			(unlocked yes)
			(layer "F.Fab")
			(hide yes)
			(effects
				(font
					(size 1 1)
					(thickness 0.15)
				)
			)
		)
		(property "License" "Apache-2.0"
			(at 0 0 0)
			(unlocked yes)
			(layer "F.Fab")
			(hide yes)
			(effects
				(font
					(size 1 1)
					(thickness 0.15)
				)
			)
		)
		(property "Author" "Antmicro"
			(at 0 0 0)
			(unlocked yes)
			(layer "F.Fab")
			(hide yes)
			(effects
				(font
					(size 1 1)
					(thickness 0.15)
				)
			)
		)
		(property "Val" "10k"
			(at 0 0 0)
			(unlocked yes)
			(layer "F.Fab")
			(hide yes)
			(effects
				(font
					(size 1 1)
					(thickness 0.15)
				)
			)
		)
		(property "Tolerance" "1%"
			(at 0 0 0)
			(unlocked yes)
			(layer "F.Fab")
			(hide yes)
			(effects
				(font
					(size 1 1)
					(thickness 0.15)
				)
			)
		)
		(sheetname "/USB Hub/")
		(sheetfile "usb_hub.kicad_sch")
		(attr smd)
		(fp_rect
			(start -0.925 -0.47)
			(end 0.925 0.47)
			(stroke
				(width 0.05)
				(type default)
			)
			(fill no)
			(layer "F.CrtYd")
		)
		(fp_rect
			(start -0.5 -0.25)
			(end 0.5 0.25)
			(stroke
				(width 0.15)
				(type solid)
			)
			(fill no)
			(layer "F.Fab")
		)
		(fp_text user "${REFERENCE}"
			(at -0.95 3.168 0)
			(layer "F.Fab")
			(effects
				(font
					(size 0.7 0.7)
					(thickness 0.15)
				)
				(justify left bottom)
			)
		)
		(fp_text user "Author: Antmicro"
			(at -0.95 4.169 0)
			(layer "F.Fab")
			(effects
				(font
					(size 0.7 0.7)
					(thickness 0.15)
				)
				(justify left bottom)
			)
		)
		(fp_text user "License: Apache-2.0"
			(at -0.95 5.169 0)
			(layer "F.Fab")
			(effects
				(font
					(size 0.7 0.7)
					(thickness 0.15)
				)
				(justify left bottom)
			)
		)
		(pad "1" smd roundrect
			(at -0.48 0)
			(size 0.59 0.64)
			(layers "F.Cu" "F.Mask" "F.Paste")
			(roundrect_rratio 0.25)
			(net 2 "+3V3")
			(pintype "passive")
		)
		(pad "2" smd roundrect
			(at 0.48 0)
			(size 0.59 0.64)
			(layers "F.Cu" "F.Mask" "F.Paste")
			(roundrect_rratio 0.25)
			(net 916 "/USB Hub/TEST3")
			(pintype "passive")
		)
	)
	(footprint "antmicro-footprints:SOT-23-8"
		(layer "F.Cu")
		(at 171.49 121.701 -90)
		(descr "http://www.ti.com/lit/ds/symlink/ina219.pdf")
		(property "Reference" "U50"
			(at 1.675 -2.759468 90)
			(layer "F.SilkS")
			(effects
				(font
					(size 0.7 0.7)
					(thickness 0.15)
				)
				(justify left bottom)
			)
		)
		(property "Value" "INA219AIDCNR"
			(at -2.925 2.8 90)
			(layer "F.Fab")
			(effects
				(font
					(size 0.7 0.7)
					(thickness 0.15)
				)
				(justify right top)
			)
		)
		(property "Datasheet" "https://www.ti.com/lit/ds/symlink/ina219.pdf?ts=1713856455637&ref_url=https%253A%252F%252Fwww.mouser.es%252F"
			(at 0 0 90)
			(layer "F.Fab")
			(hide yes)
			(effects
				(font
					(size 1.27 1.27)
					(thickness 0.15)
				)
			)
		)
		(property "Description" "Zerø-Drift, Bidirectional Current/Power Monitor With I2C Interface"
			(at 0 0 90)
			(layer "F.Fab")
			(hide yes)
			(effects
				(font
					(size 1.27 1.27)
					(thickness 0.15)
				)
			)
		)
		(property "Manufacturer" "Texas Instruments"
			(at 0 0 270)
			(unlocked yes)
			(layer "F.Fab")
			(hide yes)
			(effects
				(font
					(size 1 1)
					(thickness 0.15)
				)
			)
		)
		(property "MPN" "INA219AIDCNR"
			(at 0 0 270)
			(unlocked yes)
			(layer "F.Fab")
			(hide yes)
			(effects
				(font
					(size 1 1)
					(thickness 0.15)
				)
			)
		)
		(property "Author" "Antmicro"
			(at 0 0 270)
			(unlocked yes)
			(layer "F.Fab")
			(hide yes)
			(effects
				(font
					(size 1 1)
					(thickness 0.15)
				)
			)
		)
		(property "License" "Apache-2.0"
			(at 0 0 270)
			(unlocked yes)
			(layer "F.Fab")
			(hide yes)
			(effects
				(font
					(size 1 1)
					(thickness 0.15)
				)
			)
		)
		(sheetname "/DCDC/")
		(sheetfile "dcdc.kicad_sch")
		(attr smd)
		(fp_line
			(start -0.987 1.6)
			(end -0.987 1.324)
			(stroke
				(width 0.15)
				(type solid)
			)
			(layer "F.SilkS")
		)
		(fp_line
			(start -0.613 1.6)
			(end -0.987 1.6)
			(stroke
				(width 0.15)
				(type solid)
			)
			(layer "F.SilkS")
		)
		(fp_line
			(start 1 1.6)
			(end 0.6 1.6)
			(stroke
				(width 0.15)
				(type solid)
			)
			(layer "F.SilkS")
		)
		(fp_line
			(start 1 1.3)
			(end 1 1.6)
			(stroke
				(width 0.15)
				(type solid)
			)
			(layer "F.SilkS")
		)
		(fp_line
			(start -1 -1.3)
			(end -1 -1.6)
			(stroke
				(width 0.15)
				(type solid)
			)
			(layer "F.SilkS")
		)
		(fp_line
			(start 1 -1.3)
			(end 1 -1.6)
			(stroke
				(width 0.15)
				(type solid)
			)
			(layer "F.SilkS")
		)
		(fp_line
			(start -1 -1.6)
			(end -0.6 -1.6)
			(stroke
				(width 0.15)
				(type solid)
			)
			(layer "F.SilkS")
		)
		(fp_line
			(start 1 -1.6)
			(end 0.625 -1.6)
			(stroke
				(width 0.15)
				(type solid)
			)
			(layer "F.SilkS")
		)
		(fp_circle
			(center -1.3 -1.4)
			(end -1.25 -1.4)
			(stroke
				(width 0.15)
				(type solid)
			)
			(fill yes)
			(layer "F.SilkS")
		)
		(fp_rect
			(start -1.9 -1.75)
			(end 1.898 1.75)
			(stroke
				(width 0.05)
				(type solid)
			)
			(fill no)
			(layer "F.CrtYd")
		)
		(fp_line
			(start -1.4 -1.25)
			(end -1.2 -1.45)
			(stroke
				(width 0.15)
				(type solid)
			)
			(layer "F.Fab")
		)
		(fp_rect
			(start -1.401 -1.45)
			(end 1.398 1.449)
			(stroke
				(width 0.15)
				(type solid)
			)
			(fill no)
			(layer "F.Fab")
		)
		(fp_text user "License: Apache-2.0"
			(at -2.925 6 90)
			(layer "F.Fab")
			(effects
				(font
					(size 0.7 0.7)
					(thickness 0.15)
				)
				(justify right top)
			)
		)
		(fp_text user "${REFERENCE}"
			(at -2.925 4.8 90)
			(layer "F.Fab")
			(effects
				(font
					(size 0.7 0.7)
					(thickness 0.15)
				)
				(justify right top)
			)
		)
		(fp_text user "Author: Antmicro"
			(at -2.925 7.2 90)
			(layer "F.Fab")
			(effects
				(font
					(size 0.7 0.7)
					(thickness 0.15)
				)
				(justify right top)
			)
		)
		(pad "1" smd roundrect
			(at -1.3 -0.975 180)
			(size 0.45 1.1)
			(layers "F.Cu" "F.Mask" "F.Paste")
			(roundrect_rratio 0.25)
			(net 1281 "Net-(U50-IN+)")
			(pinfunction "IN+")
			(pintype "passive")
		)
		(pad "2" smd roundrect
			(at -1.3 -0.325 180)
			(size 0.45 1.1)
			(layers "F.Cu" "F.Mask" "F.Paste")
			(roundrect_rratio 0.25)
			(net 1161 "Net-(U50-IN-)")
			(pinfunction "IN-")
			(pintype "passive")
		)
		(pad "3" smd roundrect
			(at -1.3 0.325 180)
			(size 0.45 1.1)
			(layers "F.Cu" "F.Mask" "F.Paste")
			(roundrect_rratio 0.25)
			(net 1 "GND")
			(pinfunction "GND")
			(pintype "power_in")
		)
		(pad "4" smd roundrect
			(at -1.3 0.975 180)
			(size 0.45 1.1)
			(layers "F.Cu" "F.Mask" "F.Paste")
			(roundrect_rratio 0.25)
			(net 4 "+3V3_AON")
			(pinfunction "V_{S}")
			(pintype "power_in")
		)
		(pad "5" smd roundrect
			(at 1.3 0.975 180)
			(size 0.45 1.1)
			(layers "F.Cu" "F.Mask" "F.Paste")
			(roundrect_rratio 0.25)
			(net 853 "/I2C_{SYS}.SCL")
			(pinfunction "SCL")
			(pintype "open_collector")
		)
		(pad "6" smd roundrect
			(at 1.3 0.325 180)
			(size 0.45 1.1)
			(layers "F.Cu" "F.Mask" "F.Paste")
			(roundrect_rratio 0.25)
			(net 850 "/I2C_{SYS}.SDA")
			(pinfunction "SDA")
			(pintype "open_collector")
		)
		(pad "7" smd roundrect
			(at 1.3 -0.325 180)
			(size 0.45 1.1)
			(layers "F.Cu" "F.Mask" "F.Paste")
			(roundrect_rratio 0.25)
			(net 4 "+3V3_AON")
			(pinfunction "A0")
			(pintype "passive")
		)
		(pad "8" smd roundrect
			(at 1.3 -0.975 180)
			(size 0.45 1.1)
			(layers "F.Cu" "F.Mask" "F.Paste")
			(roundrect_rratio 0.25)
			(net 1 "GND")
			(pinfunction "A1")
			(pintype "passive")
		)
	)
	(footprint "antmicro-footprints:C_0805_2012Metric"
		(layer "F.Cu")
		(at 174.18 110.356 90)
		(descr "Capacitor SMD 0805")
		(tags "capacitor SMD 0805")
		(property "Reference" "C42"
			(at 1.89 0.41 90)
			(layer "F.SilkS")
			(effects
				(font
					(size 0.7 0.7)
					(thickness 0.15)
				)
				(justify left bottom)
			)
		)
		(property "Value" "C_22u_25V_0805"
			(at -2.055717 1.963152 90)
			(layer "F.Fab")
			(effects
				(font
					(size 0.7 0.7)
					(thickness 0.15)
				)
				(justify left bottom)
			)
		)
		(property "Datasheet" "https://product.samsungsem.com/mlcc/CL21A226MAYNNN.do"
			(at 0 0 90)
			(layer "F.Fab")
			(hide yes)
			(effects
				(font
					(size 1.27 1.27)
					(thickness 0.15)
				)
			)
		)
		(property "Description" "SMT Multilayer Ceramic Capacitor, 22uF, +/-20%, 25V, X5R, 0805 [2012 Metric]"
			(at 0 0 90)
			(layer "F.Fab")
			(hide yes)
			(effects
				(font
					(size 1.27 1.27)
					(thickness 0.15)
				)
			)
		)
		(property "MPN" "CL21A226MAYNNNE"
			(at 0 0 90)
			(unlocked yes)
			(layer "F.Fab")
			(hide yes)
			(effects
				(font
					(size 1 1)
					(thickness 0.15)
				)
			)
		)
		(property "Manufacturer" "Samsung Electro-Mechanics"
			(at 0 0 90)
			(unlocked yes)
			(layer "F.Fab")
			(hide yes)
			(effects
				(font
					(size 1 1)
					(thickness 0.15)
				)
			)
		)
		(property "License" "Apache-2.0"
			(at 0 0 90)
			(unlocked yes)
			(layer "F.Fab")
			(hide yes)
			(effects
				(font
					(size 1 1)
					(thickness 0.15)
				)
			)
		)
		(property "Author" "Antmicro"
			(at 0 0 90)
			(unlocked yes)
			(layer "F.Fab")
			(hide yes)
			(effects
				(font
					(size 1 1)
					(thickness 0.15)
				)
			)
		)
		(property "Val" "22u"
			(at 0 0 90)
			(unlocked yes)
			(layer "F.Fab")
			(hide yes)
			(effects
				(font
					(size 1 1)
					(thickness 0.15)
				)
			)
		)
		(property "Voltage" "25V"
			(at 0 0 90)
			(unlocked yes)
			(layer "F.Fab")
			(hide yes)
			(effects
				(font
					(size 1 1)
					(thickness 0.15)
				)
			)
		)
		(property "Dielectric" "X5R"
			(at 0 0 90)
			(unlocked yes)
			(layer "F.Fab")
			(hide yes)
			(effects
				(font
					(size 1 1)
					(thickness 0.15)
				)
			)
		)
		(property "Public" "False"
			(at 0 0 90)
			(unlocked yes)
			(layer "F.Fab")
			(hide yes)
			(effects
				(font
					(size 1 1)
					(thickness 0.15)
				)
			)
		)
		(sheetname "/DCDC/")
		(sheetfile "dcdc.kicad_sch")
		(attr smd)
		(fp_line
			(start -0.3 -0.7)
			(end 0.3 -0.7)
			(stroke
				(width 0.15)
				(type solid)
			)
			(layer "F.SilkS")
		)
		(fp_line
			(start -0.3 0.7)
			(end 0.3 0.7)
			(stroke
				(width 0.15)
				(type solid)
			)
			(layer "F.SilkS")
		)
		(fp_rect
			(start 1.95 -0.9)
			(end -1.95 0.9)
			(stroke
				(width 0.05)
				(type default)
			)
			(fill no)
			(layer "F.CrtYd")
		)
		(fp_rect
			(start -0.95 -0.675)
			(end 0.95 0.675)
			(stroke
				(width 0.15)
				(type solid)
			)
			(fill no)
			(layer "F.Fab")
		)
		(fp_text user "License: Apache-2.0"
			(at -1.9 4.947 90)
			(layer "F.Fab")
			(effects
				(font
					(size 0.7 0.7)
					(thickness 0.15)
				)
				(justify left bottom)
			)
		)
		(fp_text user "${REFERENCE}"
			(at -1.9 3.947 90)
			(layer "F.Fab")
			(effects
				(font
					(size 0.7 0.7)
					(thickness 0.15)
				)
				(justify left bottom)
			)
		)
		(fp_text user "Author: Antmicro"
			(at -1.9 5.947 90)
			(layer "F.Fab")
			(effects
				(font
					(size 0.7 0.7)
					(thickness 0.15)
				)
				(justify left bottom)
			)
		)
		(pad "1" smd roundrect
			(at -1.1 0 90)
			(size 1.2 1.3)
			(layers "F.Cu" "F.Mask" "F.Paste")
			(roundrect_rratio 0.25)
			(net 1 "GND")
			(pintype "passive")
		)
		(pad "2" smd roundrect
			(at 1.1 0 90)
			(size 1.2 1.3)
			(layers "F.Cu" "F.Mask" "F.Paste")
			(roundrect_rratio 0.25)
			(net 13 "VCC")
			(pintype "passive")
		)
	)
	(footprint "antmicro-footprints:C_0402_1005Metric"
		(layer "F.Cu")
		(at 204.75 86.970856 180)
		(descr "Capacitor SMD 0402")
		(tags "capacitor SMD 0402")
		(property "Reference" "C314"
			(at 5.15 -0.429144 180)
			(layer "F.SilkS")
			(effects
				(font
					(size 0.7 0.7)
					(thickness 0.15)
				)
				(justify left bottom)
			)
		)
		(property "Value" "C_100n_0402"
			(at -1.022927 2.155213 180)
			(layer "F.Fab")
			(effects
				(font
					(size 0.7 0.7)
					(thickness 0.15)
				)
				(justify left bottom)
			)
		)
		(property "Datasheet" "https://www.murata.com/products/productdetail?partno=GRM155R61H104KE14%23"
			(at 0 0 180)
			(layer "F.Fab")
			(hide yes)
			(effects
				(font
					(size 1.27 1.27)
					(thickness 0.15)
				)
			)
		)
		(property "Description" "SMD Multilayer Ceramic Capacitor, 0.1 µF, 50 V, 0402 [1005 Metric], ± 10%, X5R, GRM Series"
			(at 0 0 180)
			(layer "F.Fab")
			(hide yes)
			(effects
				(font
					(size 1.27 1.27)
					(thickness 0.15)
				)
			)
		)
		(property "Manufacturer" "Murata"
			(at 0 0 180)
			(unlocked yes)
			(layer "F.Fab")
			(hide yes)
			(effects
				(font
					(size 1 1)
					(thickness 0.15)
				)
			)
		)
		(property "MPN" "GRM155R61H104KE14D"
			(at 0 0 180)
			(unlocked yes)
			(layer "F.Fab")
			(hide yes)
			(effects
				(font
					(size 1 1)
					(thickness 0.15)
				)
			)
		)
		(property "Val" "100n"
			(at 0 0 180)
			(unlocked yes)
			(layer "F.Fab")
			(hide yes)
			(effects
				(font
					(size 1 1)
					(thickness 0.15)
				)
			)
		)
		(property "License" "Apache-2.0"
			(at 0 0 180)
			(unlocked yes)
			(layer "F.Fab")
			(hide yes)
			(effects
				(font
					(size 1 1)
					(thickness 0.15)
				)
			)
		)
		(property "Author" "Antmicro"
			(at 0 0 180)
			(unlocked yes)
			(layer "F.Fab")
			(hide yes)
			(effects
				(font
					(size 1 1)
					(thickness 0.15)
				)
			)
		)
		(property "Voltage" "50V"
			(at 0 0 180)
			(unlocked yes)
			(layer "F.Fab")
			(hide yes)
			(effects
				(font
					(size 1 1)
					(thickness 0.15)
				)
			)
		)
		(property "Dielectric" "X5R"
			(at 0 0 180)
			(unlocked yes)
			(layer "F.Fab")
			(hide yes)
			(effects
				(font
					(size 1 1)
					(thickness 0.15)
				)
			)
		)
		(sheetname "/SoM_IO2/")
		(sheetfile "som_io2.kicad_sch")
		(attr smd)
		(fp_rect
			(start -0.925 -0.47)
			(end 0.925 0.47)
			(stroke
				(width 0.05)
				(type default)
			)
			(fill no)
			(layer "F.CrtYd")
		)
		(fp_line
			(start 0.504 0.248)
			(end -0.494 0.248)
			(stroke
				(width 0.15)
				(type solid)
			)
			(layer "F.Fab")
		)
		(fp_line
			(start 0.504 -0.25)
			(end 0.504 0.248)
			(stroke
				(width 0.15)
				(type solid)
			)
			(layer "F.Fab")
		)
		(fp_line
			(start -0.494 0.248)
			(end -0.494 -0.25)
			(stroke
				(width 0.15)
				(type solid)
			)
			(layer "F.Fab")
		)
		(fp_line
			(start -0.494 -0.25)
			(end 0.504 -0.25)
			(stroke
				(width 0.15)
				(type solid)
			)
			(layer "F.Fab")
		)
		(fp_text user "License: Apache-2.0"
			(at -0.939 5.799 180)
			(layer "F.Fab")
			(effects
				(font
					(size 0.7 0.7)
					(thickness 0.15)
				)
				(justify left bottom)
			)
		)
		(fp_text user "${REFERENCE}"
			(at -0.939 4.599 180)
			(layer "F.Fab")
			(effects
				(font
					(size 0.7 0.7)
					(thickness 0.15)
				)
				(justify left bottom)
			)
		)
		(fp_text user "Author: Antmicro"
			(at -0.939 3.399 180)
			(layer "F.Fab")
			(effects
				(font
					(size 0.7 0.7)
					(thickness 0.15)
				)
				(justify left bottom)
			)
		)
		(pad "1" smd roundrect
			(at -0.48 0 180)
			(size 0.59 0.64)
			(layers "F.Cu" "F.Mask" "F.Paste")
			(roundrect_rratio 0.25)
			(net 583 "/SoM_IO2/DP0.TX0+")
			(pintype "passive")
		)
		(pad "2" smd roundrect
			(at 0.48 0 180)
			(size 0.59 0.64)
			(layers "F.Cu" "F.Mask" "F.Paste")
			(roundrect_rratio 0.25)
			(net 523 "/SoM_IO2/DP0.TX0_C+")
			(pintype "passive")
		)
	)
	(footprint "antmicro-footprints:LED_0603_1608Metric_G"
		(layer "F.Cu")
		(at 235.540532 95.71 180)
		(descr "LED SMD 0603 Green")
		(tags "LED SMD 0603 Green")
		(property "Reference" "D25"
			(at -1.059468 -0.799999 0)
			(layer "F.SilkS")
			(effects
				(font
					(size 0.7 0.7)
					(thickness 0.15)
				)
				(justify right top)
			)
		)
		(property "Value" "LED_G_0603_LTST-C190GKT"
			(at -0.001 1.599 0)
			(layer "F.Fab")
			(effects
				(font
					(size 0.7 0.7)
					(thickness 0.15)
				)
				(justify right top)
			)
		)
		(property "Datasheet" "https://media.digikey.com/pdf/Data%20Sheets/Lite-On%20PDFs/LTST-C190GKT.pdf"
			(at 0 0 0)
			(layer "F.Fab")
			(hide yes)
			(effects
				(font
					(size 1.27 1.27)
					(thickness 0.15)
				)
			)
		)
		(property "Description" "LED, Green, SMD, 0603, 20 mA, 2.1 V, 569 nm"
			(at 0 0 0)
			(layer "F.Fab")
			(hide yes)
			(effects
				(font
					(size 1.27 1.27)
					(thickness 0.15)
				)
			)
		)
		(property "MPN" "LTST-C190GKT"
			(at 0 0 180)
			(unlocked yes)
			(layer "F.Fab")
			(hide yes)
			(effects
				(font
					(size 1 1)
					(thickness 0.15)
				)
			)
		)
		(property "Manufacturer" "Lite-On"
			(at 0 0 180)
			(unlocked yes)
			(layer "F.Fab")
			(hide yes)
			(effects
				(font
					(size 1 1)
					(thickness 0.15)
				)
			)
		)
		(property "Author" "Antmicro"
			(at 0 0 180)
			(unlocked yes)
			(layer "F.Fab")
			(hide yes)
			(effects
				(font
					(size 1 1)
					(thickness 0.15)
				)
			)
		)
		(property "License" "Apache-2.0"
			(at 0 0 180)
			(unlocked yes)
			(layer "F.Fab")
			(hide yes)
			(effects
				(font
					(size 1 1)
					(thickness 0.15)
				)
			)
		)
		(property "Color" "Green"
			(at 0 0 180)
			(unlocked yes)
			(layer "F.Fab")
			(hide yes)
			(effects
				(font
					(size 1 1)
					(thickness 0.15)
				)
			)
		)
		(sheetname "/USB DP Alt mode/")
		(sheetfile "usb_dp.kicad_sch")
		(attr smd)
		(fp_line
			(start 0.22 0.35)
			(end -0.22 0.35)
			(stroke
				(width 0.15)
				(type solid)
			)
			(layer "F.SilkS")
		)
		(fp_line
			(start 0.22 -0.35)
			(end -0.22 -0.35)
			(stroke
				(width 0.15)
				(type solid)
			)
			(layer "F.SilkS")
		)
		(fp_line
			(start 0.105328 0.201008)
			(end 0.105329 -0.198992)
			(stroke
				(width 0.1)
				(type solid)
			)
			(layer "F.SilkS")
		)
		(fp_line
			(start 0.105328 0.201008)
			(end -0.094672 0.001008)
			(stroke
				(width 0.1)
				(type solid)
			)
			(layer "F.SilkS")
		)
		(fp_line
			(start 0.105328 0.001008)
			(end 0.240001 0.001)
			(stroke
				(width 0.1)
				(type solid)
			)
			(layer "F.SilkS")
		)
		(fp_line
			(start -0.094672 0.201008)
			(end -0.094672 -0.198992)
			(stroke
				(width 0.1)
				(type solid)
			)
			(layer "F.SilkS")
		)
		(fp_line
			(start -0.094672 0.001008)
			(end 0.105329 -0.198992)
			(stroke
				(width 0.1)
				(type solid)
			)
			(layer "F.SilkS")
		)
		(fp_line
			(start -0.094672 0.001008)
			(end -0.24 0.001008)
			(stroke
				(width 0.1)
				(type solid)
			)
			(layer "F.SilkS")
		)
		(fp_line
			(start -1.18 -0.319)
			(end -1.18 0.321)
			(stroke
				(width 0.15)
				(type solid)
			)
			(layer "F.SilkS")
		)
		(fp_poly
			(pts
				(xy 1.25 0.65) (xy -1.25 0.65) (xy -1.25 -0.65) (xy 1.25 -0.65)
			)
			(stroke
				(width 0.05)
				(type solid)
			)
			(fill no)
			(layer "F.CrtYd")
		)
		(fp_line
			(start 0.599 0)
			(end 0.200999 0)
			(stroke
				(width 0.15)
				(type solid)
			)
			(layer "F.Fab")
		)
		(fp_line
			(start 0.201 0.2)
			(end 0.200999 0)
			(stroke
				(width 0.15)
				(type solid)
			)
			(layer "F.Fab")
		)
		(fp_line
			(start 0.201 -0.202)
			(end -0.101 0)
			(stroke
				(width 0.15)
				(type solid)
			)
			(layer "F.Fab")
		)
		(fp_line
			(start 0.200999 0)
			(end 0.201 -0.202)
			(stroke
				(width 0.15)
				(type solid)
			)
			(layer "F.Fab")
		)
		(fp_line
			(start -0.101 0)
			(end 0.201 0.2)
			(stroke
				(width 0.15)
				(type solid)
			)
			(layer "F.Fab")
		)
		(fp_line
			(start -0.199 0.2)
			(end -0.199 0.1)
			(stroke
				(width 0.15)
				(type solid)
			)
			(layer "F.Fab")
		)
		(fp_line
			(start -0.199 0)
			(end -0.597 0)
			(stroke
				(width 0.15)
				(type solid)
			)
			(layer "F.Fab")
		)
		(fp_line
			(start -0.199 -0.202)
			(end -0.199 0.1)
			(stroke
				(width 0.15)
				(type solid)
			)
			(layer "F.Fab")
		)
		(fp_poly
			(pts
				(xy 0.848 0.4) (xy -0.85 0.4) (xy -0.85 -0.402) (xy 0.848 -0.401999)
			)
			(stroke
				(width 0.15)
				(type solid)
			)
			(fill no)
			(layer "F.Fab")
		)
		(fp_text user "Author: Antmicro"
			(at -1.4224 4.799 0)
			(layer "F.Fab")
			(effects
				(font
					(size 0.7 0.7)
					(thickness 0.15)
				)
				(justify right top)
			)
		)
		(fp_text user "License: Apache-2.0"
			(at -1.4224 3.599 0)
			(layer "F.Fab")
			(effects
				(font
					(size 0.7 0.7)
					(thickness 0.15)
				)
				(justify right top)
			)
		)
		(fp_text user "${REFERENCE}"
			(at -1.4224 5.999 0)
			(layer "F.Fab")
			(effects
				(font
					(size 0.7 0.7)
					(thickness 0.15)
				)
				(justify right top)
			)
		)
		(pad "1" smd roundrect
			(at -0.7 0)
			(size 0.8 1)
			(layers "F.Cu" "F.Mask" "F.Paste")
			(roundrect_rratio 0.2)
			(net 1 "GND")
			(pinfunction "C")
			(pintype "passive")
		)
		(pad "2" smd roundrect
			(at 0.7 0)
			(size 0.8 1)
			(layers "F.Cu" "F.Mask" "F.Paste")
			(roundrect_rratio 0.2)
			(net 1388 "Net-(D25-A)")
			(pinfunction "A")
			(pintype "passive")
		)
	)
	(footprint "antmicro-footprints:R_0402_1005Metric"
		(layer "F.Cu")
		(at 61.6 62.2 180)
		(descr "Resistor SMD 0402")
		(tags "resistor SMD 0402")
		(property "Reference" "R159"
			(at -1.45 -2.8 0)
			(layer "F.SilkS")
			(effects
				(font
					(size 0.7 0.7)
					(thickness 0.15)
				)
				(justify right top)
			)
		)
		(property "Value" "R_0R_0402"
			(at -1.011843 1.772046 0)
			(layer "F.Fab")
			(effects
				(font
					(size 0.7 0.7)
					(thickness 0.15)
				)
				(justify right top)
			)
		)
		(property "Datasheet" "https://industrial.panasonic.com/cdbs/www-data/pdf/RDA0000/AOA0000C301.pdf"
			(at 0 0 0)
			(layer "F.Fab")
			(hide yes)
			(effects
				(font
					(size 1.27 1.27)
					(thickness 0.15)
				)
			)
		)
		(property "Description" "SMD Chip Resistor, Jumper, 0 ohm, 100 mW, 0402 [1005 Metric], Thick Film, General Purpose"
			(at 0 0 0)
			(layer "F.Fab")
			(hide yes)
			(effects
				(font
					(size 1.27 1.27)
					(thickness 0.15)
				)
			)
		)
		(property "Manufacturer" "Panasonic"
			(at 0 0 180)
			(unlocked yes)
			(layer "F.Fab")
			(hide yes)
			(effects
				(font
					(size 1 1)
					(thickness 0.15)
				)
			)
		)
		(property "MPN" "ERJ2GE0R00X"
			(at 0 0 180)
			(unlocked yes)
			(layer "F.Fab")
			(hide yes)
			(effects
				(font
					(size 1 1)
					(thickness 0.15)
				)
			)
		)
		(property "Val" "0R"
			(at 0 0 180)
			(unlocked yes)
			(layer "F.Fab")
			(hide yes)
			(effects
				(font
					(size 1 1)
					(thickness 0.15)
				)
			)
		)
		(property "License" "Apache-2.0"
			(at 0 0 180)
			(unlocked yes)
			(layer "F.Fab")
			(hide yes)
			(effects
				(font
					(size 1 1)
					(thickness 0.15)
				)
			)
		)
		(property "Author" "Antmicro"
			(at 0 0 180)
			(unlocked yes)
			(layer "F.Fab")
			(hide yes)
			(effects
				(font
					(size 1 1)
					(thickness 0.15)
				)
			)
		)
		(property "Tolerance" "~"
			(at 0 0 180)
			(unlocked yes)
			(layer "F.Fab")
			(hide yes)
			(effects
				(font
					(size 1 1)
					(thickness 0.15)
				)
			)
		)
		(property "Current" "1A"
			(at 0 0 180)
			(unlocked yes)
			(layer "F.Fab")
			(hide yes)
			(effects
				(font
					(size 1 1)
					(thickness 0.15)
				)
			)
		)
		(sheetname "/CSI/")
		(sheetfile "csi.kicad_sch")
		(attr smd exclude_from_pos_files exclude_from_bom dnp)
		(fp_poly
			(pts
				(xy -0.925 -0.47) (xy -0.925 0.47) (xy 0.925 0.47) (xy 0.925 -0.47)
			)
			(stroke
				(width 0.05)
				(type default)
			)
			(fill no)
			(layer "F.CrtYd")
		)
		(fp_poly
			(pts
				(xy -0.5 -0.25) (xy -0.5 0.25) (xy 0.5 0.25) (xy 0.5 -0.25)
			)
			(stroke
				(width 0.15)
				(type solid)
			)
			(fill no)
			(layer "F.Fab")
		)
		(fp_text user "${REFERENCE}"
			(at -0.95 3.168 0)
			(layer "F.Fab")
			(effects
				(font
					(size 0.7 0.7)
					(thickness 0.15)
				)
				(justify right top)
			)
		)
		(fp_text user "License: Apache-2.0"
			(at -0.949999 5.169 0)
			(layer "F.Fab")
			(effects
				(font
					(size 0.7 0.7)
					(thickness 0.15)
				)
				(justify right top)
			)
		)
		(fp_text user "Author: Antmicro"
			(at -0.95 4.169 0)
			(layer "F.Fab")
			(effects
				(font
					(size 0.7 0.7)
					(thickness 0.15)
				)
				(justify right top)
			)
		)
		(pad "1" smd roundrect
			(at -0.48 0 180)
			(size 0.59 0.64)
			(layers "F.Cu" "F.Mask" "F.Paste")
			(roundrect_rratio 0.25)
			(net 980 "/CSI/I2C_MUX_A0")
			(pintype "passive")
		)
		(pad "2" smd roundrect
			(at 0.48 0 180)
			(size 0.59 0.64)
			(layers "F.Cu" "F.Mask" "F.Paste")
			(roundrect_rratio 0.25)
			(net 11 "+1V8")
			(pintype "passive")
		)
	)
	(footprint "antmicro-footprints:R_0402_1005Metric"
		(layer "F.Cu")
		(at 130.549999 63.98 180)
		(descr "Resistor SMD 0402")
		(tags "resistor SMD 0402")
		(property "Reference" "R313"
			(at 0.929999 -2.34 0)
			(layer "F.SilkS")
			(effects
				(font
					(size 0.7 0.7)
					(thickness 0.15)
				)
				(justify left bottom)
			)
		)
		(property "Value" "R_10k_0402"
			(at -1.011843 1.772046 0)
			(layer "F.Fab")
			(effects
				(font
					(size 0.7 0.7)
					(thickness 0.15)
				)
				(justify right top)
			)
		)
		(property "Datasheet" "https://www.bourns.com/docs/product-datasheets/cr.pdf"
			(at 0 0 0)
			(layer "F.Fab")
			(hide yes)
			(effects
				(font
					(size 1.27 1.27)
					(thickness 0.15)
				)
			)
		)
		(property "Description" "SMD Chip Resistor, 10 kohm, ± 1%, 62.5 mW, 0402 [1005 Metric], Thick Film, General Purpose"
			(at 0 0 0)
			(layer "F.Fab")
			(hide yes)
			(effects
				(font
					(size 1.27 1.27)
					(thickness 0.15)
				)
			)
		)
		(property "MPN" "CR0402-FX-1002GLF"
			(at 0 0 180)
			(unlocked yes)
			(layer "F.Fab")
			(hide yes)
			(effects
				(font
					(size 1 1)
					(thickness 0.15)
				)
			)
		)
		(property "Manufacturer" "Bourns"
			(at 0 0 180)
			(unlocked yes)
			(layer "F.Fab")
			(hide yes)
			(effects
				(font
					(size 1 1)
					(thickness 0.15)
				)
			)
		)
		(property "License" "Apache-2.0"
			(at 0 0 180)
			(unlocked yes)
			(layer "F.Fab")
			(hide yes)
			(effects
				(font
					(size 1 1)
					(thickness 0.15)
				)
			)
		)
		(property "Author" "Antmicro"
			(at 0 0 180)
			(unlocked yes)
			(layer "F.Fab")
			(hide yes)
			(effects
				(font
					(size 1 1)
					(thickness 0.15)
				)
			)
		)
		(property "Val" "10k"
			(at 0 0 180)
			(unlocked yes)
			(layer "F.Fab")
			(hide yes)
			(effects
				(font
					(size 1 1)
					(thickness 0.15)
				)
			)
		)
		(property "Tolerance" "1%"
			(at 0 0 180)
			(unlocked yes)
			(layer "F.Fab")
			(hide yes)
			(effects
				(font
					(size 1 1)
					(thickness 0.15)
				)
			)
		)
		(sheetname "/DCDC/")
		(sheetfile "dcdc.kicad_sch")
		(attr smd)
		(fp_poly
			(pts
				(xy -0.925 -0.47) (xy -0.925 0.47) (xy 0.925 0.47) (xy 0.925 -0.47)
			)
			(stroke
				(width 0.05)
				(type default)
			)
			(fill no)
			(layer "F.CrtYd")
		)
		(fp_poly
			(pts
				(xy -0.5 -0.25) (xy -0.5 0.25) (xy 0.5 0.25) (xy 0.5 -0.25)
			)
			(stroke
				(width 0.15)
				(type solid)
			)
			(fill no)
			(layer "F.Fab")
		)
		(fp_text user "License: Apache-2.0"
			(at -0.949999 5.169 0)
			(layer "F.Fab")
			(effects
				(font
					(size 0.7 0.7)
					(thickness 0.15)
				)
				(justify right top)
			)
		)
		(fp_text user "${REFERENCE}"
			(at -0.95 3.168 0)
			(layer "F.Fab")
			(effects
				(font
					(size 0.7 0.7)
					(thickness 0.15)
				)
				(justify right top)
			)
		)
		(fp_text user "Author: Antmicro"
			(at -0.95 4.169 0)
			(layer "F.Fab")
			(effects
				(font
					(size 0.7 0.7)
					(thickness 0.15)
				)
				(justify right top)
			)
		)
		(pad "1" smd roundrect
			(at -0.48 0 180)
			(size 0.59 0.64)
			(layers "F.Cu" "F.Mask" "F.Paste")
			(roundrect_rratio 0.25)
			(net 1 "GND")
			(pintype "passive")
		)
		(pad "2" smd roundrect
			(at 0.48 0 180)
			(size 0.59 0.64)
			(layers "F.Cu" "F.Mask" "F.Paste")
			(roundrect_rratio 0.25)
			(net 1308 "/DCDC/5V_{AON}_FB")
			(pintype "passive")
		)
	)
	(footprint "antmicro-footprints:C_0805_2012Metric"
		(layer "F.Cu")
		(at 173.19 99.81 90)
		(descr "Capacitor SMD 0805")
		(tags "capacitor SMD 0805")
		(property "Reference" "C290"
			(at -4.62 0.245 90)
			(layer "F.SilkS")
			(effects
				(font
					(size 0.7 0.7)
					(thickness 0.15)
				)
				(justify left bottom)
			)
		)
		(property "Value" "C_22u_25V_0805"
			(at -2.055717 1.963152 90)
			(layer "F.Fab")
			(effects
				(font
					(size 0.7 0.7)
					(thickness 0.15)
				)
				(justify left bottom)
			)
		)
		(property "Datasheet" "https://product.samsungsem.com/mlcc/CL21A226MAYNNN.do"
			(at 0 0 90)
			(layer "F.Fab")
			(hide yes)
			(effects
				(font
					(size 1.27 1.27)
					(thickness 0.15)
				)
			)
		)
		(property "Description" "SMT Multilayer Ceramic Capacitor, 22uF, +/-20%, 25V, X5R, 0805 [2012 Metric]"
			(at 0 0 90)
			(layer "F.Fab")
			(hide yes)
			(effects
				(font
					(size 1.27 1.27)
					(thickness 0.15)
				)
			)
		)
		(property "MPN" "CL21A226MAYNNNE"
			(at 0 0 90)
			(unlocked yes)
			(layer "F.Fab")
			(hide yes)
			(effects
				(font
					(size 1 1)
					(thickness 0.15)
				)
			)
		)
		(property "Manufacturer" "Samsung Electro-Mechanics"
			(at 0 0 90)
			(unlocked yes)
			(layer "F.Fab")
			(hide yes)
			(effects
				(font
					(size 1 1)
					(thickness 0.15)
				)
			)
		)
		(property "License" "Apache-2.0"
			(at 0 0 90)
			(unlocked yes)
			(layer "F.Fab")
			(hide yes)
			(effects
				(font
					(size 1 1)
					(thickness 0.15)
				)
			)
		)
		(property "Author" "Antmicro"
			(at 0 0 90)
			(unlocked yes)
			(layer "F.Fab")
			(hide yes)
			(effects
				(font
					(size 1 1)
					(thickness 0.15)
				)
			)
		)
		(property "Val" "22u"
			(at 0 0 90)
			(unlocked yes)
			(layer "F.Fab")
			(hide yes)
			(effects
				(font
					(size 1 1)
					(thickness 0.15)
				)
			)
		)
		(property "Voltage" "25V"
			(at 0 0 90)
			(unlocked yes)
			(layer "F.Fab")
			(hide yes)
			(effects
				(font
					(size 1 1)
					(thickness 0.15)
				)
			)
		)
		(property "Dielectric" "X5R"
			(at 0 0 90)
			(unlocked yes)
			(layer "F.Fab")
			(hide yes)
			(effects
				(font
					(size 1 1)
					(thickness 0.15)
				)
			)
		)
		(property "Public" "False"
			(at 0 0 90)
			(unlocked yes)
			(layer "F.Fab")
			(hide yes)
			(effects
				(font
					(size 1 1)
					(thickness 0.15)
				)
			)
		)
		(component_classes
			(class "DCDC_SOM")
		)
		(sheetname "/DCDC/")
		(sheetfile "dcdc.kicad_sch")
		(attr smd)
		(fp_line
			(start -0.3 -0.7)
			(end 0.3 -0.7)
			(stroke
				(width 0.15)
				(type solid)
			)
			(layer "F.SilkS")
		)
		(fp_line
			(start -0.3 0.7)
			(end 0.3 0.7)
			(stroke
				(width 0.15)
				(type solid)
			)
			(layer "F.SilkS")
		)
		(fp_rect
			(start 1.95 -0.9)
			(end -1.95 0.9)
			(stroke
				(width 0.05)
				(type default)
			)
			(fill no)
			(layer "F.CrtYd")
		)
		(fp_rect
			(start -0.95 -0.675)
			(end 0.95 0.675)
			(stroke
				(width 0.15)
				(type solid)
			)
			(fill no)
			(layer "F.Fab")
		)
		(fp_text user "License: Apache-2.0"
			(at -1.9 4.947 90)
			(layer "F.Fab")
			(effects
				(font
					(size 0.7 0.7)
					(thickness 0.15)
				)
				(justify left bottom)
			)
		)
		(fp_text user "${REFERENCE}"
			(at -1.9 3.947 90)
			(layer "F.Fab")
			(effects
				(font
					(size 0.7 0.7)
					(thickness 0.15)
				)
				(justify left bottom)
			)
		)
		(fp_text user "Author: Antmicro"
			(at -1.9 5.947 90)
			(layer "F.Fab")
			(effects
				(font
					(size 0.7 0.7)
					(thickness 0.15)
				)
				(justify left bottom)
			)
		)
		(pad "1" smd roundrect
			(at -1.1 0 90)
			(size 1.2 1.3)
			(layers "F.Cu" "F.Mask" "F.Paste")
			(roundrect_rratio 0.25)
			(net 1 "GND")
			(pintype "passive")
		)
		(pad "2" smd roundrect
			(at 1.1 0 90)
			(size 1.2 1.3)
			(layers "F.Cu" "F.Mask" "F.Paste")
			(roundrect_rratio 0.25)
			(net 903 "/DCDC/16V_OUT")
			(pintype "passive")
		)
	)
	(footprint "antmicro-footprints:C_0402_1005Metric"
		(layer "F.Cu")
		(at 184.054468 129.08 -90)
		(descr "Capacitor SMD 0402")
		(tags "capacitor SMD 0402")
		(property "Reference" "C56"
			(at 1.3 -1.35 90)
			(layer "F.SilkS")
			(effects
				(font
					(size 0.7 0.7)
					(thickness 0.15)
				)
				(justify left bottom)
			)
		)
		(property "Value" "C_4u7_25V_0402"
			(at -1.022927 2.155213 90)
			(layer "F.Fab")
			(effects
				(font
					(size 0.7 0.7)
					(thickness 0.15)
				)
				(justify right top)
			)
		)
		(property "Datasheet" "https://www.murata.com/products/productdetail?partno=GRM155C61E475ME15%23"
			(at 0 0 90)
			(layer "F.Fab")
			(hide yes)
			(effects
				(font
					(size 1.27 1.27)
					(thickness 0.15)
				)
			)
		)
		(property "Description" "SMD Multilayer Ceramic Capacitor"
			(at 0 0 90)
			(layer "F.Fab")
			(hide yes)
			(effects
				(font
					(size 1.27 1.27)
					(thickness 0.15)
				)
			)
		)
		(property "MPN" "GRM155C61E475ME15J"
			(at 0 0 270)
			(unlocked yes)
			(layer "F.Fab")
			(hide yes)
			(effects
				(font
					(size 1 1)
					(thickness 0.15)
				)
			)
		)
		(property "Manufacturer" "Murata"
			(at 0 0 270)
			(unlocked yes)
			(layer "F.Fab")
			(hide yes)
			(effects
				(font
					(size 1 1)
					(thickness 0.15)
				)
			)
		)
		(property "License" "Apache-2.0"
			(at 0 0 270)
			(unlocked yes)
			(layer "F.Fab")
			(hide yes)
			(effects
				(font
					(size 1 1)
					(thickness 0.15)
				)
			)
		)
		(property "Author" "Antmicro"
			(at 0 0 270)
			(unlocked yes)
			(layer "F.Fab")
			(hide yes)
			(effects
				(font
					(size 1 1)
					(thickness 0.15)
				)
			)
		)
		(property "Val" "4u7"
			(at 0 0 270)
			(unlocked yes)
			(layer "F.Fab")
			(hide yes)
			(effects
				(font
					(size 1 1)
					(thickness 0.15)
				)
			)
		)
		(property "Voltage" "25V"
			(at 0 0 270)
			(unlocked yes)
			(layer "F.Fab")
			(hide yes)
			(effects
				(font
					(size 1 1)
					(thickness 0.15)
				)
			)
		)
		(property "Dielectric" "X5S"
			(at 0 0 270)
			(unlocked yes)
			(layer "F.Fab")
			(hide yes)
			(effects
				(font
					(size 1 1)
					(thickness 0.15)
				)
			)
		)
		(sheetname "/DCDC/")
		(sheetfile "dcdc.kicad_sch")
		(attr smd)
		(fp_rect
			(start -0.925 -0.47)
			(end 0.925 0.47)
			(stroke
				(width 0.05)
				(type default)
			)
			(fill no)
			(layer "F.CrtYd")
		)
		(fp_line
			(start -0.494 0.248)
			(end -0.494 -0.25)
			(stroke
				(width 0.15)
				(type solid)
			)
			(layer "F.Fab")
		)
		(fp_line
			(start 0.504 0.248)
			(end -0.494 0.248)
			(stroke
				(width 0.15)
				(type solid)
			)
			(layer "F.Fab")
		)
		(fp_line
			(start -0.494 -0.25)
			(end 0.504 -0.25)
			(stroke
				(width 0.15)
				(type solid)
			)
			(layer "F.Fab")
		)
		(fp_line
			(start 0.504 -0.25)
			(end 0.504 0.248)
			(stroke
				(width 0.15)
				(type solid)
			)
			(layer "F.Fab")
		)
		(fp_text user "License: Apache-2.0"
			(at -0.939 5.799 90)
			(layer "F.Fab")
			(effects
				(font
					(size 0.7 0.7)
					(thickness 0.15)
				)
				(justify right top)
			)
		)
		(fp_text user "${REFERENCE}"
			(at -0.939 4.599 90)
			(layer "F.Fab")
			(effects
				(font
					(size 0.7 0.7)
					(thickness 0.15)
				)
				(justify right top)
			)
		)
		(fp_text user "Author: Antmicro"
			(at -0.939 3.399 90)
			(layer "F.Fab")
			(effects
				(font
					(size 0.7 0.7)
					(thickness 0.15)
				)
				(justify right top)
			)
		)
		(pad "1" smd roundrect
			(at -0.48 0 270)
			(size 0.59 0.64)
			(layers "F.Cu" "F.Mask" "F.Paste")
			(roundrect_rratio 0.25)
			(net 1 "GND")
			(pintype "passive")
		)
		(pad "2" smd roundrect
			(at 0.48 0 270)
			(size 0.59 0.64)
			(layers "F.Cu" "F.Mask" "F.Paste")
			(roundrect_rratio 0.25)
			(net 24 "/DCDC/3V3_VDRV")
			(pintype "passive")
		)
	)
	(footprint "antmicro-footprints:C_0402_1005Metric"
		(layer "F.Cu")
		(at 193.126 143.275 180)
		(descr "Capacitor SMD 0402")
		(tags "capacitor SMD 0402")
		(property "Reference" "C61"
			(at 3.226 -0.325 180)
			(layer "F.SilkS")
			(effects
				(font
					(size 0.7 0.7)
					(thickness 0.15)
				)
				(justify left bottom)
			)
		)
		(property "Value" "C_100n_0402"
			(at -1.022927 2.155213 180)
			(layer "F.Fab")
			(effects
				(font
					(size 0.7 0.7)
					(thickness 0.15)
				)
				(justify left bottom)
			)
		)
		(property "Datasheet" "https://www.murata.com/products/productdetail?partno=GRM155R61H104KE14%23"
			(at 0 0 180)
			(layer "F.Fab")
			(hide yes)
			(effects
				(font
					(size 1.27 1.27)
					(thickness 0.15)
				)
			)
		)
		(property "Description" "SMD Multilayer Ceramic Capacitor, 0.1 µF, 50 V, 0402 [1005 Metric], ± 10%, X5R, GRM Series"
			(at 0 0 180)
			(layer "F.Fab")
			(hide yes)
			(effects
				(font
					(size 1.27 1.27)
					(thickness 0.15)
				)
			)
		)
		(property "Manufacturer" "Murata"
			(at 0 0 180)
			(unlocked yes)
			(layer "F.Fab")
			(hide yes)
			(effects
				(font
					(size 1 1)
					(thickness 0.15)
				)
			)
		)
		(property "MPN" "GRM155R61H104KE14D"
			(at 0 0 180)
			(unlocked yes)
			(layer "F.Fab")
			(hide yes)
			(effects
				(font
					(size 1 1)
					(thickness 0.15)
				)
			)
		)
		(property "Val" "100n"
			(at 0 0 180)
			(unlocked yes)
			(layer "F.Fab")
			(hide yes)
			(effects
				(font
					(size 1 1)
					(thickness 0.15)
				)
			)
		)
		(property "License" "Apache-2.0"
			(at 0 0 180)
			(unlocked yes)
			(layer "F.Fab")
			(hide yes)
			(effects
				(font
					(size 1 1)
					(thickness 0.15)
				)
			)
		)
		(property "Author" "Antmicro"
			(at 0 0 180)
			(unlocked yes)
			(layer "F.Fab")
			(hide yes)
			(effects
				(font
					(size 1 1)
					(thickness 0.15)
				)
			)
		)
		(property "Voltage" "50V"
			(at 0 0 180)
			(unlocked yes)
			(layer "F.Fab")
			(hide yes)
			(effects
				(font
					(size 1 1)
					(thickness 0.15)
				)
			)
		)
		(property "Dielectric" "X5R"
			(at 0 0 180)
			(unlocked yes)
			(layer "F.Fab")
			(hide yes)
			(effects
				(font
					(size 1 1)
					(thickness 0.15)
				)
			)
		)
		(property "Public" "False"
			(at 0 0 180)
			(unlocked yes)
			(layer "F.Fab")
			(hide yes)
			(effects
				(font
					(size 1 1)
					(thickness 0.15)
				)
			)
		)
		(sheetname "/SFP/")
		(sheetfile "sfp.kicad_sch")
		(attr smd)
		(fp_rect
			(start -0.925 -0.47)
			(end 0.925 0.47)
			(stroke
				(width 0.05)
				(type default)
			)
			(fill no)
			(layer "F.CrtYd")
		)
		(fp_line
			(start 0.504 0.248)
			(end -0.494 0.248)
			(stroke
				(width 0.15)
				(type solid)
			)
			(layer "F.Fab")
		)
		(fp_line
			(start 0.504 -0.25)
			(end 0.504 0.248)
			(stroke
				(width 0.15)
				(type solid)
			)
			(layer "F.Fab")
		)
		(fp_line
			(start -0.494 0.248)
			(end -0.494 -0.25)
			(stroke
				(width 0.15)
				(type solid)
			)
			(layer "F.Fab")
		)
		(fp_line
			(start -0.494 -0.25)
			(end 0.504 -0.25)
			(stroke
				(width 0.15)
				(type solid)
			)
			(layer "F.Fab")
		)
		(fp_text user "${REFERENCE}"
			(at -0.939 4.599 180)
			(layer "F.Fab")
			(effects
				(font
					(size 0.7 0.7)
					(thickness 0.15)
				)
				(justify left bottom)
			)
		)
		(fp_text user "Author: Antmicro"
			(at -0.939 3.399 180)
			(layer "F.Fab")
			(effects
				(font
					(size 0.7 0.7)
					(thickness 0.15)
				)
				(justify left bottom)
			)
		)
		(fp_text user "License: Apache-2.0"
			(at -0.939 5.799 180)
			(layer "F.Fab")
			(effects
				(font
					(size 0.7 0.7)
					(thickness 0.15)
				)
				(justify left bottom)
			)
		)
		(pad "1" smd roundrect
			(at -0.48 0 180)
			(size 0.59 0.64)
			(layers "F.Cu" "F.Mask" "F.Paste")
			(roundrect_rratio 0.25)
			(net 27 "/SFP/SFI_CONN_RX_P")
			(pintype "passive")
		)
		(pad "2" smd roundrect
			(at 0.48 0 180)
			(size 0.59 0.64)
			(layers "F.Cu" "F.Mask" "F.Paste")
			(roundrect_rratio 0.25)
			(net 101 "/SFP/SFI.RX+")
			(pintype "passive")
		)
	)
	(footprint "antmicro-footprints:TP_SMD_0.75mm"
		(layer "F.Cu")
		(at 177.5 57.1 90)
		(property "Reference" "TP98"
			(at -1.88 -0.51 90)
			(layer "F.SilkS")
			(hide yes)
			(effects
				(font
					(size 0.7 0.7)
					(thickness 0.15)
				)
				(justify left bottom)
			)
		)
		(property "Value" "TP_0.75mm_SMD"
			(at 0 1.2 90)
			(layer "F.Fab")
			(effects
				(font
					(size 0.7 0.7)
					(thickness 0.15)
				)
				(justify left bottom)
			)
		)
		(property "Description" "SMT test point"
			(at 0 0 90)
			(layer "F.Fab")
			(hide yes)
			(effects
				(font
					(size 1.27 1.27)
					(thickness 0.15)
				)
			)
		)
		(property "MPN" ""
			(at 0 0 90)
			(unlocked yes)
			(layer "F.Fab")
			(hide yes)
			(effects
				(font
					(size 1 1)
					(thickness 0.15)
				)
			)
		)
		(property "Manufacturer" ""
			(at 0 0 90)
			(unlocked yes)
			(layer "F.Fab")
			(hide yes)
			(effects
				(font
					(size 1 1)
					(thickness 0.15)
				)
			)
		)
		(property "Author" "Antmicro"
			(at 0 0 90)
			(unlocked yes)
			(layer "F.Fab")
			(hide yes)
			(effects
				(font
					(size 1 1)
					(thickness 0.15)
				)
			)
		)
		(property "License" "Apache-2.0"
			(at 0 0 90)
			(unlocked yes)
			(layer "F.Fab")
			(hide yes)
			(effects
				(font
					(size 1 1)
					(thickness 0.15)
				)
			)
		)
		(sheetname "/Power/")
		(sheetfile "power.kicad_sch")
		(attr exclude_from_pos_files exclude_from_bom)
		(fp_circle
			(center 0 0)
			(end 0.475 0)
			(stroke
				(width 0.05)
				(type default)
			)
			(fill no)
			(layer "F.CrtYd")
		)
		(fp_text user "License: Apache-2.0"
			(at -0.4 5.101 90)
			(layer "F.Fab")
			(effects
				(font
					(size 0.7 0.7)
					(thickness 0.15)
				)
				(justify left bottom)
			)
		)
		(fp_text user "Author: Antmicro"
			(at -0.4 3.901 90)
			(layer "F.Fab")
			(effects
				(font
					(size 0.7 0.7)
					(thickness 0.15)
				)
				(justify left bottom)
			)
		)
		(fp_text user "${REFERENCE}"
			(at -0.4 2.7 90)
			(layer "F.Fab")
			(effects
				(font
					(size 0.7 0.7)
					(thickness 0.15)
				)
				(justify left bottom)
			)
		)
		(pad "1" smd circle
			(at 0 0 90)
			(size 0.75 0.75)
			(layers "F.Cu" "F.Mask")
			(net 634 "+12V")
			(pinfunction "1")
			(pintype "passive")
		)
	)
	(footprint "antmicro-footprints:C_0805_2012Metric"
		(layer "F.Cu")
		(at 173.17 69.11 90)
		(descr "Capacitor SMD 0805")
		(tags "capacitor SMD 0805")
		(property "Reference" "C277"
			(at 1.91 0.739468 90)
			(layer "F.SilkS")
			(effects
				(font
					(size 0.7 0.7)
					(thickness 0.15)
				)
				(justify left bottom)
			)
		)
		(property "Value" "C_22u_25V_0805"
			(at -2.055717 1.963152 90)
			(layer "F.Fab")
			(effects
				(font
					(size 0.7 0.7)
					(thickness 0.15)
				)
				(justify left bottom)
			)
		)
		(property "Datasheet" "https://product.samsungsem.com/mlcc/CL21A226MAYNNN.do"
			(at 0 0 90)
			(layer "F.Fab")
			(hide yes)
			(effects
				(font
					(size 1.27 1.27)
					(thickness 0.15)
				)
			)
		)
		(property "Description" "SMT Multilayer Ceramic Capacitor, 22uF, +/-20%, 25V, X5R, 0805 [2012 Metric]"
			(at 0 0 90)
			(layer "F.Fab")
			(hide yes)
			(effects
				(font
					(size 1.27 1.27)
					(thickness 0.15)
				)
			)
		)
		(property "MPN" "CL21A226MAYNNNE"
			(at 0 0 90)
			(unlocked yes)
			(layer "F.Fab")
			(hide yes)
			(effects
				(font
					(size 1 1)
					(thickness 0.15)
				)
			)
		)
		(property "Manufacturer" "Samsung Electro-Mechanics"
			(at 0 0 90)
			(unlocked yes)
			(layer "F.Fab")
			(hide yes)
			(effects
				(font
					(size 1 1)
					(thickness 0.15)
				)
			)
		)
		(property "License" "Apache-2.0"
			(at 0 0 90)
			(unlocked yes)
			(layer "F.Fab")
			(hide yes)
			(effects
				(font
					(size 1 1)
					(thickness 0.15)
				)
			)
		)
		(property "Author" "Antmicro"
			(at 0 0 90)
			(unlocked yes)
			(layer "F.Fab")
			(hide yes)
			(effects
				(font
					(size 1 1)
					(thickness 0.15)
				)
			)
		)
		(property "Val" "22u"
			(at 0 0 90)
			(unlocked yes)
			(layer "F.Fab")
			(hide yes)
			(effects
				(font
					(size 1 1)
					(thickness 0.15)
				)
			)
		)
		(property "Voltage" "25V"
			(at 0 0 90)
			(unlocked yes)
			(layer "F.Fab")
			(hide yes)
			(effects
				(font
					(size 1 1)
					(thickness 0.15)
				)
			)
		)
		(property "Dielectric" "X5R"
			(at 0 0 90)
			(unlocked yes)
			(layer "F.Fab")
			(hide yes)
			(effects
				(font
					(size 1 1)
					(thickness 0.15)
				)
			)
		)
		(property "Public" "False"
			(at 0 0 90)
			(unlocked yes)
			(layer "F.Fab")
			(hide yes)
			(effects
				(font
					(size 1 1)
					(thickness 0.15)
				)
			)
		)
		(component_classes
			(class "DCDC_20V")
		)
		(sheetname "/DCDC/")
		(sheetfile "dcdc.kicad_sch")
		(attr smd)
		(fp_line
			(start -0.3 -0.7)
			(end 0.3 -0.7)
			(stroke
				(width 0.15)
				(type solid)
			)
			(layer "F.SilkS")
		)
		(fp_line
			(start -0.3 0.7)
			(end 0.3 0.7)
			(stroke
				(width 0.15)
				(type solid)
			)
			(layer "F.SilkS")
		)
		(fp_rect
			(start 1.95 -0.9)
			(end -1.95 0.9)
			(stroke
				(width 0.05)
				(type default)
			)
			(fill no)
			(layer "F.CrtYd")
		)
		(fp_rect
			(start -0.95 -0.675)
			(end 0.95 0.675)
			(stroke
				(width 0.15)
				(type solid)
			)
			(fill no)
			(layer "F.Fab")
		)
		(fp_text user "License: Apache-2.0"
			(at -1.9 4.947 90)
			(layer "F.Fab")
			(effects
				(font
					(size 0.7 0.7)
					(thickness 0.15)
				)
				(justify left bottom)
			)
		)
		(fp_text user "Author: Antmicro"
			(at -1.9 5.947 90)
			(layer "F.Fab")
			(effects
				(font
					(size 0.7 0.7)
					(thickness 0.15)
				)
				(justify left bottom)
			)
		)
		(fp_text user "${REFERENCE}"
			(at -1.9 3.947 90)
			(layer "F.Fab")
			(effects
				(font
					(size 0.7 0.7)
					(thickness 0.15)
				)
				(justify left bottom)
			)
		)
		(pad "1" smd roundrect
			(at -1.1 0 90)
			(size 1.2 1.3)
			(layers "F.Cu" "F.Mask" "F.Paste")
			(roundrect_rratio 0.25)
			(net 1 "GND")
			(pintype "passive")
		)
		(pad "2" smd roundrect
			(at 1.1 0 90)
			(size 1.2 1.3)
			(layers "F.Cu" "F.Mask" "F.Paste")
			(roundrect_rratio 0.25)
			(net 13 "VCC")
			(pintype "passive")
		)
	)
	(footprint "antmicro-footprints:C_0402_1005Metric"
		(layer "F.Cu")
		(at 195.2 79)
		(descr "Capacitor SMD 0402")
		(tags "capacitor SMD 0402")
		(property "Reference" "C120"
			(at -3.66 0.34 0)
			(layer "F.SilkS")
			(effects
				(font
					(size 0.7 0.7)
					(thickness 0.15)
				)
				(justify left bottom)
			)
		)
		(property "Value" "C_10u_0402"
			(at -1.022927 2.155213 0)
			(layer "F.Fab")
			(effects
				(font
					(size 0.7 0.7)
					(thickness 0.15)
				)
				(justify left bottom)
			)
		)
		(property "Datasheet" "https://www.yageo.com/en/Chart/Download/pdf/CC0402MRX5R5BB106"
			(at 0 0 0)
			(layer "F.Fab")
			(hide yes)
			(effects
				(font
					(size 1.27 1.27)
					(thickness 0.15)
				)
			)
		)
		(property "Description" "SMD Multilayer Ceramic Capacitor, 10 µF, 6.3 V, 0402 [1005 Metric], ± 20%, X5R, CC Series"
			(at 0 0 0)
			(layer "F.Fab")
			(hide yes)
			(effects
				(font
					(size 1.27 1.27)
					(thickness 0.15)
				)
			)
		)
		(property "MPN" "CC0402MRX5R5BB106"
			(at 0 0 0)
			(unlocked yes)
			(layer "F.Fab")
			(hide yes)
			(effects
				(font
					(size 1 1)
					(thickness 0.15)
				)
			)
		)
		(property "Manufacturer" "YAGEO"
			(at 0 0 0)
			(unlocked yes)
			(layer "F.Fab")
			(hide yes)
			(effects
				(font
					(size 1 1)
					(thickness 0.15)
				)
			)
		)
		(property "License" "Apache-2.0"
			(at 0 0 0)
			(unlocked yes)
			(layer "F.Fab")
			(hide yes)
			(effects
				(font
					(size 1 1)
					(thickness 0.15)
				)
			)
		)
		(property "Author" "Antmicro"
			(at 0 0 0)
			(unlocked yes)
			(layer "F.Fab")
			(hide yes)
			(effects
				(font
					(size 1 1)
					(thickness 0.15)
				)
			)
		)
		(property "Val" "10u"
			(at 0 0 0)
			(unlocked yes)
			(layer "F.Fab")
			(hide yes)
			(effects
				(font
					(size 1 1)
					(thickness 0.15)
				)
			)
		)
		(property "Voltage" ""
			(at 0 0 0)
			(unlocked yes)
			(layer "F.Fab")
			(hide yes)
			(effects
				(font
					(size 1 1)
					(thickness 0.15)
				)
			)
		)
		(property "Dielectric" ""
			(at 0 0 0)
			(unlocked yes)
			(layer "F.Fab")
			(hide yes)
			(effects
				(font
					(size 1 1)
					(thickness 0.15)
				)
			)
		)
		(sheetname "/USB Debug, PD/")
		(sheetfile "usb_debug_pd.kicad_sch")
		(attr smd)
		(fp_poly
			(pts
				(xy -0.925 -0.47) (xy 0.925 -0.47) (xy 0.925 0.47) (xy -0.925 0.47)
			)
			(stroke
				(width 0.05)
				(type default)
			)
			(fill no)
			(layer "F.CrtYd")
		)
		(fp_line
			(start -0.494 -0.25)
			(end 0.504 -0.25)
			(stroke
				(width 0.15)
				(type solid)
			)
			(layer "F.Fab")
		)
		(fp_line
			(start -0.494 0.248)
			(end -0.494 -0.25)
			(stroke
				(width 0.15)
				(type solid)
			)
			(layer "F.Fab")
		)
		(fp_line
			(start 0.504 -0.25)
			(end 0.504 0.248)
			(stroke
				(width 0.15)
				(type solid)
			)
			(layer "F.Fab")
		)
		(fp_line
			(start 0.504 0.248)
			(end -0.494 0.248)
			(stroke
				(width 0.15)
				(type solid)
			)
			(layer "F.Fab")
		)
		(fp_text user "License: Apache-2.0"
			(at -0.939 5.799 0)
			(layer "F.Fab")
			(effects
				(font
					(size 0.7 0.7)
					(thickness 0.15)
				)
				(justify left bottom)
			)
		)
		(fp_text user "Author: Antmicro"
			(at -0.939 3.399 0)
			(layer "F.Fab")
			(effects
				(font
					(size 0.7 0.7)
					(thickness 0.15)
				)
				(justify left bottom)
			)
		)
		(fp_text user "${REFERENCE}"
			(at -0.939 4.599 0)
			(layer "F.Fab")
			(effects
				(font
					(size 0.7 0.7)
					(thickness 0.15)
				)
				(justify left bottom)
			)
		)
		(pad "1" smd roundrect
			(at -0.48 0)
			(size 0.59 0.64)
			(layers "F.Cu" "F.Mask" "F.Paste")
			(roundrect_rratio 0.25)
			(net 1 "GND")
			(pintype "passive")
		)
		(pad "2" smd roundrect
			(at 0.48 0)
			(size 0.59 0.64)
			(layers "F.Cu" "F.Mask" "F.Paste")
			(roundrect_rratio 0.25)
			(net 293 "/USB Debug, PD/PDC_LDO_1V8")
			(pintype "passive")
		)
	)
	(footprint "antmicro-footprints:C_0402_1005Metric"
		(layer "F.Cu")
		(at 172.399468 119.226)
		(descr "Capacitor SMD 0402")
		(tags "capacitor SMD 0402")
		(property "Reference" "C383"
			(at -5.599468 0.374 0)
			(layer "F.SilkS")
			(effects
				(font
					(size 0.7 0.7)
					(thickness 0.15)
				)
				(justify left bottom)
			)
		)
		(property "Value" "C_100n_0402"
			(at -1.022927 2.155213 0)
			(layer "F.Fab")
			(effects
				(font
					(size 0.7 0.7)
					(thickness 0.15)
				)
				(justify left bottom)
			)
		)
		(property "Datasheet" "https://www.murata.com/products/productdetail?partno=GRM155R61H104KE14%23"
			(at 0 0 0)
			(layer "F.Fab")
			(hide yes)
			(effects
				(font
					(size 1.27 1.27)
					(thickness 0.15)
				)
			)
		)
		(property "Description" "SMD Multilayer Ceramic Capacitor, 0.1 µF, 50 V, 0402 [1005 Metric], ± 10%, X5R, GRM Series"
			(at 0 0 0)
			(layer "F.Fab")
			(hide yes)
			(effects
				(font
					(size 1.27 1.27)
					(thickness 0.15)
				)
			)
		)
		(property "Manufacturer" "Murata"
			(at 0 0 0)
			(unlocked yes)
			(layer "F.Fab")
			(hide yes)
			(effects
				(font
					(size 1 1)
					(thickness 0.15)
				)
			)
		)
		(property "MPN" "GRM155R61H104KE14D"
			(at 0 0 0)
			(unlocked yes)
			(layer "F.Fab")
			(hide yes)
			(effects
				(font
					(size 1 1)
					(thickness 0.15)
				)
			)
		)
		(property "Val" "100n"
			(at 0 0 0)
			(unlocked yes)
			(layer "F.Fab")
			(hide yes)
			(effects
				(font
					(size 1 1)
					(thickness 0.15)
				)
			)
		)
		(property "License" "Apache-2.0"
			(at 0 0 0)
			(unlocked yes)
			(layer "F.Fab")
			(hide yes)
			(effects
				(font
					(size 1 1)
					(thickness 0.15)
				)
			)
		)
		(property "Author" "Antmicro"
			(at 0 0 0)
			(unlocked yes)
			(layer "F.Fab")
			(hide yes)
			(effects
				(font
					(size 1 1)
					(thickness 0.15)
				)
			)
		)
		(property "Voltage" "50V"
			(at 0 0 0)
			(unlocked yes)
			(layer "F.Fab")
			(hide yes)
			(effects
				(font
					(size 1 1)
					(thickness 0.15)
				)
			)
		)
		(property "Dielectric" "X5R"
			(at 0 0 0)
			(unlocked yes)
			(layer "F.Fab")
			(hide yes)
			(effects
				(font
					(size 1 1)
					(thickness 0.15)
				)
			)
		)
		(sheetname "/DCDC/")
		(sheetfile "dcdc.kicad_sch")
		(attr smd)
		(fp_rect
			(start -0.925 -0.47)
			(end 0.925 0.47)
			(stroke
				(width 0.05)
				(type default)
			)
			(fill no)
			(layer "F.CrtYd")
		)
		(fp_line
			(start -0.494 -0.25)
			(end 0.504 -0.25)
			(stroke
				(width 0.15)
				(type solid)
			)
			(layer "F.Fab")
		)
		(fp_line
			(start -0.494 0.248)
			(end -0.494 -0.25)
			(stroke
				(width 0.15)
				(type solid)
			)
			(layer "F.Fab")
		)
		(fp_line
			(start 0.504 -0.25)
			(end 0.504 0.248)
			(stroke
				(width 0.15)
				(type solid)
			)
			(layer "F.Fab")
		)
		(fp_line
			(start 0.504 0.248)
			(end -0.494 0.248)
			(stroke
				(width 0.15)
				(type solid)
			)
			(layer "F.Fab")
		)
		(fp_text user "License: Apache-2.0"
			(at -0.939 5.799 0)
			(layer "F.Fab")
			(effects
				(font
					(size 0.7 0.7)
					(thickness 0.15)
				)
				(justify left bottom)
			)
		)
		(fp_text user "${REFERENCE}"
			(at -0.939 4.599 0)
			(layer "F.Fab")
			(effects
				(font
					(size 0.7 0.7)
					(thickness 0.15)
				)
				(justify left bottom)
			)
		)
		(fp_text user "Author: Antmicro"
			(at -0.939 3.399 0)
			(layer "F.Fab")
			(effects
				(font
					(size 0.7 0.7)
					(thickness 0.15)
				)
				(justify left bottom)
			)
		)
		(pad "1" smd roundrect
			(at -0.48 0)
			(size 0.59 0.64)
			(layers "F.Cu" "F.Mask" "F.Paste")
			(roundrect_rratio 0.25)
			(net 1161 "Net-(U50-IN-)")
			(pintype "passive")
		)
		(pad "2" smd roundrect
			(at 0.48 0)
			(size 0.59 0.64)
			(layers "F.Cu" "F.Mask" "F.Paste")
			(roundrect_rratio 0.25)
			(net 1281 "Net-(U50-IN+)")
			(pintype "passive")
		)
	)
	(footprint "antmicro-footprints:L_Bourns-SRP5030CA"
		(layer "F.Cu")
		(at 178.765 134.5 180)
		(property "Reference" "L2"
			(at -3.079468 2.13 90)
			(layer "F.SilkS")
			(effects
				(font
					(size 0.7 0.7)
					(thickness 0.15)
				)
				(justify right top)
			)
		)
		(property "Value" "L_560n_17.7A_Bourns-SRP5030CA"
			(at 0 4.241 0)
			(layer "F.Fab")
			(effects
				(font
					(size 0.7 0.7)
					(thickness 0.15)
				)
				(justify right top)
			)
		)
		(property "Datasheet" "https://www.bourns.com/docs/Product-Datasheets/SRP5030CA.pdf"
			(at 0 0 0)
			(layer "F.Fab")
			(hide yes)
			(effects
				(font
					(size 1.27 1.27)
					(thickness 0.15)
				)
			)
		)
		(property "Description" "Power Inductor (SMT), 560 nH, 17.7 A, Shielded, 22.2 A, SRP5030CA"
			(at 0 0 0)
			(layer "F.Fab")
			(hide yes)
			(effects
				(font
					(size 1.27 1.27)
					(thickness 0.15)
				)
			)
		)
		(property "Val" "560n/17.7A"
			(at 0 0 180)
			(unlocked yes)
			(layer "F.Fab")
			(hide yes)
			(effects
				(font
					(size 1 1)
					(thickness 0.15)
				)
			)
		)
		(property "Manufacturer" "Bourns"
			(at 0 0 180)
			(unlocked yes)
			(layer "F.Fab")
			(hide yes)
			(effects
				(font
					(size 1 1)
					(thickness 0.15)
				)
			)
		)
		(property "MPN" "SRP5030CA-R56M"
			(at 0 0 180)
			(unlocked yes)
			(layer "F.Fab")
			(hide yes)
			(effects
				(font
					(size 1 1)
					(thickness 0.15)
				)
			)
		)
		(property "ISat" "22.2 A"
			(at 0 0 180)
			(unlocked yes)
			(layer "F.Fab")
			(hide yes)
			(effects
				(font
					(size 1 1)
					(thickness 0.15)
				)
			)
		)
		(property "IMax" "17.7 A"
			(at 0 0 180)
			(unlocked yes)
			(layer "F.Fab")
			(hide yes)
			(effects
				(font
					(size 1 1)
					(thickness 0.15)
				)
			)
		)
		(property "Size" "5.5x5.3"
			(at 0 0 180)
			(unlocked yes)
			(layer "F.Fab")
			(hide yes)
			(effects
				(font
					(size 1 1)
					(thickness 0.15)
				)
			)
		)
		(property "Author" "Antmicro"
			(at 0 0 180)
			(unlocked yes)
			(layer "F.Fab")
			(hide yes)
			(effects
				(font
					(size 1 1)
					(thickness 0.15)
				)
			)
		)
		(property "License" "Apache-2.0"
			(at 0 0 180)
			(unlocked yes)
			(layer "F.Fab")
			(hide yes)
			(effects
				(font
					(size 1 1)
					(thickness 0.15)
				)
			)
		)
		(sheetname "/DCDC/")
		(sheetfile "dcdc.kicad_sch")
		(attr smd)
		(fp_line
			(start 2.65 2.75)
			(end 2.65 -2.75)
			(stroke
				(width 0.15)
				(type solid)
			)
			(layer "F.SilkS")
		)
		(fp_line
			(start -2.65 2.75)
			(end 2.65 2.75)
			(stroke
				(width 0.15)
				(type solid)
			)
			(layer "F.SilkS")
		)
		(fp_line
			(start -2.65 2.75)
			(end -2.65 -2.75)
			(stroke
				(width 0.15)
				(type solid)
			)
			(layer "F.SilkS")
		)
		(fp_line
			(start -2.65 -2.75)
			(end 2.65 -2.75)
			(stroke
				(width 0.15)
				(type solid)
			)
			(layer "F.SilkS")
		)
		(fp_rect
			(start -2.89 -2.99)
			(end 2.89 2.99)
			(stroke
				(width 0.05)
				(type solid)
			)
			(fill no)
			(layer "F.CrtYd")
		)
		(fp_line
			(start 2.65 2.75)
			(end -2.65 2.75)
			(stroke
				(width 0.15)
				(type solid)
			)
			(layer "F.Fab")
		)
		(fp_line
			(start 2.65 -2.75)
			(end 2.65 2.75)
			(stroke
				(width 0.15)
				(type solid)
			)
			(layer "F.Fab")
		)
		(fp_line
			(start -2.65 2.75)
			(end -2.65 -2.75)
			(stroke
				(width 0.15)
				(type solid)
			)
			(layer "F.Fab")
		)
		(fp_line
			(start -2.65 -2.75)
			(end 2.65 -2.75)
			(stroke
				(width 0.15)
				(type solid)
			)
			(layer "F.Fab")
		)
		(fp_text user "${REFERENCE}"
			(at -2.89 8.641 0)
			(layer "F.Fab")
			(effects
				(font
					(size 0.7 0.7)
					(thickness 0.15)
				)
				(justify right top)
			)
		)
		(fp_text user "Author: Antmicro"
			(at -2.89 7.441 0)
			(layer "F.Fab")
			(effects
				(font
					(size 0.7 0.7)
					(thickness 0.15)
				)
				(justify right top)
			)
		)
		(fp_text user "License: Apache-2.0"
			(at -2.89 6.241 0)
			(layer "F.Fab")
			(effects
				(font
					(size 0.7 0.7)
					(thickness 0.15)
				)
				(justify right top)
			)
		)
		(pad "1" smd roundrect
			(at -1.625 0 180)
			(size 1.25 4.7)
			(layers "F.Cu" "F.Mask" "F.Paste")
			(roundrect_rratio 0.1)
			(net 1182 "/DCDC/3V3_SW")
			(pintype "passive")
		)
		(pad "2" smd roundrect
			(at 1.625 0 180)
			(size 1.25 4.7)
			(layers "F.Cu" "F.Mask" "F.Paste")
			(roundrect_rratio 0.1)
			(net 567 "/DCDC/3V3_OUT")
			(pintype "passive")
		)
	)
	(footprint "antmicro-footprints:C_0402_1005Metric"
		(layer "F.Cu")
		(at 61 92.3 -90)
		(descr "Capacitor SMD 0402")
		(tags "capacitor SMD 0402")
		(property "Reference" "C164"
			(at -1.4 -0.7 90)
			(layer "F.SilkS")
			(effects
				(font
					(size 0.7 0.7)
					(thickness 0.15)
				)
				(justify right top)
			)
		)
		(property "Value" "C_1u_0402"
			(at -1.022927 2.155213 90)
			(layer "F.Fab")
			(effects
				(font
					(size 0.7 0.7)
					(thickness 0.15)
				)
				(justify right top)
			)
		)
		(property "Datasheet" "https://product.tdk.com/en/search/capacitor/ceramic/mlcc/info?part_no=C1005X6S1A105K050BC"
			(at 0 0 90)
			(layer "F.Fab")
			(hide yes)
			(effects
				(font
					(size 1.27 1.27)
					(thickness 0.15)
				)
			)
		)
		(property "Description" "SMD Multilayer Ceramic Capacitor, 1 µF, 10 V, 0402 [1005 Metric], ± 10%, X6S, C"
			(at 0 0 90)
			(layer "F.Fab")
			(hide yes)
			(effects
				(font
					(size 1.27 1.27)
					(thickness 0.15)
				)
			)
		)
		(property "Manufacturer" "TDK"
			(at 0 0 270)
			(unlocked yes)
			(layer "F.Fab")
			(hide yes)
			(effects
				(font
					(size 1 1)
					(thickness 0.15)
				)
			)
		)
		(property "MPN" "C1005X6S1A105K050BC"
			(at 0 0 270)
			(unlocked yes)
			(layer "F.Fab")
			(hide yes)
			(effects
				(font
					(size 1 1)
					(thickness 0.15)
				)
			)
		)
		(property "Val" "1u"
			(at 0 0 270)
			(unlocked yes)
			(layer "F.Fab")
			(hide yes)
			(effects
				(font
					(size 1 1)
					(thickness 0.15)
				)
			)
		)
		(property "License" "Apache-2.0"
			(at 0 0 270)
			(unlocked yes)
			(layer "F.Fab")
			(hide yes)
			(effects
				(font
					(size 1 1)
					(thickness 0.15)
				)
			)
		)
		(property "Author" "Antmicro"
			(at 0 0 270)
			(unlocked yes)
			(layer "F.Fab")
			(hide yes)
			(effects
				(font
					(size 1 1)
					(thickness 0.15)
				)
			)
		)
		(property "Voltage" ""
			(at 0 0 270)
			(unlocked yes)
			(layer "F.Fab")
			(hide yes)
			(effects
				(font
					(size 1 1)
					(thickness 0.15)
				)
			)
		)
		(property "Dielectric" ""
			(at 0 0 270)
			(unlocked yes)
			(layer "F.Fab")
			(hide yes)
			(effects
				(font
					(size 1 1)
					(thickness 0.15)
				)
			)
		)
		(sheetname "/CSI/")
		(sheetfile "csi.kicad_sch")
		(attr smd)
		(fp_poly
			(pts
				(xy -0.925 -0.47) (xy 0.925 -0.47) (xy 0.925 0.47) (xy -0.925 0.47)
			)
			(stroke
				(width 0.05)
				(type default)
			)
			(fill no)
			(layer "F.CrtYd")
		)
		(fp_line
			(start -0.494 0.248)
			(end -0.494 -0.25)
			(stroke
				(width 0.15)
				(type solid)
			)
			(layer "F.Fab")
		)
		(fp_line
			(start 0.504 0.248)
			(end -0.494 0.248)
			(stroke
				(width 0.15)
				(type solid)
			)
			(layer "F.Fab")
		)
		(fp_line
			(start -0.494 -0.25)
			(end 0.504 -0.25)
			(stroke
				(width 0.15)
				(type solid)
			)
			(layer "F.Fab")
		)
		(fp_line
			(start 0.504 -0.25)
			(end 0.504 0.248)
			(stroke
				(width 0.15)
				(type solid)
			)
			(layer "F.Fab")
		)
		(fp_text user "License: Apache-2.0"
			(at -0.939 5.799 90)
			(layer "F.Fab")
			(effects
				(font
					(size 0.7 0.7)
					(thickness 0.15)
				)
				(justify right top)
			)
		)
		(fp_text user "${REFERENCE}"
			(at -0.939 4.599 90)
			(layer "F.Fab")
			(effects
				(font
					(size 0.7 0.7)
					(thickness 0.15)
				)
				(justify right top)
			)
		)
		(fp_text user "Author: Antmicro"
			(at -0.939 3.399 90)
			(layer "F.Fab")
			(effects
				(font
					(size 0.7 0.7)
					(thickness 0.15)
				)
				(justify right top)
			)
		)
		(pad "1" smd roundrect
			(at -0.48 0 270)
			(size 0.59 0.64)
			(layers "F.Cu" "F.Mask" "F.Paste")
			(roundrect_rratio 0.25)
			(net 1 "GND")
			(pintype "passive")
		)
		(pad "2" smd roundrect
			(at 0.48 0 270)
			(size 0.59 0.64)
			(layers "F.Cu" "F.Mask" "F.Paste")
			(roundrect_rratio 0.25)
			(net 6 "/CSI/CSIA_3V3")
			(pintype "passive")
		)
	)
	(footprint "antmicro-footprints:C_0402_1005Metric"
		(layer "F.Cu")
		(at 205.6 82.5)
		(descr "Capacitor SMD 0402")
		(tags "capacitor SMD 0402")
		(property "Reference" "C136"
			(at 0.8 0.4 0)
			(layer "F.SilkS")
			(effects
				(font
					(size 0.7 0.7)
					(thickness 0.15)
				)
				(justify left bottom)
			)
		)
		(property "Value" "C_100n_0402"
			(at -1.022927 2.155213 0)
			(layer "F.Fab")
			(effects
				(font
					(size 0.7 0.7)
					(thickness 0.15)
				)
				(justify left bottom)
			)
		)
		(property "Datasheet" "https://www.murata.com/products/productdetail?partno=GRM155R61H104KE14%23"
			(at 0 0 0)
			(layer "F.Fab")
			(hide yes)
			(effects
				(font
					(size 1.27 1.27)
					(thickness 0.15)
				)
			)
		)
		(property "Description" "SMD Multilayer Ceramic Capacitor, 0.1 µF, 50 V, 0402 [1005 Metric], ± 10%, X5R, GRM Series"
			(at 0 0 0)
			(layer "F.Fab")
			(hide yes)
			(effects
				(font
					(size 1.27 1.27)
					(thickness 0.15)
				)
			)
		)
		(property "MPN" "GRM155R61H104KE14D"
			(at 0 0 0)
			(unlocked yes)
			(layer "F.Fab")
			(hide yes)
			(effects
				(font
					(size 1 1)
					(thickness 0.15)
				)
			)
		)
		(property "Manufacturer" "Murata"
			(at 0 0 0)
			(unlocked yes)
			(layer "F.Fab")
			(hide yes)
			(effects
				(font
					(size 1 1)
					(thickness 0.15)
				)
			)
		)
		(property "Val" "100n"
			(at 0 0 0)
			(unlocked yes)
			(layer "F.Fab")
			(hide yes)
			(effects
				(font
					(size 1 1)
					(thickness 0.15)
				)
			)
		)
		(property "License" "Apache-2.0"
			(at 0 0 0)
			(unlocked yes)
			(layer "F.Fab")
			(hide yes)
			(effects
				(font
					(size 1 1)
					(thickness 0.15)
				)
			)
		)
		(property "Author" "Antmicro"
			(at 0 0 0)
			(unlocked yes)
			(layer "F.Fab")
			(hide yes)
			(effects
				(font
					(size 1 1)
					(thickness 0.15)
				)
			)
		)
		(property "Voltage" "50V"
			(at 0 0 0)
			(unlocked yes)
			(layer "F.Fab")
			(hide yes)
			(effects
				(font
					(size 1 1)
					(thickness 0.15)
				)
			)
		)
		(property "Dielectric" "X5R"
			(at 0 0 0)
			(unlocked yes)
			(layer "F.Fab")
			(hide yes)
			(effects
				(font
					(size 1 1)
					(thickness 0.15)
				)
			)
		)
		(sheetname "/USB DP Alt mode/")
		(sheetfile "usb_dp.kicad_sch")
		(attr smd)
		(fp_poly
			(pts
				(xy -0.925 -0.47) (xy 0.925 -0.47) (xy 0.925 0.47) (xy -0.925 0.47)
			)
			(stroke
				(width 0.05)
				(type default)
			)
			(fill no)
			(layer "F.CrtYd")
		)
		(fp_line
			(start -0.494 -0.25)
			(end 0.504 -0.25)
			(stroke
				(width 0.15)
				(type solid)
			)
			(layer "F.Fab")
		)
		(fp_line
			(start -0.494 0.248)
			(end -0.494 -0.25)
			(stroke
				(width 0.15)
				(type solid)
			)
			(layer "F.Fab")
		)
		(fp_line
			(start 0.504 -0.25)
			(end 0.504 0.248)
			(stroke
				(width 0.15)
				(type solid)
			)
			(layer "F.Fab")
		)
		(fp_line
			(start 0.504 0.248)
			(end -0.494 0.248)
			(stroke
				(width 0.15)
				(type solid)
			)
			(layer "F.Fab")
		)
		(fp_text user "${REFERENCE}"
			(at -0.939 4.599 0)
			(layer "F.Fab")
			(effects
				(font
					(size 0.7 0.7)
					(thickness 0.15)
				)
				(justify left bottom)
			)
		)
		(fp_text user "Author: Antmicro"
			(at -0.939 3.399 0)
			(layer "F.Fab")
			(effects
				(font
					(size 0.7 0.7)
					(thickness 0.15)
				)
				(justify left bottom)
			)
		)
		(fp_text user "License: Apache-2.0"
			(at -0.939 5.799 0)
			(layer "F.Fab")
			(effects
				(font
					(size 0.7 0.7)
					(thickness 0.15)
				)
				(justify left bottom)
			)
		)
		(pad "1" smd roundrect
			(at -0.48 0)
			(size 0.59 0.64)
			(layers "F.Cu" "F.Mask" "F.Paste")
			(roundrect_rratio 0.25)
			(net 522 "/Power/USBPD1_HV")
			(pintype "passive")
		)
		(pad "2" smd roundrect
			(at 0.48 0)
			(size 0.59 0.64)
			(layers "F.Cu" "F.Mask" "F.Paste")
			(roundrect_rratio 0.25)
			(net 1 "GND")
			(pintype "passive")
		)
	)
	(footprint "antmicro-footprints:C_0402_1005Metric"
		(layer "F.Cu")
		(at 216.6 84.3 90)
		(descr "Capacitor SMD 0402")
		(tags "capacitor SMD 0402")
		(property "Reference" "C126"
			(at 0.9 0.4 90)
			(layer "F.SilkS")
			(effects
				(font
					(size 0.7 0.7)
					(thickness 0.15)
				)
				(justify left bottom)
			)
		)
		(property "Value" "C_100n_0402"
			(at -1.022927 2.155213 90)
			(layer "F.Fab")
			(effects
				(font
					(size 0.7 0.7)
					(thickness 0.15)
				)
				(justify left bottom)
			)
		)
		(property "Datasheet" "https://www.murata.com/products/productdetail?partno=GRM155R61H104KE14%23"
			(at 0 0 90)
			(layer "F.Fab")
			(hide yes)
			(effects
				(font
					(size 1.27 1.27)
					(thickness 0.15)
				)
			)
		)
		(property "Description" "SMD Multilayer Ceramic Capacitor, 0.1 µF, 50 V, 0402 [1005 Metric], ± 10%, X5R, GRM Series"
			(at 0 0 90)
			(layer "F.Fab")
			(hide yes)
			(effects
				(font
					(size 1.27 1.27)
					(thickness 0.15)
				)
			)
		)
		(property "Manufacturer" "Murata"
			(at 0 0 90)
			(unlocked yes)
			(layer "F.Fab")
			(hide yes)
			(effects
				(font
					(size 1 1)
					(thickness 0.15)
				)
			)
		)
		(property "MPN" "GRM155R61H104KE14D"
			(at 0 0 90)
			(unlocked yes)
			(layer "F.Fab")
			(hide yes)
			(effects
				(font
					(size 1 1)
					(thickness 0.15)
				)
			)
		)
		(property "Val" "100n"
			(at 0 0 90)
			(unlocked yes)
			(layer "F.Fab")
			(hide yes)
			(effects
				(font
					(size 1 1)
					(thickness 0.15)
				)
			)
		)
		(property "License" "Apache-2.0"
			(at 0 0 90)
			(unlocked yes)
			(layer "F.Fab")
			(hide yes)
			(effects
				(font
					(size 1 1)
					(thickness 0.15)
				)
			)
		)
		(property "Author" "Antmicro"
			(at 0 0 90)
			(unlocked yes)
			(layer "F.Fab")
			(hide yes)
			(effects
				(font
					(size 1 1)
					(thickness 0.15)
				)
			)
		)
		(property "Voltage" "50V"
			(at 0 0 90)
			(unlocked yes)
			(layer "F.Fab")
			(hide yes)
			(effects
				(font
					(size 1 1)
					(thickness 0.15)
				)
			)
		)
		(property "Dielectric" "X5R"
			(at 0 0 90)
			(unlocked yes)
			(layer "F.Fab")
			(hide yes)
			(effects
				(font
					(size 1 1)
					(thickness 0.15)
				)
			)
		)
		(sheetname "/USB DP Alt mode/")
		(sheetfile "usb_dp.kicad_sch")
		(attr smd)
		(fp_poly
			(pts
				(xy -0.925 -0.47) (xy -0.925 0.47) (xy 0.925 0.47) (xy 0.925 -0.47)
			)
			(stroke
				(width 0.05)
				(type default)
			)
			(fill no)
			(layer "F.CrtYd")
		)
		(fp_line
			(start 0.504 -0.25)
			(end 0.504 0.248)
			(stroke
				(width 0.15)
				(type solid)
			)
			(layer "F.Fab")
		)
		(fp_line
			(start -0.494 -0.25)
			(end 0.504 -0.25)
			(stroke
				(width 0.15)
				(type solid)
			)
			(layer "F.Fab")
		)
		(fp_line
			(start 0.504 0.248)
			(end -0.494 0.248)
			(stroke
				(width 0.15)
				(type solid)
			)
			(layer "F.Fab")
		)
		(fp_line
			(start -0.494 0.248)
			(end -0.494 -0.25)
			(stroke
				(width 0.15)
				(type solid)
			)
			(layer "F.Fab")
		)
		(fp_text user "License: Apache-2.0"
			(at -0.939 5.799 90)
			(layer "F.Fab")
			(effects
				(font
					(size 0.7 0.7)
					(thickness 0.15)
				)
				(justify left bottom)
			)
		)
		(fp_text user "${REFERENCE}"
			(at -0.939 4.599 90)
			(layer "F.Fab")
			(effects
				(font
					(size 0.7 0.7)
					(thickness 0.15)
				)
				(justify left bottom)
			)
		)
		(fp_text user "Author: Antmicro"
			(at -0.939 3.399 90)
			(layer "F.Fab")
			(effects
				(font
					(size 0.7 0.7)
					(thickness 0.15)
				)
				(justify left bottom)
			)
		)
		(pad "1" smd roundrect
			(at -0.48 0 90)
			(size 0.59 0.64)
			(layers "F.Cu" "F.Mask" "F.Paste")
			(roundrect_rratio 0.25)
			(net 2 "+3V3")
			(pintype "passive")
		)
		(pad "2" smd roundrect
			(at 0.48 0 90)
			(size 0.59 0.64)
			(layers "F.Cu" "F.Mask" "F.Paste")
			(roundrect_rratio 0.25)
			(net 1 "GND")
			(pintype "passive")
		)
	)
	(footprint "antmicro-footprints:C_0805_2012Metric"
		(layer "F.Cu")
		(at 171.34 73.32 -90)
		(descr "Capacitor SMD 0805")
		(tags "capacitor SMD 0805")
		(property "Reference" "C285"
			(at 1.78449 -1.468678 90)
			(layer "F.SilkS")
			(effects
				(font
					(size 0.7 0.7)
					(thickness 0.15)
				)
				(justify right top)
			)
		)
		(property "Value" "C_22u_25V_0805"
			(at -2.055717 1.963152 90)
			(layer "F.Fab")
			(effects
				(font
					(size 0.7 0.7)
					(thickness 0.15)
				)
				(justify right top)
			)
		)
		(property "Datasheet" "https://product.samsungsem.com/mlcc/CL21A226MAYNNN.do"
			(at 0 0 90)
			(layer "F.Fab")
			(hide yes)
			(effects
				(font
					(size 1.27 1.27)
					(thickness 0.15)
				)
			)
		)
		(property "Description" "SMT Multilayer Ceramic Capacitor, 22uF, +/-20%, 25V, X5R, 0805 [2012 Metric]"
			(at 0 0 90)
			(layer "F.Fab")
			(hide yes)
			(effects
				(font
					(size 1.27 1.27)
					(thickness 0.15)
				)
			)
		)
		(property "MPN" "CL21A226MAYNNNE"
			(at 0 0 270)
			(unlocked yes)
			(layer "F.Fab")
			(hide yes)
			(effects
				(font
					(size 1 1)
					(thickness 0.15)
				)
			)
		)
		(property "Manufacturer" "Samsung Electro-Mechanics"
			(at 0 0 270)
			(unlocked yes)
			(layer "F.Fab")
			(hide yes)
			(effects
				(font
					(size 1 1)
					(thickness 0.15)
				)
			)
		)
		(property "License" "Apache-2.0"
			(at 0 0 270)
			(unlocked yes)
			(layer "F.Fab")
			(hide yes)
			(effects
				(font
					(size 1 1)
					(thickness 0.15)
				)
			)
		)
		(property "Author" "Antmicro"
			(at 0 0 270)
			(unlocked yes)
			(layer "F.Fab")
			(hide yes)
			(effects
				(font
					(size 1 1)
					(thickness 0.15)
				)
			)
		)
		(property "Val" "22u"
			(at 0 0 270)
			(unlocked yes)
			(layer "F.Fab")
			(hide yes)
			(effects
				(font
					(size 1 1)
					(thickness 0.15)
				)
			)
		)
		(property "Voltage" "25V"
			(at 0 0 270)
			(unlocked yes)
			(layer "F.Fab")
			(hide yes)
			(effects
				(font
					(size 1 1)
					(thickness 0.15)
				)
			)
		)
		(property "Dielectric" "X5R"
			(at 0 0 270)
			(unlocked yes)
			(layer "F.Fab")
			(hide yes)
			(effects
				(font
					(size 1 1)
					(thickness 0.15)
				)
			)
		)
		(property "Public" "False"
			(at 0 0 270)
			(unlocked yes)
			(layer "F.Fab")
			(hide yes)
			(effects
				(font
					(size 1 1)
					(thickness 0.15)
				)
			)
		)
		(component_classes
			(class "DCDC_20V")
		)
		(sheetname "/DCDC/")
		(sheetfile "dcdc.kicad_sch")
		(attr smd)
		(fp_line
			(start -0.3 0.7)
			(end 0.3 0.7)
			(stroke
				(width 0.15)
				(type solid)
			)
			(layer "F.SilkS")
		)
		(fp_line
			(start -0.3 -0.7)
			(end 0.3 -0.7)
			(stroke
				(width 0.15)
				(type solid)
			)
			(layer "F.SilkS")
		)
		(fp_rect
			(start 1.95 -0.9)
			(end -1.95 0.9)
			(stroke
				(width 0.05)
				(type default)
			)
			(fill no)
			(layer "F.CrtYd")
		)
		(fp_rect
			(start -0.95 -0.675)
			(end 0.95 0.675)
			(stroke
				(width 0.15)
				(type solid)
			)
			(fill no)
			(layer "F.Fab")
		)
		(fp_text user "License: Apache-2.0"
			(at -1.9 4.947 90)
			(layer "F.Fab")
			(effects
				(font
					(size 0.7 0.7)
					(thickness 0.15)
				)
				(justify right top)
			)
		)
		(fp_text user "Author: Antmicro"
			(at -1.9 5.947 90)
			(layer "F.Fab")
			(effects
				(font
					(size 0.7 0.7)
					(thickness 0.15)
				)
				(justify right top)
			)
		)
		(fp_text user "${REFERENCE}"
			(at -1.9 3.947 90)
			(layer "F.Fab")
			(effects
				(font
					(size 0.7 0.7)
					(thickness 0.15)
				)
				(justify right top)
			)
		)
		(pad "1" smd roundrect
			(at -1.1 0 270)
			(size 1.2 1.3)
			(layers "F.Cu" "F.Mask" "F.Paste")
			(roundrect_rratio 0.25)
			(net 1 "GND")
			(pintype "passive")
		)
		(pad "2" smd roundrect
			(at 1.1 0 270)
			(size 1.2 1.3)
			(layers "F.Cu" "F.Mask" "F.Paste")
			(roundrect_rratio 0.25)
			(net 1105 "/DCDC/20V_OUT")
			(pintype "passive")
		)
	)
	(footprint "antmicro-footprints:SOIC-8_3.9x4.9x1.75mm_P1.27mm"
		(layer "F.Cu")
		(at 131 138.002 90)
		(property "Reference" "U2"
			(at 0 -2.85 90)
			(layer "F.SilkS")
			(effects
				(font
					(size 0.7 0.7)
					(thickness 0.15)
				)
				(justify left bottom)
			)
		)
		(property "Value" "AT24CS01_SOIC8"
			(at 0 3.65 90)
			(layer "F.Fab")
			(effects
				(font
					(size 0.7 0.7)
					(thickness 0.15)
				)
				(justify left bottom)
			)
		)
		(property "Datasheet" "https://ww1.microchip.com/downloads/aemDocuments/documents/MPD/ProductDocuments/DataSheets/20006330A.pdf"
			(at 0 0 90)
			(layer "F.Fab")
			(hide yes)
			(effects
				(font
					(size 1.27 1.27)
					(thickness 0.15)
				)
			)
		)
		(property "Description" "EEPROM, 1 Kbit, 128 x 8bit, Serial I2C (2-Wire), 1 MHz, SOIC-8"
			(at 0 0 90)
			(layer "F.Fab")
			(hide yes)
			(effects
				(font
					(size 1.27 1.27)
					(thickness 0.15)
				)
			)
		)
		(property "Manufacturer" "Microchip Technology"
			(at 0 0 90)
			(unlocked yes)
			(layer "F.Fab")
			(hide yes)
			(effects
				(font
					(size 1 1)
					(thickness 0.15)
				)
			)
		)
		(property "MPN" "AT24CS01-SSHM-B"
			(at 0 0 90)
			(unlocked yes)
			(layer "F.Fab")
			(hide yes)
			(effects
				(font
					(size 1 1)
					(thickness 0.15)
				)
			)
		)
		(property "Author" "Antmicro"
			(at 0 0 90)
			(unlocked yes)
			(layer "F.Fab")
			(hide yes)
			(effects
				(font
					(size 1 1)
					(thickness 0.15)
				)
			)
		)
		(property "License" "Apache-2.0"
			(at 0 0 90)
			(unlocked yes)
			(layer "F.Fab")
			(hide yes)
			(effects
				(font
					(size 1 1)
					(thickness 0.15)
				)
			)
		)
		(sheetname "/Expansion connector/")
		(sheetfile "expansion_connector.kicad_sch")
		(attr smd)
		(fp_line
			(start -1.95 -2.452)
			(end 1.95 -2.45)
			(stroke
				(width 0.15)
				(type solid)
			)
			(layer "F.SilkS")
		)
		(fp_line
			(start -1.95 2.45)
			(end 1.95 2.45)
			(stroke
				(width 0.15)
				(type solid)
			)
			(layer "F.SilkS")
		)
		(fp_circle
			(center -2.4 -2.45)
			(end -2.35 -2.4)
			(stroke
				(width 0.15)
				(type solid)
			)
			(fill yes)
			(layer "F.SilkS")
		)
		(fp_rect
			(start -3.625 -2.7)
			(end 3.625 2.7)
			(stroke
				(width 0.05)
				(type solid)
			)
			(fill no)
			(layer "F.CrtYd")
		)
		(fp_line
			(start 1.949 -2.452)
			(end 1.949 2.45)
			(stroke
				(width 0.15)
				(type solid)
			)
			(layer "F.Fab")
		)
		(fp_line
			(start -0.683 -2.452)
			(end 1.949 -2.452)
			(stroke
				(width 0.15)
				(type solid)
			)
			(layer "F.Fab")
		)
		(fp_line
			(start -1.95 -1.18)
			(end -0.683 -2.452)
			(stroke
				(width 0.15)
				(type solid)
			)
			(layer "F.Fab")
		)
		(fp_line
			(start 1.949 2.45)
			(end -1.95 2.45)
			(stroke
				(width 0.15)
				(type solid)
			)
			(layer "F.Fab")
		)
		(fp_line
			(start -1.95 2.45)
			(end -1.95 -1.18)
			(stroke
				(width 0.15)
				(type solid)
			)
			(layer "F.Fab")
		)
		(fp_text user "Author: Antmicro"
			(at -3.476 6.099 90)
			(layer "F.Fab")
			(effects
				(font
					(size 0.7 0.7)
					(thickness 0.15)
				)
				(justify left bottom)
			)
		)
		(fp_text user "License: Apache-2.0"
			(at -3.476 5.099 90)
			(layer "F.Fab")
			(effects
				(font
					(size 0.7 0.7)
					(thickness 0.15)
				)
				(justify left bottom)
			)
		)
		(fp_text user "${REFERENCE}"
			(at -3.476 7.099 90)
			(layer "F.Fab")
			(effects
				(font
					(size 0.7 0.7)
					(thickness 0.15)
				)
				(justify left bottom)
			)
		)
		(pad "1" smd roundrect
			(at -2.714 -1.905 180)
			(size 0.65 1.525)
			(layers "F.Cu" "F.Mask" "F.Paste")
			(roundrect_rratio 0.25)
			(net 677 "/Expansion connector/ADDR0")
			(pinfunction "A0")
			(pintype "input")
		)
		(pad "2" smd roundrect
			(at -2.714 -0.635 180)
			(size 0.65 1.525)
			(layers "F.Cu" "F.Mask" "F.Paste")
			(roundrect_rratio 0.25)
			(net 472 "/Expansion connector/ADDR1")
			(pinfunction "A1")
			(pintype "input")
		)
		(pad "3" smd roundrect
			(at -2.714 0.632 180)
			(size 0.65 1.525)
			(layers "F.Cu" "F.Mask" "F.Paste")
			(roundrect_rratio 0.25)
			(net 1 "GND")
			(pinfunction "A2")
			(pintype "input")
		)
		(pad "4" smd roundrect
			(at -2.714 1.902 180)
			(size 0.65 1.525)
			(layers "F.Cu" "F.Mask" "F.Paste")
			(roundrect_rratio 0.25)
			(net 1 "GND")
			(pinfunction "GND")
			(pintype "power_in")
		)
		(pad "5" smd roundrect
			(at 2.712 1.902 180)
			(size 0.65 1.525)
			(layers "F.Cu" "F.Mask" "F.Paste")
			(roundrect_rratio 0.25)
			(net 561 "/Expansion connector/I2C0.SDA")
			(pinfunction "SDA")
			(pintype "bidirectional")
		)
		(pad "6" smd roundrect
			(at 2.712 0.632 180)
			(size 0.65 1.525)
			(layers "F.Cu" "F.Mask" "F.Paste")
			(roundrect_rratio 0.25)
			(net 407 "/Expansion connector/I2C0.SCL")
			(pinfunction "SCL")
			(pintype "input")
		)
		(pad "7" smd roundrect
			(at 2.712 -0.635 180)
			(size 0.65 1.525)
			(layers "F.Cu" "F.Mask" "F.Paste")
			(roundrect_rratio 0.25)
			(net 1 "GND")
			(pinfunction "WP")
			(pintype "input")
		)
		(pad "8" smd roundrect
			(at 2.712 -1.905 180)
			(size 0.65 1.525)
			(layers "F.Cu" "F.Mask" "F.Paste")
			(roundrect_rratio 0.25)
			(net 148 "/Expansion connector/+3V3_AUX")
			(pinfunction "VCC")
			(pintype "power_in")
		)
	)
	(footprint "antmicro-footprints:R_0402_1005Metric"
		(layer "F.Cu")
		(at 88 61.5 180)
		(descr "Resistor SMD 0402")
		(tags "resistor SMD 0402")
		(property "Reference" "R224"
			(at 16.3 -8.8 0)
			(layer "F.SilkS")
			(effects
				(font
					(size 0.7 0.7)
					(thickness 0.15)
				)
				(justify right top)
			)
		)
		(property "Value" "R_10k_0402"
			(at -1.011843 1.772047 0)
			(layer "F.Fab")
			(effects
				(font
					(size 0.7 0.7)
					(thickness 0.15)
				)
				(justify right top)
			)
		)
		(property "Datasheet" "https://www.bourns.com/docs/product-datasheets/cr.pdf"
			(at 0 0 0)
			(layer "F.Fab")
			(hide yes)
			(effects
				(font
					(size 1.27 1.27)
					(thickness 0.15)
				)
			)
		)
		(property "Description" "SMD Chip Resistor, 10 kohm, ± 1%, 62.5 mW, 0402 [1005 Metric], Thick Film, General Purpose"
			(at 0 0 0)
			(layer "F.Fab")
			(hide yes)
			(effects
				(font
					(size 1.27 1.27)
					(thickness 0.15)
				)
			)
		)
		(property "MPN" "CR0402-FX-1002GLF"
			(at 0 0 180)
			(unlocked yes)
			(layer "F.Fab")
			(hide yes)
			(effects
				(font
					(size 1 1)
					(thickness 0.15)
				)
			)
		)
		(property "Manufacturer" "Bourns"
			(at 0 0 180)
			(unlocked yes)
			(layer "F.Fab")
			(hide yes)
			(effects
				(font
					(size 1 1)
					(thickness 0.15)
				)
			)
		)
		(property "License" "Apache-2.0"
			(at 0 0 180)
			(unlocked yes)
			(layer "F.Fab")
			(hide yes)
			(effects
				(font
					(size 1 1)
					(thickness 0.15)
				)
			)
		)
		(property "Author" "Antmicro"
			(at 0 0 180)
			(unlocked yes)
			(layer "F.Fab")
			(hide yes)
			(effects
				(font
					(size 1 1)
					(thickness 0.15)
				)
			)
		)
		(property "Val" "10k"
			(at 0 0 180)
			(unlocked yes)
			(layer "F.Fab")
			(hide yes)
			(effects
				(font
					(size 1 1)
					(thickness 0.15)
				)
			)
		)
		(property "Tolerance" "1%"
			(at 0 0 180)
			(unlocked yes)
			(layer "F.Fab")
			(hide yes)
			(effects
				(font
					(size 1 1)
					(thickness 0.15)
				)
			)
		)
		(sheetname "/SoM_Power/")
		(sheetfile "som_power.kicad_sch")
		(attr smd)
		(fp_rect
			(start -0.925 -0.47)
			(end 0.925 0.47)
			(stroke
				(width 0.05)
				(type default)
			)
			(fill no)
			(layer "F.CrtYd")
		)
		(fp_rect
			(start -0.5 -0.25)
			(end 0.5 0.25)
			(stroke
				(width 0.15)
				(type solid)
			)
			(fill no)
			(layer "F.Fab")
		)
		(fp_text user "Author: Antmicro"
			(at -0.95 4.169 0)
			(layer "F.Fab")
			(effects
				(font
					(size 0.7 0.7)
					(thickness 0.15)
				)
				(justify right top)
			)
		)
		(fp_text user "License: Apache-2.0"
			(at -0.95 5.169 0)
			(layer "F.Fab")
			(effects
				(font
					(size 0.7 0.7)
					(thickness 0.15)
				)
				(justify right top)
			)
		)
		(fp_text user "${REFERENCE}"
			(at -0.95 3.168 0)
			(layer "F.Fab")
			(effects
				(font
					(size 0.7 0.7)
					(thickness 0.15)
				)
				(justify right top)
			)
		)
		(pad "1" smd roundrect
			(at -0.48 0 180)
			(size 0.59 0.64)
			(layers "F.Cu" "F.Mask" "F.Paste")
			(roundrect_rratio 0.25)
			(net 1027 "Net-(U70-~{CLR})")
			(pintype "passive")
		)
		(pad "2" smd roundrect
			(at 0.48 0 180)
			(size 0.59 0.64)
			(layers "F.Cu" "F.Mask" "F.Paste")
			(roundrect_rratio 0.25)
			(net 213 "+5V_SOM")
			(pintype "passive")
		)
	)
	(footprint "antmicro-footprints:SOD-523"
		(layer "F.Cu")
		(at 112.45 63.45 180)
		(property "Reference" "D55"
			(at -1.07 -0.73 0)
			(layer "F.SilkS")
			(effects
				(font
					(size 0.7 0.7)
					(thickness 0.15)
				)
				(justify right top)
			)
		)
		(property "Value" "PESD5Z5.0F"
			(at 0 1.499 0)
			(layer "F.Fab")
			(effects
				(font
					(size 0.7 0.7)
					(thickness 0.15)
				)
				(justify right top)
			)
		)
		(property "Datasheet" "https://assets.nexperia.com/documents/data-sheet/PESD5Z5_0.pdf"
			(at 0 0 0)
			(layer "F.Fab")
			(hide yes)
			(effects
				(font
					(size 1.27 1.27)
					(thickness 0.15)
				)
			)
		)
		(property "Description" "Unidirectional TVS, 30 kV,  SOD-523, 5 V, 89 pF"
			(at 0 0 0)
			(layer "F.Fab")
			(hide yes)
			(effects
				(font
					(size 1.27 1.27)
					(thickness 0.15)
				)
			)
		)
		(property "Manufacturer" "Nexperia"
			(at 0 0 180)
			(unlocked yes)
			(layer "F.Fab")
			(hide yes)
			(effects
				(font
					(size 1 1)
					(thickness 0.15)
				)
			)
		)
		(property "MPN" "PESD5Z5.0F"
			(at 0 0 180)
			(unlocked yes)
			(layer "F.Fab")
			(hide yes)
			(effects
				(font
					(size 1 1)
					(thickness 0.15)
				)
			)
		)
		(property "Author" "Antmicro"
			(at 0 0 180)
			(unlocked yes)
			(layer "F.Fab")
			(hide yes)
			(effects
				(font
					(size 1 1)
					(thickness 0.15)
				)
			)
		)
		(property "License" "Apache-2.0"
			(at 0 0 180)
			(unlocked yes)
			(layer "F.Fab")
			(hide yes)
			(effects
				(font
					(size 1 1)
					(thickness 0.15)
				)
			)
		)
		(sheetname "/SoM_Power/")
		(sheetfile "som_power.kicad_sch")
		(attr smd)
		(fp_line
			(start -0.35 -0.5)
			(end -0.35 0.5)
			(stroke
				(width 0.15)
				(type solid)
			)
			(layer "F.SilkS")
		)
		(fp_poly
			(pts
				(xy -1 -0.6) (xy 1 -0.6) (xy 1 0.6) (xy -1 0.6)
			)
			(stroke
				(width 0.05)
				(type solid)
			)
			(fill no)
			(layer "F.CrtYd")
		)
		(fp_line
			(start 0.65 -0.425)
			(end 0.65 0.423)
			(stroke
				(width 0.15)
				(type solid)
			)
			(layer "F.Fab")
		)
		(fp_line
			(start -0.35 -0.4)
			(end -0.35 0.4)
			(stroke
				(width 0.15)
				(type solid)
			)
			(layer "F.Fab")
		)
		(fp_line
			(start -0.652 0.423)
			(end 0.65 0.423)
			(stroke
				(width 0.15)
				(type solid)
			)
			(layer "F.Fab")
		)
		(fp_line
			(start -0.652 0.423)
			(end -0.652 -0.425)
			(stroke
				(width 0.15)
				(type solid)
			)
			(layer "F.Fab")
		)
		(fp_line
			(start -0.652 -0.425)
			(end 0.65 -0.425)
			(stroke
				(width 0.15)
				(type solid)
			)
			(layer "F.Fab")
		)
		(fp_text user "${REFERENCE}"
			(at -1.276 3.499 0)
			(layer "F.Fab")
			(effects
				(font
					(size 0.7 0.7)
					(thickness 0.15)
				)
				(justify right top)
			)
		)
		(fp_text user "Author: Antmicro"
			(at -1.276 4.7 0)
			(layer "F.Fab")
			(effects
				(font
					(size 0.7 0.7)
					(thickness 0.15)
				)
				(justify right top)
			)
		)
		(fp_text user "License: Apache-2.0"
			(at -1.276 5.9 0)
			(layer "F.Fab")
			(effects
				(font
					(size 0.7 0.7)
					(thickness 0.15)
				)
				(justify right top)
			)
		)
		(pad "1" smd roundrect
			(at -0.701 0 180)
			(size 0.5 0.6)
			(layers "F.Cu" "F.Mask" "F.Paste")
			(roundrect_rratio 0.25)
			(net 213 "+5V_SOM")
			(pinfunction "C")
			(pintype "passive")
		)
		(pad "2" smd roundrect
			(at 0.699001 0 180)
			(size 0.5 0.6)
			(layers "F.Cu" "F.Mask" "F.Paste")
			(roundrect_rratio 0.25)
			(net 1 "GND")
			(pinfunction "A")
			(pintype "passive")
		)
	)
	(footprint "antmicro-footprints:XDFN-2_1x0.60mm"
		(layer "F.Cu")
		(at 195.25 55.5 -90)
		(property "Reference" "D5"
			(at 0.6 0.55 90)
			(layer "F.SilkS")
			(effects
				(font
					(size 0.7 0.7)
					(thickness 0.15)
				)
				(justify left bottom)
			)
		)
		(property "Value" "TPD1E0B04_XDFN-2"
			(at 0 1.5 90)
			(layer "F.Fab")
			(effects
				(font
					(size 0.7 0.7)
					(thickness 0.15)
				)
				(justify right top)
			)
		)
		(property "Datasheet" "https://www.ti.com/general/docs/suppproductinfo.tsp?distId=26&gotoUrl=https://www.ti.com/lit/gpn/tpd1e0b04"
			(at 0 0 90)
			(layer "F.Fab")
			(hide yes)
			(effects
				(font
					(size 1.27 1.27)
					(thickness 0.15)
				)
			)
		)
		(property "Description" "Bidirectional TVS, 8 kV,  XDFN-2, 3.6 V, 0.18 pF"
			(at 0 0 90)
			(layer "F.Fab")
			(hide yes)
			(effects
				(font
					(size 1.27 1.27)
					(thickness 0.15)
				)
			)
		)
		(property "MPN" "TPD1E0B04DPYR"
			(at 0 0 90)
			(layer "F.Fab")
			(hide yes)
			(effects
				(font
					(size 1.27 1.27)
					(thickness 0.15)
				)
			)
		)
		(property "Manufacturer" "Texas Instruments"
			(at 0 0 90)
			(layer "F.Fab")
			(hide yes)
			(effects
				(font
					(size 1.27 1.27)
					(thickness 0.15)
				)
			)
		)
		(property "Author" "Antmicro"
			(at 0 0 270)
			(unlocked yes)
			(layer "F.Fab")
			(hide yes)
			(effects
				(font
					(size 1 1)
					(thickness 0.15)
				)
			)
		)
		(property "License" "Apache-2.0"
			(at 0 0 270)
			(unlocked yes)
			(layer "F.Fab")
			(hide yes)
			(effects
				(font
					(size 1 1)
					(thickness 0.15)
				)
			)
		)
		(sheetname "/SoM_Power/")
		(sheetfile "som_power.kicad_sch")
		(attr smd)
		(fp_poly
			(pts
				(xy -0.725 -0.475) (xy 0.725 -0.475) (xy 0.725 0.475) (xy -0.725 0.475)
			)
			(stroke
				(width 0.05)
				(type solid)
			)
			(fill no)
			(layer "F.CrtYd")
		)
		(fp_poly
			(pts
				(xy -0.55 -0.35) (xy 0.55 -0.35) (xy 0.55 0.35) (xy -0.55 0.35)
			)
			(stroke
				(width 0.15)
				(type solid)
			)
			(fill no)
			(layer "F.Fab")
		)
		(fp_text user "Author: Antmicro"
			(at -0.8 4.4 90)
			(layer "F.Fab")
			(effects
				(font
					(size 0.7 0.7)
					(thickness 0.15)
				)
				(justify right top)
			)
		)
		(fp_text user "License: Apache-2.0"
			(at -0.799999 5.6 90)
			(layer "F.Fab")
			(effects
				(font
					(size 0.7 0.7)
					(thickness 0.15)
				)
				(justify right top)
			)
		)
		(fp_text user "${REFERENCE}"
			(at -0.8 3.2 90)
			(layer "F.Fab")
			(effects
				(font
					(size 0.7 0.7)
					(thickness 0.15)
				)
				(justify right top)
			)
		)
		(pad "1" smd roundrect
			(at -0.350999 0 270)
			(size 0.3 0.5)
			(layers "F.Cu" "F.Mask" "F.Paste")
			(roundrect_rratio 0.25)
			(net 1 "GND")
			(pinfunction "C")
			(pintype "passive")
		)
		(pad "2" smd roundrect
			(at 0.349 0 270)
			(size 0.3 0.5)
			(layers "F.Cu" "F.Mask" "F.Paste")
			(roundrect_rratio 0.25)
			(net 702 "/SoM_Power/~{SYS_RESET}")
			(pinfunction "A")
			(pintype "passive")
		)
	)
	(footprint "antmicro-footprints:C_0805_2012Metric"
		(layer "F.Cu")
		(at 174.52 142.4 90)
		(descr "Capacitor SMD 0805")
		(tags "capacitor SMD 0805")
		(property "Reference" "C308"
			(at 1.9 0.18 90)
			(layer "F.SilkS")
			(effects
				(font
					(size 0.7 0.7)
					(thickness 0.15)
				)
				(justify left bottom)
			)
		)
		(property "Value" "C_22u_25V_0805"
			(at -2.055717 1.963152 90)
			(layer "F.Fab")
			(effects
				(font
					(size 0.7 0.7)
					(thickness 0.15)
				)
				(justify left bottom)
			)
		)
		(property "Datasheet" "https://product.samsungsem.com/mlcc/CL21A226MAYNNN.do"
			(at 0 0 90)
			(layer "F.Fab")
			(hide yes)
			(effects
				(font
					(size 1.27 1.27)
					(thickness 0.15)
				)
			)
		)
		(property "Description" "SMT Multilayer Ceramic Capacitor, 22uF, +/-20%, 25V, X5R, 0805 [2012 Metric]"
			(at 0 0 90)
			(layer "F.Fab")
			(hide yes)
			(effects
				(font
					(size 1.27 1.27)
					(thickness 0.15)
				)
			)
		)
		(property "Manufacturer" "Samsung Electro-Mechanics"
			(at 0 0 90)
			(unlocked yes)
			(layer "F.Fab")
			(hide yes)
			(effects
				(font
					(size 1 1)
					(thickness 0.15)
				)
			)
		)
		(property "MPN" "CL21A226MAYNNNE"
			(at 0 0 90)
			(unlocked yes)
			(layer "F.Fab")
			(hide yes)
			(effects
				(font
					(size 1 1)
					(thickness 0.15)
				)
			)
		)
		(property "Val" "22u"
			(at 0 0 90)
			(unlocked yes)
			(layer "F.Fab")
			(hide yes)
			(effects
				(font
					(size 1 1)
					(thickness 0.15)
				)
			)
		)
		(property "License" "Apache-2.0"
			(at 0 0 90)
			(unlocked yes)
			(layer "F.Fab")
			(hide yes)
			(effects
				(font
					(size 1 1)
					(thickness 0.15)
				)
			)
		)
		(property "Author" "Antmicro"
			(at 0 0 90)
			(unlocked yes)
			(layer "F.Fab")
			(hide yes)
			(effects
				(font
					(size 1 1)
					(thickness 0.15)
				)
			)
		)
		(property "Voltage" "25V"
			(at 0 0 90)
			(unlocked yes)
			(layer "F.Fab")
			(hide yes)
			(effects
				(font
					(size 1 1)
					(thickness 0.15)
				)
			)
		)
		(property "Dielectric" "X5R"
			(at 0 0 90)
			(unlocked yes)
			(layer "F.Fab")
			(hide yes)
			(effects
				(font
					(size 1 1)
					(thickness 0.15)
				)
			)
		)
		(property "Public" "False"
			(at 0 0 90)
			(unlocked yes)
			(layer "F.Fab")
			(hide yes)
			(effects
				(font
					(size 1 1)
					(thickness 0.15)
				)
			)
		)
		(sheetname "/DCDC/")
		(sheetfile "dcdc.kicad_sch")
		(attr smd)
		(fp_line
			(start -0.3 -0.7)
			(end 0.3 -0.7)
			(stroke
				(width 0.15)
				(type solid)
			)
			(layer "F.SilkS")
		)
		(fp_line
			(start -0.3 0.7)
			(end 0.3 0.7)
			(stroke
				(width 0.15)
				(type solid)
			)
			(layer "F.SilkS")
		)
		(fp_rect
			(start 1.95 -0.9)
			(end -1.95 0.9)
			(stroke
				(width 0.05)
				(type default)
			)
			(fill no)
			(layer "F.CrtYd")
		)
		(fp_rect
			(start -0.95 -0.675)
			(end 0.95 0.675)
			(stroke
				(width 0.15)
				(type solid)
			)
			(fill no)
			(layer "F.Fab")
		)
		(fp_text user "Author: Antmicro"
			(at -1.9 5.947 90)
			(layer "F.Fab")
			(effects
				(font
					(size 0.7 0.7)
					(thickness 0.15)
				)
				(justify left bottom)
			)
		)
		(fp_text user "${REFERENCE}"
			(at -1.9 3.947 90)
			(layer "F.Fab")
			(effects
				(font
					(size 0.7 0.7)
					(thickness 0.15)
				)
				(justify left bottom)
			)
		)
		(fp_text user "License: Apache-2.0"
			(at -1.9 4.947 90)
			(layer "F.Fab")
			(effects
				(font
					(size 0.7 0.7)
					(thickness 0.15)
				)
				(justify left bottom)
			)
		)
		(pad "1" smd roundrect
			(at -1.1 0 90)
			(size 1.2 1.3)
			(layers "F.Cu" "F.Mask" "F.Paste")
			(roundrect_rratio 0.25)
			(net 1 "GND")
			(pintype "passive")
		)
		(pad "2" smd roundrect
			(at 1.1 0 90)
			(size 1.2 1.3)
			(layers "F.Cu" "F.Mask" "F.Paste")
			(roundrect_rratio 0.25)
			(net 13 "VCC")
			(pintype "passive")
		)
	)
	(footprint "antmicro-footprints:Vishay_PowerPAK_1212-8_Single"
		(layer "F.Cu")
		(at 216.736 72.512)
		(descr "PowerPAK 1212-8 Single")
		(tags "Vishay PowerPAK 1212-8 Single")
		(property "Reference" "Q33"
			(at 2.914 0.388 90)
			(layer "F.SilkS")
			(effects
				(font
					(size 0.7 0.7)
					(thickness 0.15)
				)
				(justify left bottom)
			)
		)
		(property "Value" "SISS05DN-T1-GE3"
			(at 0 2.7 0)
			(layer "F.Fab")
			(effects
				(font
					(size 0.7 0.7)
					(thickness 0.15)
				)
				(justify left bottom)
			)
		)
		(property "Datasheet" "https://www.vishay.com/docs/77029/siss05dn.pdf"
			(at 0 0 0)
			(layer "F.Fab")
			(hide yes)
			(effects
				(font
					(size 1.27 1.27)
					(thickness 0.15)
				)
			)
		)
		(property "Description" "Power MOSFET, P Channel, 30 V, 108 A, 0.0035 ohm, PowerPAK 1212, Surface Mount"
			(at 0 0 0)
			(layer "F.Fab")
			(hide yes)
			(effects
				(font
					(size 1.27 1.27)
					(thickness 0.15)
				)
			)
		)
		(property "MPN" "SISS05DN-T1-GE3"
			(at 0 0 0)
			(unlocked yes)
			(layer "F.Fab")
			(hide yes)
			(effects
				(font
					(size 1 1)
					(thickness 0.15)
				)
			)
		)
		(property "Manufacturer" "Vishay"
			(at 0 0 0)
			(unlocked yes)
			(layer "F.Fab")
			(hide yes)
			(effects
				(font
					(size 1 1)
					(thickness 0.15)
				)
			)
		)
		(property "Author" "Antmicro"
			(at 0 0 0)
			(unlocked yes)
			(layer "F.Fab")
			(hide yes)
			(effects
				(font
					(size 1 1)
					(thickness 0.15)
				)
			)
		)
		(property "License" "Apache-2.0"
			(at 0 0 0)
			(unlocked yes)
			(layer "F.Fab")
			(hide yes)
			(effects
				(font
					(size 1 1)
					(thickness 0.15)
				)
			)
		)
		(sheetname "/Power/")
		(sheetfile "power.kicad_sch")
		(attr smd)
		(fp_line
			(start -1.651 -1.651)
			(end -1.651 -1.317)
			(stroke
				(width 0.15)
				(type solid)
			)
			(layer "F.SilkS")
		)
		(fp_line
			(start -1.651 -1.651)
			(end 1.648 -1.651)
			(stroke
				(width 0.15)
				(type solid)
			)
			(layer "F.SilkS")
		)
		(fp_line
			(start -1.635 1.3)
			(end -1.635 1.634)
			(stroke
				(width 0.15)
				(type solid)
			)
			(layer "F.SilkS")
		)
		(fp_line
			(start -1.635 1.634)
			(end 1.634 1.634)
			(stroke
				(width 0.15)
				(type solid)
			)
			(layer "F.SilkS")
		)
		(fp_line
			(start 1.634 1.3)
			(end 1.634 1.634)
			(stroke
				(width 0.15)
				(type solid)
			)
			(layer "F.SilkS")
		)
		(fp_line
			(start 1.648 -1.651)
			(end 1.648 -1.317)
			(stroke
				(width 0.15)
				(type solid)
			)
			(layer "F.SilkS")
		)
		(fp_circle
			(center -1.9 -1.4)
			(end -1.85 -1.4)
			(stroke
				(width 0.15)
				(type solid)
			)
			(fill yes)
			(layer "F.SilkS")
		)
		(fp_rect
			(start -2 -1.8)
			(end 2 1.798)
			(stroke
				(width 0.05)
				(type solid)
			)
			(fill no)
			(layer "F.CrtYd")
		)
		(fp_line
			(start -1.6425 -1.4175)
			(end -1.4175 -1.6425)
			(stroke
				(width 0.15)
				(type solid)
			)
			(layer "F.Fab")
		)
		(fp_rect
			(start -1.651 -1.651)
			(end 1.648 1.648)
			(stroke
				(width 0.15)
				(type solid)
			)
			(fill no)
			(layer "F.Fab")
		)
		(fp_text user "Author: Antmicro"
			(at -8 5.9 0)
			(layer "F.Fab")
			(effects
				(font
					(size 0.7 0.7)
					(thickness 0.15)
				)
				(justify left bottom)
			)
		)
		(fp_text user "License: Apache-2.0"
			(at -8 7.1 0)
			(layer "F.Fab")
			(effects
				(font
					(size 0.7 0.7)
					(thickness 0.15)
				)
				(justify left bottom)
			)
		)
		(fp_text user "${REFERENCE}"
			(at -8 4.7 0)
			(layer "F.Fab")
			(effects
				(font
					(size 0.7 0.7)
					(thickness 0.15)
				)
				(justify left bottom)
			)
		)
		(pad "1" smd rect
			(at -1.436 -0.99)
			(size 0.99 0.405)
			(layers "F.Cu" "F.Mask" "F.Paste")
			(net 1383 "VCC_NO_OVP")
			(pinfunction "S")
			(pintype "passive")
		)
		(pad "2" smd rect
			(at -1.436 -0.332)
			(size 0.99 0.405)
			(layers "F.Cu" "F.Mask" "F.Paste")
			(net 1383 "VCC_NO_OVP")
			(pinfunction "S")
			(pintype "passive")
		)
		(pad "3" smd rect
			(at -1.436 0.33)
			(size 0.99 0.405)
			(layers "F.Cu" "F.Mask" "F.Paste")
			(net 1383 "VCC_NO_OVP")
			(pinfunction "S")
			(pintype "passive")
		)
		(pad "4" smd rect
			(at -1.436 0.988)
			(size 0.99 0.405)
			(layers "F.Cu" "F.Mask" "F.Paste")
			(net 1384 "Net-(Q32-G)")
			(pinfunction "G")
			(pintype "input")
		)
		(pad "5" smd custom
			(at 0.557 0)
			(size 1.725 2.235)
			(layers "F.Cu" "F.Mask" "F.Paste")
			(net 3 "VCC_IN")
			(pinfunction "D")
			(pintype "passive")
			(zone_connect 2)
			(options
				(clearance outline)
				(anchor rect)
			)
			(primitives
				(gr_poly
					(pts
						(xy 0.8625 0.1275) (xy 0.8625 -0.1275) (xy 1.3725 -0.1275) (xy 1.3725 -0.5325) (xy 0.8625 -0.5325)
						(xy 0.8625 -0.7875) (xy 1.3725 -0.7875) (xy 1.3725 -1.195) (xy 0.6125 -1.195) (xy 0.6125 1.195)
						(xy 1.3725 1.195) (xy 1.3725 0.7875) (xy 0.8625 0.7875) (xy 0.8625 0.5325) (xy 1.3725 0.5325)
						(xy 1.3725 0.1275)
					)
					(width 0)
					(fill yes)
				)
			)
		)
	)
	(footprint "antmicro-footprints:WQFN-30-1EP_4.6x2.6mm_P0.4mm"
		(layer "F.Cu")
		(at 215.249 102.335)
		(property "Reference" "U56"
			(at -1.149 3.565 0)
			(layer "F.SilkS")
			(effects
				(font
					(size 0.7 0.7)
					(thickness 0.15)
				)
				(justify left bottom)
			)
		)
		(property "Value" "HD3SS3220IRNHR"
			(at 0 3.5 0)
			(layer "F.Fab")
			(effects
				(font
					(size 0.7 0.7)
					(thickness 0.15)
				)
				(justify right top)
			)
		)
		(property "Datasheet" "https://www.ti.com/lit/ds/symlink/hd3ss3220.pdf?ts=1663000043694&ref_url=https%253A%252F%252Fwww.google.com%252F"
			(at 0 0 0)
			(layer "F.Fab")
			(hide yes)
			(effects
				(font
					(size 1.27 1.27)
					(thickness 0.15)
				)
			)
		)
		(property "Description" "USB Interface IC 10-Gbps USB 3.1 Type-C 2:1 mux with DRP Controller 30-WQFN -40°C to 85°C"
			(at 0 0 0)
			(layer "F.Fab")
			(hide yes)
			(effects
				(font
					(size 1.27 1.27)
					(thickness 0.15)
				)
			)
		)
		(property "Manufacturer" "Texas Instruments"
			(at 0 0 0)
			(unlocked yes)
			(layer "F.Fab")
			(hide yes)
			(effects
				(font
					(size 1 1)
					(thickness 0.15)
				)
			)
		)
		(property "MPN" "HD3SS3220IRNHR"
			(at 0 0 0)
			(unlocked yes)
			(layer "F.Fab")
			(hide yes)
			(effects
				(font
					(size 1 1)
					(thickness 0.15)
				)
			)
		)
		(property "Author" "Antmicro"
			(at 0 0 0)
			(unlocked yes)
			(layer "F.Fab")
			(hide yes)
			(effects
				(font
					(size 1 1)
					(thickness 0.15)
				)
			)
		)
		(property "License" "Apache-2.0"
			(at 0 0 0)
			(unlocked yes)
			(layer "F.Fab")
			(hide yes)
			(effects
				(font
					(size 1 1)
					(thickness 0.15)
				)
			)
		)
		(sheetname "/Recovery USB/")
		(sheetfile "recovery_usb.kicad_sch")
		(attr smd)
		(fp_line
			(start -1.253 -2.26)
			(end -1.253 -2.01)
			(stroke
				(width 0.15)
				(type solid)
			)
			(layer "F.SilkS")
		)
		(fp_line
			(start -1.253 -2.26)
			(end -1.003 -2.26)
			(stroke
				(width 0.15)
				(type solid)
			)
			(layer "F.SilkS")
		)
		(fp_line
			(start -1.253 2.24)
			(end -1.253 1.99)
			(stroke
				(width 0.15)
				(type solid)
			)
			(layer "F.SilkS")
		)
		(fp_line
			(start -1.253 2.24)
			(end -1.003 2.24)
			(stroke
				(width 0.15)
				(type solid)
			)
			(layer "F.SilkS")
		)
		(fp_line
			(start 1.247 -2.26)
			(end 0.997 -2.26)
			(stroke
				(width 0.15)
				(type solid)
			)
			(layer "F.SilkS")
		)
		(fp_line
			(start 1.247 -2.26)
			(end 1.247 -2.01)
			(stroke
				(width 0.15)
				(type solid)
			)
			(layer "F.SilkS")
		)
		(fp_line
			(start 1.247 2.24)
			(end 0.997 2.24)
			(stroke
				(width 0.15)
				(type solid)
			)
			(layer "F.SilkS")
		)
		(fp_line
			(start 1.247 2.24)
			(end 1.247 1.99)
			(stroke
				(width 0.15)
				(type solid)
			)
			(layer "F.SilkS")
		)
		(fp_circle
			(center -1.5 -2.5)
			(end -1.45 -2.5)
			(stroke
				(width 0.15)
				(type solid)
			)
			(fill yes)
			(layer "F.SilkS")
		)
		(fp_rect
			(start -1.6 -2.6)
			(end 1.6 2.6)
			(stroke
				(width 0.05)
				(type solid)
			)
			(fill no)
			(layer "F.CrtYd")
		)
		(fp_rect
			(start -1.3 -2.3)
			(end 1.3 2.3)
			(stroke
				(width 0.15)
				(type solid)
			)
			(fill no)
			(layer "F.Fab")
		)
		(fp_text user "${REFERENCE}"
			(at -1.6 4.8 0)
			(layer "F.Fab")
			(effects
				(font
					(size 0.7 0.7)
					(thickness 0.15)
				)
				(justify left bottom)
			)
		)
		(fp_text user "Author: Antmicro"
			(at -1.6 6 0)
			(layer "F.Fab")
			(effects
				(font
					(size 0.7 0.7)
					(thickness 0.15)
				)
				(justify left bottom)
			)
		)
		(fp_text user "License: Apache-2.0"
			(at -1.6 7.199 0)
			(layer "F.Fab")
			(effects
				(font
					(size 0.7 0.7)
					(thickness 0.15)
				)
				(justify left bottom)
			)
		)
		(pad "1" smd rect
			(at -1.232 -1.809 90)
			(size 0.2 0.45)
			(layers "F.Cu" "F.Mask" "F.Paste")
			(net 801 "/Recovery USB/USBC2_CC2")
			(pinfunction "CC2")
			(pintype "passive")
		)
		(pad "2" smd rect
			(at -1.203 -1.41 90)
			(size 0.2 0.5)
			(layers "F.Cu" "F.Mask" "F.Paste")
			(net 806 "/Recovery USB/USBC2_CC1")
			(pinfunction "CC1")
			(pintype "passive")
		)
		(pad "3" smd rect
			(at -1.203 -1.01 90)
			(size 0.2 0.5)
			(layers "F.Cu" "F.Mask" "F.Paste")
			(net 1023 "/Recovery USB/USBC2_I_MODE")
			(pinfunction "CURRENT_MODE")
			(pintype "passive")
		)
		(pad "4" smd rect
			(at -1.203 -0.609 90)
			(size 0.2 0.5)
			(layers "F.Cu" "F.Mask" "F.Paste")
			(net 1012 "/Recovery USB/USBC2_PORT")
			(pinfunction "PORT")
			(pintype "passive")
		)
		(pad "5" smd rect
			(at -1.203 -0.21 90)
			(size 0.2 0.5)
			(layers "F.Cu" "F.Mask" "F.Paste")
			(net 1246 "/Recovery USB/USBC2_VBUS_DET_MUX")
			(pinfunction "VBUS_DET")
			(pintype "passive")
		)
		(pad "6" smd rect
			(at -1.203 0.191 90)
			(size 0.2 0.5)
			(layers "F.Cu" "F.Mask" "F.Paste")
			(net 1131 "/Recovery USB/USBSS_TX_P")
			(pinfunction "TX+")
			(pintype "passive")
		)
		(pad "7" smd rect
			(at -1.203 0.59 90)
			(size 0.2 0.5)
			(layers "F.Cu" "F.Mask" "F.Paste")
			(net 1129 "/Recovery USB/USBSS_TX_N")
			(pinfunction "TX-")
			(pintype "passive")
		)
		(pad "8" smd rect
			(at -1.203 0.99 90)
			(size 0.2 0.5)
			(layers "F.Cu" "F.Mask" "F.Paste")
			(net 2 "+3V3")
			(pinfunction "VCC33")
			(pintype "passive")
		)
		(pad "9" smd rect
			(at -1.203 1.391 90)
			(size 0.2 0.5)
			(layers "F.Cu" "F.Mask" "F.Paste")
			(net 1130 "/Recovery USB/USBSS_RX_P")
			(pinfunction "RX+")
			(pintype "passive")
		)
		(pad "10" smd rect
			(at -1.232 1.79 90)
			(size 0.2 0.45)
			(layers "F.Cu" "F.Mask" "F.Paste")
			(net 1128 "/Recovery USB/USBSS_RX_N")
			(pinfunction "RX-")
			(pintype "passive")
		)
		(pad "11" smd rect
			(at -0.804 2.191)
			(size 0.2 0.45)
			(layers "F.Cu" "F.Mask" "F.Paste")
			(net 1013 "/Recovery USB/USBC2_DIR")
			(pinfunction "DIR")
			(pintype "passive")
		)
		(pad "12" smd rect
			(at -0.403 2.191)
			(size 0.2 0.5)
			(layers "F.Cu" "F.Mask" "F.Paste")
			(net 1021 "/Recovery USB/~{USBC2_EN_MUX}")
			(pinfunction "ENn_MUX")
			(pintype "passive")
		)
		(pad "13" smd rect
			(at -0.003 2.191)
			(size 0.2 0.5)
			(layers "F.Cu" "F.Mask" "F.Paste")
			(net 1 "GND")
			(pinfunction "GND")
			(pintype "passive")
		)
		(pad "14" smd rect
			(at 0.396 2.191)
			(size 0.2 0.5)
			(layers "F.Cu" "F.Mask" "F.Paste")
			(net 800 "/Recovery USB/USBC2_RX1_N")
			(pinfunction "RX1-")
			(pintype "passive")
		)
		(pad "15" smd rect
			(at 0.797 2.191)
			(size 0.2 0.45)
			(layers "F.Cu" "F.Mask" "F.Paste")
			(net 802 "/Recovery USB/USBC2_RX1_P")
			(pinfunction "RX1+")
			(pintype "passive")
		)
		(pad "16" smd rect
			(at 1.222 1.79 90)
			(size 0.2 0.45)
			(layers "F.Cu" "F.Mask" "F.Paste")
			(net 234 "/Recovery USB/USBC2_TX1_N")
			(pinfunction "TX1-")
			(pintype "passive")
		)
		(pad "17" smd rect
			(at 1.196 1.391 90)
			(size 0.2 0.5)
			(layers "F.Cu" "F.Mask" "F.Paste")
			(net 242 "/Recovery USB/USBC2_TX1_P")
			(pinfunction "TX1+")
			(pintype "passive")
		)
		(pad "18" smd rect
			(at 1.196 0.99 90)
			(size 0.2 0.5)
			(layers "F.Cu" "F.Mask" "F.Paste")
			(net 807 "/Recovery USB/USBC2_RX2_N")
			(pinfunction "RX2-")
			(pintype "passive")
		)
		(pad "19" smd rect
			(at 1.196 0.59 90)
			(size 0.2 0.5)
			(layers "F.Cu" "F.Mask" "F.Paste")
			(net 804 "/Recovery USB/USBC2_RX2_P")
			(pinfunction "RX2+")
			(pintype "passive")
		)
		(pad "20" smd rect
			(at 1.196 0.191 90)
			(size 0.2 0.5)
			(layers "F.Cu" "F.Mask" "F.Paste")
			(net 237 "/Recovery USB/USBC2_TX2_N")
			(pinfunction "TX2-")
			(pintype "passive")
		)
		(pad "21" smd rect
			(at 1.196 -0.21 90)
			(size 0.2 0.5)
			(layers "F.Cu" "F.Mask" "F.Paste")
			(net 260 "/Recovery USB/USBC2_TX2_P")
			(pinfunction "TX2+")
			(pintype "passive")
		)
		(pad "22" smd rect
			(at 1.196 -0.609 90)
			(size 0.2 0.5)
			(layers "F.Cu" "F.Mask" "F.Paste")
			(net 1011 "/Recovery USB/USBC2_ADDR")
			(pinfunction "ADDR")
			(pintype "passive")
		)
		(pad "23" smd rect
			(at 1.196 -1.01 90)
			(size 0.2 0.5)
			(layers "F.Cu" "F.Mask" "F.Paste")
			(net 1366 "/Recovery USB/~{USBC2_INT_R}")
			(pinfunction "INT_N/OUT3")
			(pintype "passive")
		)
		(pad "24" smd rect
			(at 1.196 -1.41 90)
			(size 0.2 0.5)
			(layers "F.Cu" "F.Mask" "F.Paste")
			(net 1014 "/Recovery USB/USBC2_FAULT_N")
			(pinfunction "VCONN_FAULT_N")
			(pintype "passive")
		)
		(pad "25" smd rect
			(at 1.222 -1.809 90)
			(size 0.2 0.45)
			(layers "F.Cu" "F.Mask" "F.Paste")
			(net 1024 "/Recovery USB/USBC2_I2C_SDA")
			(pinfunction "SDA/OUT1")
			(pintype "passive")
		)
		(pad "26" smd rect
			(at 0.797 -2.21)
			(size 0.2 0.45)
			(layers "F.Cu" "F.Mask" "F.Paste")
			(net 1025 "/Recovery USB/USBC2_I2C_SCL")
			(pinfunction "SCL/OUT2")
			(pintype "passive")
		)
		(pad "27" smd rect
			(at 0.396 -2.21)
			(size 0.2 0.5)
			(layers "F.Cu" "F.Mask" "F.Paste")
			(net 889 "/Recovery USB/USBC2_ID")
			(pinfunction "ID")
			(pintype "passive")
		)
		(pad "28" smd rect
			(at -0.003 -2.21)
			(size 0.2 0.5)
			(layers "F.Cu" "F.Mask" "F.Paste")
			(net 1 "GND")
			(pinfunction "GND")
			(pintype "passive")
		)
		(pad "29" smd rect
			(at -0.403 -2.21)
			(size 0.2 0.5)
			(layers "F.Cu" "F.Mask" "F.Paste")
			(net 1022 "/Recovery USB/~{USBC2_EN_CC}")
			(pinfunction "ENn_CC")
			(pintype "passive")
		)
		(pad "30" smd rect
			(at -0.804 -2.21)
			(size 0.2 0.45)
			(layers "F.Cu" "F.Mask" "F.Paste")
			(net 5 "+5V")
			(pinfunction "VDD5")
			(pintype "passive")
		)
		(pad "31" smd rect
			(at -0.003 -0.01)
			(size 1.2 3.2)
			(layers "F.Cu" "F.Mask" "F.Paste")
			(net 1 "GND")
			(pinfunction "GND")
			(pintype "passive")
		)
	)
	(footprint "antmicro-footprints:TP_SMD_0.75mm"
		(layer "F.Cu")
		(at 173 57.15 90)
		(property "Reference" "TP9"
			(at -1.49 -0.65875 90)
			(layer "F.SilkS")
			(hide yes)
			(effects
				(font
					(size 0.7 0.7)
					(thickness 0.15)
				)
				(justify left bottom)
			)
		)
		(property "Value" "TP_0.75mm_SMD"
			(at 0 1.2 90)
			(layer "F.Fab")
			(effects
				(font
					(size 0.7 0.7)
					(thickness 0.15)
				)
				(justify left bottom)
			)
		)
		(property "Description" "SMT test point"
			(at 0 0 90)
			(layer "F.Fab")
			(hide yes)
			(effects
				(font
					(size 1.27 1.27)
					(thickness 0.15)
				)
			)
		)
		(property "MPN" ""
			(at 0 0 90)
			(unlocked yes)
			(layer "F.Fab")
			(hide yes)
			(effects
				(font
					(size 1 1)
					(thickness 0.15)
				)
			)
		)
		(property "Manufacturer" ""
			(at 0 0 90)
			(unlocked yes)
			(layer "F.Fab")
			(hide yes)
			(effects
				(font
					(size 1 1)
					(thickness 0.15)
				)
			)
		)
		(property "Author" "Antmicro"
			(at 0 0 90)
			(unlocked yes)
			(layer "F.Fab")
			(hide yes)
			(effects
				(font
					(size 1 1)
					(thickness 0.15)
				)
			)
		)
		(property "License" "Apache-2.0"
			(at 0 0 90)
			(unlocked yes)
			(layer "F.Fab")
			(hide yes)
			(effects
				(font
					(size 1 1)
					(thickness 0.15)
				)
			)
		)
		(sheetname "/Power/")
		(sheetfile "power.kicad_sch")
		(attr exclude_from_pos_files exclude_from_bom)
		(fp_circle
			(center 0 0)
			(end 0.475 0)
			(stroke
				(width 0.05)
				(type default)
			)
			(fill no)
			(layer "F.CrtYd")
		)
		(fp_text user "Author: Antmicro"
			(at -0.4 3.901 90)
			(layer "F.Fab")
			(effects
				(font
					(size 0.7 0.7)
					(thickness 0.15)
				)
				(justify left bottom)
			)
		)
		(fp_text user "${REFERENCE}"
			(at -0.4 2.7 90)
			(layer "F.Fab")
			(effects
				(font
					(size 0.7 0.7)
					(thickness 0.15)
				)
				(justify left bottom)
			)
		)
		(fp_text user "License: Apache-2.0"
			(at -0.4 5.101 90)
			(layer "F.Fab")
			(effects
				(font
					(size 0.7 0.7)
					(thickness 0.15)
				)
				(justify left bottom)
			)
		)
		(pad "1" smd circle
			(at 0 0 90)
			(size 0.75 0.75)
			(layers "F.Cu" "F.Mask")
			(net 491 "+5V_AON")
			(pinfunction "1")
			(pintype "passive")
		)
	)
	(footprint "antmicro-footprints:VQFN-100-1EP_12x12x0.85mm_P0.4mm"
		(layer "F.Cu")
		(at 205.353 125.699 180)
		(property "Reference" "U21"
			(at 6.653 6.699 180)
			(layer "F.SilkS")
			(effects
				(font
					(size 0.7 0.7)
					(thickness 0.15)
				)
				(justify left bottom)
			)
		)
		(property "Value" "USB7252C"
			(at 0 7.6 0)
			(layer "F.Fab")
			(effects
				(font
					(size 0.7 0.7)
					(thickness 0.15)
				)
				(justify right top)
			)
		)
		(property "Datasheet" "https://ww1.microchip.com/downloads/en/DeviceDoc/00003852A.pdf"
			(at 0 0 0)
			(layer "F.Fab")
			(hide yes)
			(effects
				(font
					(size 1.27 1.27)
					(thickness 0.15)
				)
			)
		)
		(property "Description" "4-Port USB 3.2 Hub, 2x Type-C with Power Delivery support, 1x USB 3.2, 1x USB 2.0"
			(at 0 0 0)
			(layer "F.Fab")
			(hide yes)
			(effects
				(font
					(size 1.27 1.27)
					(thickness 0.15)
				)
			)
		)
		(property "MPN" "USB7252CT-I/KDX "
			(at 0 0 180)
			(unlocked yes)
			(layer "F.Fab")
			(hide yes)
			(effects
				(font
					(size 1 1)
					(thickness 0.15)
				)
			)
		)
		(property "Manufacturer" "Microchip Technology"
			(at 0 0 180)
			(unlocked yes)
			(layer "F.Fab")
			(hide yes)
			(effects
				(font
					(size 1 1)
					(thickness 0.15)
				)
			)
		)
		(property "Author" "Antmicro"
			(at 0 0 180)
			(unlocked yes)
			(layer "F.Fab")
			(hide yes)
			(effects
				(font
					(size 1 1)
					(thickness 0.15)
				)
			)
		)
		(property "License" "Apache-2.0"
			(at 0 0 180)
			(unlocked yes)
			(layer "F.Fab")
			(hide yes)
			(effects
				(font
					(size 1 1)
					(thickness 0.15)
				)
			)
		)
		(sheetname "/USB Hub/")
		(sheetfile "usb_hub.kicad_sch")
		(attr smd)
		(fp_line
			(start 6.121 6.121)
			(end 6.121 5.233)
			(stroke
				(width 0.15)
				(type solid)
			)
			(layer "F.SilkS")
		)
		(fp_line
			(start 6.121 -5.236)
			(end 6.121 -6.122)
			(stroke
				(width 0.15)
				(type solid)
			)
			(layer "F.SilkS")
		)
		(fp_line
			(start 6.121 -6.122)
			(end 5.233 -6.122)
			(stroke
				(width 0.15)
				(type solid)
			)
			(layer "F.SilkS")
		)
		(fp_line
			(start 5.233 6.121)
			(end 6.121 6.121)
			(stroke
				(width 0.15)
				(type solid)
			)
			(layer "F.SilkS")
		)
		(fp_line
			(start -5.236 -6.122)
			(end -6.122 -6.122)
			(stroke
				(width 0.15)
				(type solid)
			)
			(layer "F.SilkS")
		)
		(fp_line
			(start -6.122 6.121)
			(end -5.236 6.121)
			(stroke
				(width 0.15)
				(type solid)
			)
			(layer "F.SilkS")
		)
		(fp_line
			(start -6.122 5.233)
			(end -6.122 6.121)
			(stroke
				(width 0.15)
				(type solid)
			)
			(layer "F.SilkS")
		)
		(fp_line
			(start -6.122 -6.122)
			(end -6.122 -5.236)
			(stroke
				(width 0.15)
				(type solid)
			)
			(layer "F.SilkS")
		)
		(fp_circle
			(center -6.4 -5.1)
			(end -6.35 -5.05)
			(stroke
				(width 0.15)
				(type solid)
			)
			(fill yes)
			(layer "F.SilkS")
		)
		(fp_rect
			(start 1.6 1.6)
			(end 3.4 3.4)
			(stroke
				(width 0.12)
				(type solid)
			)
			(fill yes)
			(layer "F.Paste")
		)
		(fp_rect
			(start 1.6 -3.351)
			(end 3.4 -1.551)
			(stroke
				(width 0.12)
				(type solid)
			)
			(fill yes)
			(layer "F.Paste")
		)
		(fp_rect
			(start -0.9 -0.9)
			(end 0.9 0.9)
			(stroke
				(width 0.12)
				(type solid)
			)
			(fill yes)
			(layer "F.Paste")
		)
		(fp_rect
			(start -3.4 1.6)
			(end -1.6 3.4)
			(stroke
				(width 0.12)
				(type solid)
			)
			(fill yes)
			(layer "F.Paste")
		)
		(fp_rect
			(start -3.4 -3.4)
			(end -1.6 -1.6)
			(stroke
				(width 0.12)
				(type solid)
			)
			(fill yes)
			(layer "F.Paste")
		)
		(fp_rect
			(start -6.55 -6.55)
			(end 6.55 6.55)
			(stroke
				(width 0.05)
				(type solid)
			)
			(fill no)
			(layer "F.CrtYd")
		)
		(fp_line
			(start 5.993 5.993)
			(end 5.993 5.993)
			(stroke
				(width 0.15)
				(type solid)
			)
			(layer "F.Fab")
		)
		(fp_line
			(start 5.993 5.993)
			(end 5.993 -5.995)
			(stroke
				(width 0.15)
				(type solid)
			)
			(layer "F.Fab")
		)
		(fp_line
			(start 5.993 4.926)
			(end 5.993 4.926)
			(stroke
				(width 0.15)
				(type solid)
			)
			(layer "F.Fab")
		)
		(fp_line
			(start 5.993 4.926)
			(end 5.993 4.671)
			(stroke
				(width 0.15)
				(type solid)
			)
			(layer "F.Fab")
		)
		(fp_line
			(start 5.993 4.671)
			(end 5.993 4.926)
			(stroke
				(width 0.15)
				(type solid)
			)
			(layer "F.Fab")
		)
		(fp_line
			(start 5.993 4.671)
			(end 5.993 4.671)
			(stroke
				(width 0.15)
				(type solid)
			)
			(layer "F.Fab")
		)
		(fp_line
			(start 5.993 4.527)
			(end 5.993 4.527)
			(stroke
				(width 0.15)
				(type solid)
			)
			(layer "F.Fab")
		)
		(fp_line
			(start 5.993 4.527)
			(end 5.993 4.272)
			(stroke
				(width 0.15)
				(type solid)
			)
			(layer "F.Fab")
		)
		(fp_line
			(start 5.993 4.272)
			(end 5.993 4.527)
			(stroke
				(width 0.15)
				(type solid)
			)
			(layer "F.Fab")
		)
		(fp_line
			(start 5.993 4.272)
			(end 5.993 4.272)
			(stroke
				(width 0.15)
				(type solid)
			)
			(layer "F.Fab")
		)
		(fp_line
			(start 5.993 4.126)
			(end 5.993 4.126)
			(stroke
				(width 0.15)
				(type solid)
			)
			(layer "F.Fab")
		)
		(fp_line
			(start 5.993 4.126)
			(end 5.993 3.873)
			(stroke
				(width 0.15)
				(type solid)
			)
			(layer "F.Fab")
		)
		(fp_line
			(start 5.993 3.873)
			(end 5.993 4.126)
			(stroke
				(width 0.15)
				(type solid)
			)
			(layer "F.Fab")
		)
		(fp_line
			(start 5.993 3.873)
			(end 5.993 3.873)
			(stroke
				(width 0.15)
				(type solid)
			)
			(layer "F.Fab")
		)
		(fp_line
			(start 5.993 3.725)
			(end 5.993 3.725)
			(stroke
				(width 0.15)
				(type solid)
			)
			(layer "F.Fab")
		)
		(fp_line
			(start 5.993 3.725)
			(end 5.993 3.471)
			(stroke
				(width 0.15)
				(type solid)
			)
			(layer "F.Fab")
		)
		(fp_line
			(start 5.993 3.471)
			(end 5.993 3.725)
			(stroke
				(width 0.15)
				(type solid)
			)
			(layer "F.Fab")
		)
		(fp_line
			(start 5.993 3.471)
			(end 5.993 3.471)
			(stroke
				(width 0.15)
				(type solid)
			)
			(layer "F.Fab")
		)
		(fp_line
			(start 5.993 3.325)
			(end 5.993 3.325)
			(stroke
				(width 0.15)
				(type solid)
			)
			(layer "F.Fab")
		)
		(fp_line
			(start 5.993 3.325)
			(end 5.993 3.072)
			(stroke
				(width 0.15)
				(type solid)
			)
			(layer "F.Fab")
		)
		(fp_line
			(start 5.993 3.072)
			(end 5.993 3.325)
			(stroke
				(width 0.15)
				(type solid)
			)
			(layer "F.Fab")
		)
		(fp_line
			(start 5.993 3.072)
			(end 5.993 3.072)
			(stroke
				(width 0.15)
				(type solid)
			)
			(layer "F.Fab")
		)
		(fp_line
			(start 5.993 2.926)
			(end 5.993 2.926)
			(stroke
				(width 0.15)
				(type solid)
			)
			(layer "F.Fab")
		)
		(fp_line
			(start 5.993 2.926)
			(end 5.993 2.672)
			(stroke
				(width 0.15)
				(type solid)
			)
			(layer "F.Fab")
		)
		(fp_line
			(start 5.993 2.672)
			(end 5.993 2.926)
			(stroke
				(width 0.15)
				(type solid)
			)
			(layer "F.Fab")
		)
		(fp_line
			(start 5.993 2.672)
			(end 5.993 2.672)
			(stroke
				(width 0.15)
				(type solid)
			)
			(layer "F.Fab")
		)
		(fp_line
			(start 5.993 2.527)
			(end 5.993 2.527)
			(stroke
				(width 0.15)
				(type solid)
			)
			(layer "F.Fab")
		)
		(fp_line
			(start 5.993 2.527)
			(end 5.993 2.273)
			(stroke
				(width 0.15)
				(type solid)
			)
			(layer "F.Fab")
		)
		(fp_line
			(start 5.993 2.273)
			(end 5.993 2.527)
			(stroke
				(width 0.15)
				(type solid)
			)
			(layer "F.Fab")
		)
		(fp_line
			(start 5.993 2.273)
			(end 5.993 2.273)
			(stroke
				(width 0.15)
				(type solid)
			)
			(layer "F.Fab")
		)
		(fp_line
			(start 5.993 2.125)
			(end 5.993 2.125)
			(stroke
				(width 0.15)
				(type solid)
			)
			(layer "F.Fab")
		)
		(fp_line
			(start 5.993 2.125)
			(end 5.993 1.872)
			(stroke
				(width 0.15)
				(type solid)
			)
			(layer "F.Fab")
		)
		(fp_line
			(start 5.993 1.872)
			(end 5.993 2.125)
			(stroke
				(width 0.15)
				(type solid)
			)
			(layer "F.Fab")
		)
		(fp_line
			(start 5.993 1.872)
			(end 5.993 1.872)
			(stroke
				(width 0.15)
				(type solid)
			)
			(layer "F.Fab")
		)
		(fp_line
			(start 5.993 1.727)
			(end 5.993 1.727)
			(stroke
				(width 0.15)
				(type solid)
			)
			(layer "F.Fab")
		)
		(fp_line
			(start 5.993 1.727)
			(end 5.993 1.473)
			(stroke
				(width 0.15)
				(type solid)
			)
			(layer "F.Fab")
		)
		(fp_line
			(start 5.993 1.473)
			(end 5.993 1.727)
			(stroke
				(width 0.15)
				(type solid)
			)
			(layer "F.Fab")
		)
		(fp_line
			(start 5.993 1.473)
			(end 5.993 1.473)
			(stroke
				(width 0.15)
				(type solid)
			)
			(layer "F.Fab")
		)
		(fp_line
			(start 5.993 1.326)
			(end 5.993 1.326)
			(stroke
				(width 0.15)
				(type solid)
			)
			(layer "F.Fab")
		)
		(fp_line
			(start 5.993 1.326)
			(end 5.993 1.072)
			(stroke
				(width 0.15)
				(type solid)
			)
			(layer "F.Fab")
		)
		(fp_line
			(start 5.993 1.072)
			(end 5.993 1.326)
			(stroke
				(width 0.15)
				(type solid)
			)
			(layer "F.Fab")
		)
		(fp_line
			(start 5.993 1.072)
			(end 5.993 1.072)
			(stroke
				(width 0.15)
				(type solid)
			)
			(layer "F.Fab")
		)
		(fp_line
			(start 5.993 0.927)
			(end 5.993 0.927)
			(stroke
				(width 0.15)
				(type solid)
			)
			(layer "F.Fab")
		)
		(fp_line
			(start 5.993 0.927)
			(end 5.993 0.673)
			(stroke
				(width 0.15)
				(type solid)
			)
			(layer "F.Fab")
		)
		(fp_line
			(start 5.993 0.673)
			(end 5.993 0.927)
			(stroke
				(width 0.15)
				(type solid)
			)
			(layer "F.Fab")
		)
		(fp_line
			(start 5.993 0.673)
			(end 5.993 0.673)
			(stroke
				(width 0.15)
				(type solid)
			)
			(layer "F.Fab")
		)
		(fp_line
			(start 5.993 0.527)
			(end 5.993 0.527)
			(stroke
				(width 0.15)
				(type solid)
			)
			(layer "F.Fab")
		)
		(fp_line
			(start 5.993 0.527)
			(end 5.993 0.273)
			(stroke
				(width 0.15)
				(type solid)
			)
			(layer "F.Fab")
		)
		(fp_line
			(start 5.993 0.273)
			(end 5.993 0.527)
			(stroke
				(width 0.15)
				(type solid)
			)
			(layer "F.Fab")
		)
		(fp_line
			(start 5.993 0.273)
			(end 5.993 0.273)
			(stroke
				(width 0.15)
				(type solid)
			)
			(layer "F.Fab")
		)
		(fp_line
			(start 5.993 0.125)
			(end 5.993 0.125)
			(stroke
				(width 0.15)
				(type solid)
			)
			(layer "F.Fab")
		)
		(fp_line
			(start 5.993 0.125)
			(end 5.993 -0.127)
			(stroke
				(width 0.15)
				(type solid)
			)
			(layer "F.Fab")
		)
		(fp_line
			(start 5.993 -0.127)
			(end 5.993 0.125)
			(stroke
				(width 0.15)
				(type solid)
			)
			(layer "F.Fab")
		)
		(fp_line
			(start 5.993 -0.127)
			(end 5.993 -0.127)
			(stroke
				(width 0.15)
				(type solid)
			)
			(layer "F.Fab")
		)
		(fp_line
			(start 5.993 -0.275)
			(end 5.993 -0.275)
			(stroke
				(width 0.15)
				(type solid)
			)
			(layer "F.Fab")
		)
		(fp_line
			(start 5.993 -0.275)
			(end 5.993 -0.529)
			(stroke
				(width 0.15)
				(type solid)
			)
			(layer "F.Fab")
		)
		(fp_line
			(start 5.993 -0.529)
			(end 5.993 -0.275)
			(stroke
				(width 0.15)
				(type solid)
			)
			(layer "F.Fab")
		)
		(fp_line
			(start 5.993 -0.529)
			(end 5.993 -0.529)
			(stroke
				(width 0.15)
				(type solid)
			)
			(layer "F.Fab")
		)
		(fp_line
			(start 5.993 -0.675)
			(end 5.993 -0.675)
			(stroke
				(width 0.15)
				(type solid)
			)
			(layer "F.Fab")
		)
		(fp_line
			(start 5.993 -0.675)
			(end 5.993 -0.929)
			(stroke
				(width 0.15)
				(type solid)
			)
			(layer "F.Fab")
		)
		(fp_line
			(start 5.993 -0.929)
			(end 5.993 -0.675)
			(stroke
				(width 0.15)
				(type solid)
			)
			(layer "F.Fab")
		)
		(fp_line
			(start 5.993 -0.929)
			(end 5.993 -0.929)
			(stroke
				(width 0.15)
				(type solid)
			)
			(layer "F.Fab")
		)
		(fp_line
			(start 5.993 -1.073)
			(end 5.993 -1.073)
			(stroke
				(width 0.15)
				(type solid)
			)
			(layer "F.Fab")
		)
		(fp_line
			(start 5.993 -1.073)
			(end 5.993 -1.327)
			(stroke
				(width 0.15)
				(type solid)
			)
			(layer "F.Fab")
		)
		(fp_line
			(start 5.993 -1.327)
			(end 5.993 -1.073)
			(stroke
				(width 0.15)
				(type solid)
			)
			(layer "F.Fab")
		)
		(fp_line
			(start 5.993 -1.327)
			(end 5.993 -1.327)
			(stroke
				(width 0.15)
				(type solid)
			)
			(layer "F.Fab")
		)
		(fp_line
			(start 5.993 -1.474)
			(end 5.993 -1.474)
			(stroke
				(width 0.15)
				(type solid)
			)
			(layer "F.Fab")
		)
		(fp_line
			(start 5.993 -1.474)
			(end 5.993 -1.728)
			(stroke
				(width 0.15)
				(type solid)
			)
			(layer "F.Fab")
		)
		(fp_line
			(start 5.993 -1.728)
			(end 5.993 -1.474)
			(stroke
				(width 0.15)
				(type solid)
			)
			(layer "F.Fab")
		)
		(fp_line
			(start 5.993 -1.728)
			(end 5.993 -1.728)
			(stroke
				(width 0.15)
				(type solid)
			)
			(layer "F.Fab")
		)
		(fp_line
			(start 5.993 -1.873)
			(end 5.993 -1.873)
			(stroke
				(width 0.15)
				(type solid)
			)
			(layer "F.Fab")
		)
		(fp_line
			(start 5.993 -1.873)
			(end 5.993 -2.128)
			(stroke
				(width 0.15)
				(type solid)
			)
			(layer "F.Fab")
		)
		(fp_line
			(start 5.993 -2.128)
			(end 5.993 -1.873)
			(stroke
				(width 0.15)
				(type solid)
			)
			(layer "F.Fab")
		)
		(fp_line
			(start 5.993 -2.128)
			(end 5.993 -2.128)
			(stroke
				(width 0.15)
				(type solid)
			)
			(layer "F.Fab")
		)
		(fp_line
			(start 5.993 -2.274)
			(end 5.993 -2.274)
			(stroke
				(width 0.15)
				(type solid)
			)
			(layer "F.Fab")
		)
		(fp_line
			(start 5.993 -2.274)
			(end 5.993 -2.528)
			(stroke
				(width 0.15)
				(type solid)
			)
			(layer "F.Fab")
		)
		(fp_line
			(start 5.993 -2.528)
			(end 5.993 -2.274)
			(stroke
				(width 0.15)
				(type solid)
			)
			(layer "F.Fab")
		)
		(fp_line
			(start 5.993 -2.528)
			(end 5.993 -2.528)
			(stroke
				(width 0.15)
				(type solid)
			)
			(layer "F.Fab")
		)
		(fp_line
			(start 5.993 -2.673)
			(end 5.993 -2.673)
			(stroke
				(width 0.15)
				(type solid)
			)
			(layer "F.Fab")
		)
		(fp_line
			(start 5.993 -2.673)
			(end 5.993 -2.927)
			(stroke
				(width 0.15)
				(type solid)
			)
			(layer "F.Fab")
		)
		(fp_line
			(start 5.993 -2.927)
			(end 5.993 -2.673)
			(stroke
				(width 0.15)
				(type solid)
			)
			(layer "F.Fab")
		)
		(fp_line
			(start 5.993 -2.927)
			(end 5.993 -2.927)
			(stroke
				(width 0.15)
				(type solid)
			)
			(layer "F.Fab")
		)
		(fp_line
			(start 5.993 -3.073)
			(end 5.993 -3.073)
			(stroke
				(width 0.15)
				(type solid)
			)
			(layer "F.Fab")
		)
		(fp_line
			(start 5.993 -3.073)
			(end 5.993 -3.327)
			(stroke
				(width 0.15)
				(type solid)
			)
			(layer "F.Fab")
		)
		(fp_line
			(start 5.993 -3.327)
			(end 5.993 -3.073)
			(stroke
				(width 0.15)
				(type solid)
			)
			(layer "F.Fab")
		)
		(fp_line
			(start 5.993 -3.327)
			(end 5.993 -3.327)
			(stroke
				(width 0.15)
				(type solid)
			)
			(layer "F.Fab")
		)
		(fp_line
			(start 5.993 -3.473)
			(end 5.993 -3.473)
			(stroke
				(width 0.15)
				(type solid)
			)
			(layer "F.Fab")
		)
		(fp_line
			(start 5.993 -3.473)
			(end 5.993 -3.727)
			(stroke
				(width 0.15)
				(type solid)
			)
			(layer "F.Fab")
		)
		(fp_line
			(start 5.993 -3.727)
			(end 5.993 -3.473)
			(stroke
				(width 0.15)
				(type solid)
			)
			(layer "F.Fab")
		)
		(fp_line
			(start 5.993 -3.727)
			(end 5.993 -3.727)
			(stroke
				(width 0.15)
				(type solid)
			)
			(layer "F.Fab")
		)
		(fp_line
			(start 5.993 -3.874)
			(end 5.993 -3.874)
			(stroke
				(width 0.15)
				(type solid)
			)
			(layer "F.Fab")
		)
		(fp_line
			(start 5.993 -3.874)
			(end 5.993 -4.127)
			(stroke
				(width 0.15)
				(type solid)
			)
			(layer "F.Fab")
		)
		(fp_line
			(start 5.993 -4.127)
			(end 5.993 -3.874)
			(stroke
				(width 0.15)
				(type solid)
			)
			(layer "F.Fab")
		)
		(fp_line
			(start 5.993 -4.127)
			(end 5.993 -4.127)
			(stroke
				(width 0.15)
				(type solid)
			)
			(layer "F.Fab")
		)
		(fp_line
			(start 5.993 -4.273)
			(end 5.993 -4.273)
			(stroke
				(width 0.15)
				(type solid)
			)
			(layer "F.Fab")
		)
		(fp_line
			(start 5.993 -4.273)
			(end 5.993 -4.528)
			(stroke
				(width 0.15)
				(type solid)
			)
			(layer "F.Fab")
		)
		(fp_line
			(start 5.993 -4.528)
			(end 5.993 -4.273)
			(stroke
				(width 0.15)
				(type solid)
			)
			(layer "F.Fab")
		)
		(fp_line
			(start 5.993 -4.528)
			(end 5.993 -4.528)
			(stroke
				(width 0.15)
				(type solid)
			)
			(layer "F.Fab")
		)
		(fp_line
			(start 5.993 -4.673)
			(end 5.993 -4.673)
			(stroke
				(width 0.15)
				(type solid)
			)
			(layer "F.Fab")
		)
		(fp_line
			(start 5.993 -4.673)
			(end 5.993 -4.928)
			(stroke
				(width 0.15)
				(type solid)
			)
			(layer "F.Fab")
		)
		(fp_line
			(start 5.993 -4.928)
			(end 5.993 -4.673)
			(stroke
				(width 0.15)
				(type solid)
			)
			(layer "F.Fab")
		)
		(fp_line
			(start 5.993 -4.928)
			(end 5.993 -4.928)
			(stroke
				(width 0.15)
				(type solid)
			)
			(layer "F.Fab")
		)
		(fp_line
			(start 5.993 -5.995)
			(end 5.993 -5.995)
			(stroke
				(width 0.15)
				(type solid)
			)
			(layer "F.Fab")
		)
		(fp_line
			(start 5.993 -5.995)
			(end -5.995 -5.995)
			(stroke
				(width 0.15)
				(type solid)
			)
			(layer "F.Fab")
		)
		(fp_line
			(start 4.926 5.993)
			(end 4.926 5.993)
			(stroke
				(width 0.15)
				(type solid)
			)
			(layer "F.Fab")
		)
		(fp_line
			(start 4.926 5.993)
			(end 4.671 5.993)
			(stroke
				(width 0.15)
				(type solid)
			)
			(layer "F.Fab")
		)
		(fp_line
			(start 4.926 -5.995)
			(end 4.926 -5.995)
			(stroke
				(width 0.15)
				(type solid)
			)
			(layer "F.Fab")
		)
		(fp_line
			(start 4.926 -5.995)
			(end 4.671 -5.995)
			(stroke
				(width 0.15)
				(type solid)
			)
			(layer "F.Fab")
		)
		(fp_line
			(start 4.671 5.993)
			(end 4.926 5.993)
			(stroke
				(width 0.15)
				(type solid)
			)
			(layer "F.Fab")
		)
		(fp_line
			(start 4.671 5.993)
			(end 4.671 5.993)
			(stroke
				(width 0.15)
				(type solid)
			)
			(layer "F.Fab")
		)
		(fp_line
			(start 4.671 -5.995)
			(end 4.926 -5.995)
			(stroke
				(width 0.15)
				(type solid)
			)
			(layer "F.Fab")
		)
		(fp_line
			(start 4.671 -5.995)
			(end 4.671 -5.995)
			(stroke
				(width 0.15)
				(type solid)
			)
			(layer "F.Fab")
		)
		(fp_line
			(start 4.527 -5.995)
			(end 4.527 -5.995)
			(stroke
				(width 0.15)
				(type solid)
			)
			(layer "F.Fab")
		)
		(fp_line
			(start 4.527 -5.995)
			(end 4.272 -5.995)
			(stroke
				(width 0.15)
				(type solid)
			)
			(layer "F.Fab")
		)
		(fp_line
			(start 4.525 5.993)
			(end 4.525 5.993)
			(stroke
				(width 0.15)
				(type solid)
			)
			(layer "F.Fab")
		)
		(fp_line
			(start 4.525 5.993)
			(end 4.272 5.993)
			(stroke
				(width 0.15)
				(type solid)
			)
			(layer "F.Fab")
		)
		(fp_line
			(start 4.272 5.993)
			(end 4.525 5.993)
			(stroke
				(width 0.15)
				(type solid)
			)
			(layer "F.Fab")
		)
		(fp_line
			(start 4.272 5.993)
			(end 4.272 5.993)
			(stroke
				(width 0.15)
				(type solid)
			)
			(layer "F.Fab")
		)
		(fp_line
			(start 4.272 -5.995)
			(end 4.527 -5.995)
			(stroke
				(width 0.15)
				(type solid)
			)
			(layer "F.Fab")
		)
		(fp_line
			(start 4.272 -5.995)
			(end 4.272 -5.995)
			(stroke
				(width 0.15)
				(type solid)
			)
			(layer "F.Fab")
		)
		(fp_line
			(start 4.126 5.993)
			(end 4.126 5.993)
			(stroke
				(width 0.15)
				(type solid)
			)
			(layer "F.Fab")
		)
		(fp_line
			(start 4.126 5.993)
			(end 3.871 5.993)
			(stroke
				(width 0.15)
				(type solid)
			)
			(layer "F.Fab")
		)
		(fp_line
			(start 4.126 -5.995)
			(end 4.126 -5.995)
			(stroke
				(width 0.15)
				(type solid)
			)
			(layer "F.Fab")
		)
		(fp_line
			(start 4.126 -5.995)
			(end 3.873 -5.995)
			(stroke
				(width 0.15)
				(type solid)
			)
			(layer "F.Fab")
		)
		(fp_line
			(start 3.873 -5.995)
			(end 4.126 -5.995)
			(stroke
				(width 0.15)
				(type solid)
			)
			(layer "F.Fab")
		)
		(fp_line
			(start 3.873 -5.995)
			(end 3.873 -5.995)
			(stroke
				(width 0.15)
				(type solid)
			)
			(layer "F.Fab")
		)
		(fp_line
			(start 3.871 5.993)
			(end 4.126 5.993)
			(stroke
				(width 0.15)
				(type solid)
			)
			(layer "F.Fab")
		)
		(fp_line
			(start 3.871 5.993)
			(end 3.871 5.993)
			(stroke
				(width 0.15)
				(type solid)
			)
			(layer "F.Fab")
		)
		(fp_line
			(start 3.725 5.993)
			(end 3.725 5.993)
			(stroke
				(width 0.15)
				(type solid)
			)
			(layer "F.Fab")
		)
		(fp_line
			(start 3.725 5.993)
			(end 3.471 5.993)
			(stroke
				(width 0.15)
				(type solid)
			)
			(layer "F.Fab")
		)
		(fp_line
			(start 3.725 -5.995)
			(end 3.725 -5.995)
			(stroke
				(width 0.15)
				(type solid)
			)
			(layer "F.Fab")
		)
		(fp_line
			(start 3.725 -5.995)
			(end 3.471 -5.995)
			(stroke
				(width 0.15)
				(type solid)
			)
			(layer "F.Fab")
		)
		(fp_line
			(start 3.471 5.993)
			(end 3.725 5.993)
			(stroke
				(width 0.15)
				(type solid)
			)
			(layer "F.Fab")
		)
		(fp_line
			(start 3.471 5.993)
			(end 3.471 5.993)
			(stroke
				(width 0.15)
				(type solid)
			)
			(layer "F.Fab")
		)
		(fp_line
			(start 3.471 -5.995)
			(end 3.725 -5.995)
			(stroke
				(width 0.15)
				(type solid)
			)
			(layer "F.Fab")
		)
		(fp_line
			(start 3.471 -5.995)
			(end 3.471 -5.995)
			(stroke
				(width 0.15)
				(type solid)
			)
			(layer "F.Fab")
		)
		(fp_line
			(start 3.325 5.993)
			(end 3.325 5.993)
			(stroke
				(width 0.15)
				(type solid)
			)
			(layer "F.Fab")
		)
		(fp_line
			(start 3.325 5.993)
			(end 3.072 5.993)
			(stroke
				(width 0.15)
				(type solid)
			)
			(layer "F.Fab")
		)
		(fp_line
			(start 3.325 -5.995)
			(end 3.325 -5.995)
			(stroke
				(width 0.15)
				(type solid)
			)
			(layer "F.Fab")
		)
		(fp_line
			(start 3.325 -5.995)
			(end 3.072 -5.995)
			(stroke
				(width 0.15)
				(type solid)
			)
			(layer "F.Fab")
		)
		(fp_line
			(start 3.072 5.993)
			(end 3.325 5.993)
			(stroke
				(width 0.15)
				(type solid)
			)
			(layer "F.Fab")
		)
		(fp_line
			(start 3.072 5.993)
			(end 3.072 5.993)
			(stroke
				(width 0.15)
				(type solid)
			)
			(layer "F.Fab")
		)
		(fp_line
			(start 3.072 -5.995)
			(end 3.325 -5.995)
			(stroke
				(width 0.15)
				(type solid)
			)
			(layer "F.Fab")
		)
		(fp_line
			(start 3.072 -5.995)
			(end 3.072 -5.995)
			(stroke
				(width 0.15)
				(type solid)
			)
			(layer "F.Fab")
		)
		(fp_line
			(start 2.926 5.993)
			(end 2.926 5.993)
			(stroke
				(width 0.15)
				(type solid)
			)
			(layer "F.Fab")
		)
		(fp_line
			(start 2.926 5.993)
			(end 2.672 5.993)
			(stroke
				(width 0.15)
				(type solid)
			)
			(layer "F.Fab")
		)
		(fp_line
			(start 2.926 -5.995)
			(end 2.926 -5.995)
			(stroke
				(width 0.15)
				(type solid)
			)
			(layer "F.Fab")
		)
		(fp_line
			(start 2.926 -5.995)
			(end 2.672 -5.995)
			(stroke
				(width 0.15)
				(type solid)
			)
			(layer "F.Fab")
		)
		(fp_line
			(start 2.672 5.993)
			(end 2.926 5.993)
			(stroke
				(width 0.15)
				(type solid)
			)
			(layer "F.Fab")
		)
		(fp_line
			(start 2.672 5.993)
			(end 2.672 5.993)
			(stroke
				(width 0.15)
				(type solid)
			)
			(layer "F.Fab")
		)
		(fp_line
			(start 2.672 -5.995)
			(end 2.926 -5.995)
			(stroke
				(width 0.15)
				(type solid)
			)
			(layer "F.Fab")
		)
		(fp_line
			(start 2.672 -5.995)
			(end 2.672 -5.995)
			(stroke
				(width 0.15)
				(type solid)
			)
			(layer "F.Fab")
		)
		(fp_line
			(start 2.527 5.993)
			(end 2.527 5.993)
			(stroke
				(width 0.15)
				(type solid)
			)
			(layer "F.Fab")
		)
		(fp_line
			(start 2.527 5.993)
			(end 2.273 5.993)
			(stroke
				(width 0.15)
				(type solid)
			)
			(layer "F.Fab")
		)
		(fp_line
			(start 2.527 -5.995)
			(end 2.527 -5.995)
			(stroke
				(width 0.15)
				(type solid)
			)
			(layer "F.Fab")
		)
		(fp_line
			(start 2.527 -5.995)
			(end 2.273 -5.995)
			(stroke
				(width 0.15)
				(type solid)
			)
			(layer "F.Fab")
		)
		(fp_line
			(start 2.273 5.993)
			(end 2.527 5.993)
			(stroke
				(width 0.15)
				(type solid)
			)
			(layer "F.Fab")
		)
		(fp_line
			(start 2.273 5.993)
			(end 2.273 5.993)
			(stroke
				(width 0.15)
				(type solid)
			)
			(layer "F.Fab")
		)
		(fp_line
			(start 2.273 -5.995)
			(end 2.527 -5.995)
			(stroke
				(width 0.15)
				(type solid)
			)
			(layer "F.Fab")
		)
		(fp_line
			(start 2.273 -5.995)
			(end 2.273 -5.995)
			(stroke
				(width 0.15)
				(type solid)
			)
			(layer "F.Fab")
		)
		(fp_line
			(start 2.125 5.993)
			(end 2.125 5.993)
			(stroke
				(width 0.15)
				(type solid)
			)
			(layer "F.Fab")
		)
		(fp_line
			(start 2.125 5.993)
			(end 1.872 5.993)
			(stroke
				(width 0.15)
				(type solid)
			)
			(layer "F.Fab")
		)
		(fp_line
			(start 2.125 -5.995)
			(end 2.125 -5.995)
			(stroke
				(width 0.15)
				(type solid)
			)
			(layer "F.Fab")
		)
		(fp_line
			(start 2.125 -5.995)
			(end 1.872 -5.995)
			(stroke
				(width 0.15)
				(type solid)
			)
			(layer "F.Fab")
		)
		(fp_line
			(start 1.872 5.993)
			(end 2.125 5.993)
			(stroke
				(width 0.15)
				(type solid)
			)
			(layer "F.Fab")
		)
		(fp_line
			(start 1.872 5.993)
			(end 1.872 5.993)
			(stroke
				(width 0.15)
				(type solid)
			)
			(layer "F.Fab")
		)
		(fp_line
			(start 1.872 -5.995)
			(end 2.125 -5.995)
			(stroke
				(width 0.15)
				(type solid)
			)
			(layer "F.Fab")
		)
		(fp_line
			(start 1.872 -5.995)
			(end 1.872 -5.995)
			(stroke
				(width 0.15)
				(type solid)
			)
			(layer "F.Fab")
		)
		(fp_line
			(start 1.727 5.993)
			(end 1.727 5.993)
			(stroke
				(width 0.15)
				(type solid)
			)
			(layer "F.Fab")
		)
		(fp_line
			(start 1.727 5.993)
			(end 1.473 5.993)
			(stroke
				(width 0.15)
				(type solid)
			)
			(layer "F.Fab")
		)
		(fp_line
			(start 1.727 -5.995)
			(end 1.727 -5.995)
			(stroke
				(width 0.15)
				(type solid)
			)
			(layer "F.Fab")
		)
		(fp_line
			(start 1.727 -5.995)
			(end 1.473 -5.995)
			(stroke
				(width 0.15)
				(type solid)
			)
			(layer "F.Fab")
		)
		(fp_line
			(start 1.473 5.993)
			(end 1.727 5.993)
			(stroke
				(width 0.15)
				(type solid)
			)
			(layer "F.Fab")
		)
		(fp_line
			(start 1.473 5.993)
			(end 1.473 5.993)
			(stroke
				(width 0.15)
				(type solid)
			)
			(layer "F.Fab")
		)
		(fp_line
			(start 1.473 -5.995)
			(end 1.727 -5.995)
			(stroke
				(width 0.15)
				(type solid)
			)
			(layer "F.Fab")
		)
		(fp_line
			(start 1.473 -5.995)
			(end 1.473 -5.995)
			(stroke
				(width 0.15)
				(type solid)
			)
			(layer "F.Fab")
		)
		(fp_line
			(start 1.326 5.993)
			(end 1.326 5.993)
			(stroke
				(width 0.15)
				(type solid)
			)
			(layer "F.Fab")
		)
		(fp_line
			(start 1.326 5.993)
			(end 1.072 5.993)
			(stroke
				(width 0.15)
				(type solid)
			)
			(layer "F.Fab")
		)
		(fp_line
			(start 1.326 -5.995)
			(end 1.326 -5.995)
			(stroke
				(width 0.15)
				(type solid)
			)
			(layer "F.Fab")
		)
		(fp_line
			(start 1.326 -5.995)
			(end 1.072 -5.995)
			(stroke
				(width 0.15)
				(type solid)
			)
			(layer "F.Fab")
		)
		(fp_line
			(start 1.072 5.993)
			(end 1.326 5.993)
			(stroke
				(width 0.15)
				(type solid)
			)
			(layer "F.Fab")
		)
		(fp_line
			(start 1.072 5.993)
			(end 1.072 5.993)
			(stroke
				(width 0.15)
				(type solid)
			)
			(layer "F.Fab")
		)
		(fp_line
			(start 1.072 -5.995)
			(end 1.326 -5.995)
			(stroke
				(width 0.15)
				(type solid)
			)
			(layer "F.Fab")
		)
		(fp_line
			(start 1.072 -5.995)
			(end 1.072 -5.995)
			(stroke
				(width 0.15)
				(type solid)
			)
			(layer "F.Fab")
		)
		(fp_line
			(start 0.927 5.993)
			(end 0.927 5.993)
			(stroke
				(width 0.15)
				(type solid)
			)
			(layer "F.Fab")
		)
		(fp_line
			(start 0.927 5.993)
			(end 0.673 5.993)
			(stroke
				(width 0.15)
				(type solid)
			)
			(layer "F.Fab")
		)
		(fp_line
			(start 0.927 -5.995)
			(end 0.927 -5.995)
			(stroke
				(width 0.15)
				(type solid)
			)
			(layer "F.Fab")
		)
		(fp_line
			(start 0.927 -5.995)
			(end 0.673 -5.995)
			(stroke
				(width 0.15)
				(type solid)
			)
			(layer "F.Fab")
		)
		(fp_line
			(start 0.673 5.993)
			(end 0.927 5.993)
			(stroke
				(width 0.15)
				(type solid)
			)
			(layer "F.Fab")
		)
		(fp_line
			(start 0.673 5.993)
			(end 0.673 5.993)
			(stroke
				(width 0.15)
				(type solid)
			)
			(layer "F.Fab")
		)
		(fp_line
			(start 0.673 -5.995)
			(end 0.927 -5.995)
			(stroke
				(width 0.15)
				(type solid)
			)
			(layer "F.Fab")
		)
		(fp_line
			(start 0.673 -5.995)
			(end 0.673 -5.995)
			(stroke
				(width 0.15)
				(type solid)
			)
			(layer "F.Fab")
		)
		(fp_line
			(start 0.527 5.993)
			(end 0.527 5.993)
			(stroke
				(width 0.15)
				(type solid)
			)
			(layer "F.Fab")
		)
		(fp_line
			(start 0.527 5.993)
			(end 0.273 5.993)
			(stroke
				(width 0.15)
				(type solid)
			)
			(layer "F.Fab")
		)
		(fp_line
			(start 0.527 -5.995)
			(end 0.527 -5.995)
			(stroke
				(width 0.15)
				(type solid)
			)
			(layer "F.Fab")
		)
		(fp_line
			(start 0.527 -5.995)
			(end 0.273 -5.995)
			(stroke
				(width 0.15)
				(type solid)
			)
			(layer "F.Fab")
		)
		(fp_line
			(start 0.273 5.993)
			(end 0.527 5.993)
			(stroke
				(width 0.15)
				(type solid)
			)
			(layer "F.Fab")
		)
		(fp_line
			(start 0.273 5.993)
			(end 0.273 5.993)
			(stroke
				(width 0.15)
				(type solid)
			)
			(layer "F.Fab")
		)
		(fp_line
			(start 0.273 -5.995)
			(end 0.527 -5.995)
			(stroke
				(width 0.15)
				(type solid)
			)
			(layer "F.Fab")
		)
		(fp_line
			(start 0.273 -5.995)
			(end 0.273 -5.995)
			(stroke
				(width 0.15)
				(type solid)
			)
			(layer "F.Fab")
		)
		(fp_line
			(start 0.125 5.993)
			(end 0.125 5.993)
			(stroke
				(width 0.15)
				(type solid)
			)
			(layer "F.Fab")
		)
		(fp_line
			(start 0.125 5.993)
			(end -0.127 5.993)
			(stroke
				(width 0.15)
				(type solid)
			)
			(layer "F.Fab")
		)
		(fp_line
			(start 0.125 -5.995)
			(end 0.125 -5.995)
			(stroke
				(width 0.15)
				(type solid)
			)
			(layer "F.Fab")
		)
		(fp_line
			(start 0.125 -5.995)
			(end -0.127 -5.995)
			(stroke
				(width 0.15)
				(type solid)
			)
			(layer "F.Fab")
		)
		(fp_line
			(start -0.127 5.993)
			(end 0.125 5.993)
			(stroke
				(width 0.15)
				(type solid)
			)
			(layer "F.Fab")
		)
		(fp_line
			(start -0.127 5.993)
			(end -0.127 5.993)
			(stroke
				(width 0.15)
				(type solid)
			)
			(layer "F.Fab")
		)
		(fp_line
			(start -0.127 -5.995)
			(end 0.125 -5.995)
			(stroke
				(width 0.15)
				(type solid)
			)
			(layer "F.Fab")
		)
		(fp_line
			(start -0.127 -5.995)
			(end -0.127 -5.995)
			(stroke
				(width 0.15)
				(type solid)
			)
			(layer "F.Fab")
		)
		(fp_line
			(start -0.275 5.993)
			(end -0.275 5.993)
			(stroke
				(width 0.15)
				(type solid)
			)
			(layer "F.Fab")
		)
		(fp_line
			(start -0.275 5.993)
			(end -0.529 5.993)
			(stroke
				(width 0.15)
				(type solid)
			)
			(layer "F.Fab")
		)
		(fp_line
			(start -0.275 -5.995)
			(end -0.275 -5.995)
			(stroke
				(width 0.15)
				(type solid)
			)
			(layer "F.Fab")
		)
		(fp_line
			(start -0.275 -5.995)
			(end -0.529 -5.995)
			(stroke
				(width 0.15)
				(type solid)
			)
			(layer "F.Fab")
		)
		(fp_line
			(start -0.529 5.993)
			(end -0.275 5.993)
			(stroke
				(width 0.15)
				(type solid)
			)
			(layer "F.Fab")
		)
		(fp_line
			(start -0.529 5.993)
			(end -0.529 5.993)
			(stroke
				(width 0.15)
				(type solid)
			)
			(layer "F.Fab")
		)
		(fp_line
			(start -0.529 -5.995)
			(end -0.275 -5.995)
			(stroke
				(width 0.15)
				(type solid)
			)
			(layer "F.Fab")
		)
		(fp_line
			(start -0.529 -5.995)
			(end -0.529 -5.995)
			(stroke
				(width 0.15)
				(type solid)
			)
			(layer "F.Fab")
		)
		(fp_line
			(start -0.675 5.993)
			(end -0.675 5.993)
			(stroke
				(width 0.15)
				(type solid)
			)
			(layer "F.Fab")
		)
		(fp_line
			(start -0.675 5.993)
			(end -0.929 5.993)
			(stroke
				(width 0.15)
				(type solid)
			)
			(layer "F.Fab")
		)
		(fp_line
			(start -0.675 -5.995)
			(end -0.675 -5.995)
			(stroke
				(width 0.15)
				(type solid)
			)
			(layer "F.Fab")
		)
		(fp_line
			(start -0.675 -5.995)
			(end -0.929 -5.995)
			(stroke
				(width 0.15)
				(type solid)
			)
			(layer "F.Fab")
		)
		(fp_line
			(start -0.929 5.993)
			(end -0.675 5.993)
			(stroke
				(width 0.15)
				(type solid)
			)
			(layer "F.Fab")
		)
		(fp_line
			(start -0.929 5.993)
			(end -0.929 5.993)
			(stroke
				(width 0.15)
				(type solid)
			)
			(layer "F.Fab")
		)
		(fp_line
			(start -0.929 -5.995)
			(end -0.675 -5.995)
			(stroke
				(width 0.15)
				(type solid)
			)
			(layer "F.Fab")
		)
		(fp_line
			(start -0.929 -5.995)
			(end -0.929 -5.995)
			(stroke
				(width 0.15)
				(type solid)
			)
			(layer "F.Fab")
		)
		(fp_line
			(start -1.073 5.993)
			(end -1.073 5.993)
			(stroke
				(width 0.15)
				(type solid)
			)
			(layer "F.Fab")
		)
		(fp_line
			(start -1.073 5.993)
			(end -1.327 5.993)
			(stroke
				(width 0.15)
				(type solid)
			)
			(layer "F.Fab")
		)
		(fp_line
			(start -1.073 -5.995)
			(end -1.073 -5.995)
			(stroke
				(width 0.15)
				(type solid)
			)
			(layer "F.Fab")
		)
		(fp_line
			(start -1.073 -5.995)
			(end -1.327 -5.995)
			(stroke
				(width 0.15)
				(type solid)
			)
			(layer "F.Fab")
		)
		(fp_line
			(start -1.327 5.993)
			(end -1.073 5.993)
			(stroke
				(width 0.15)
				(type solid)
			)
			(layer "F.Fab")
		)
		(fp_line
			(start -1.327 5.993)
			(end -1.327 5.993)
			(stroke
				(width 0.15)
				(type solid)
			)
			(layer "F.Fab")
		)
		(fp_line
			(start -1.327 -5.995)
			(end -1.073 -5.995)
			(stroke
				(width 0.15)
				(type solid)
			)
			(layer "F.Fab")
		)
		(fp_line
			(start -1.327 -5.995)
			(end -1.327 -5.995)
			(stroke
				(width 0.15)
				(type solid)
			)
			(layer "F.Fab")
		)
		(fp_line
			(start -1.474 5.993)
			(end -1.474 5.993)
			(stroke
				(width 0.15)
				(type solid)
			)
			(layer "F.Fab")
		)
		(fp_line
			(start -1.474 5.993)
			(end -1.728 5.993)
			(stroke
				(width 0.15)
				(type solid)
			)
			(layer "F.Fab")
		)
		(fp_line
			(start -1.474 -5.995)
			(end -1.474 -5.995)
			(stroke
				(width 0.15)
				(type solid)
			)
			(layer "F.Fab")
		)
		(fp_line
			(start -1.474 -5.995)
			(end -1.728 -5.995)
			(stroke
				(width 0.15)
				(type solid)
			)
			(layer "F.Fab")
		)
		(fp_line
			(start -1.728 5.993)
			(end -1.474 5.993)
			(stroke
				(width 0.15)
				(type solid)
			)
			(layer "F.Fab")
		)
		(fp_line
			(start -1.728 5.993)
			(end -1.728 5.993)
			(stroke
				(width 0.15)
				(type solid)
			)
			(layer "F.Fab")
		)
		(fp_line
			(start -1.728 -5.995)
			(end -1.474 -5.995)
			(stroke
				(width 0.15)
				(type solid)
			)
			(layer "F.Fab")
		)
		(fp_line
			(start -1.728 -5.995)
			(end -1.728 -5.995)
			(stroke
				(width 0.15)
				(type solid)
			)
			(layer "F.Fab")
		)
		(fp_line
			(start -1.873 5.993)
			(end -1.873 5.993)
			(stroke
				(width 0.15)
				(type solid)
			)
			(layer "F.Fab")
		)
		(fp_line
			(start -1.873 5.993)
			(end -2.128 5.993)
			(stroke
				(width 0.15)
				(type solid)
			)
			(layer "F.Fab")
		)
		(fp_line
			(start -1.873 -5.995)
			(end -1.873 -5.995)
			(stroke
				(width 0.15)
				(type solid)
			)
			(layer "F.Fab")
		)
		(fp_line
			(start -1.873 -5.995)
			(end -2.128 -5.995)
			(stroke
				(width 0.15)
				(type solid)
			)
			(layer "F.Fab")
		)
		(fp_line
			(start -2.128 5.993)
			(end -1.873 5.993)
			(stroke
				(width 0.15)
				(type solid)
			)
			(layer "F.Fab")
		)
		(fp_line
			(start -2.128 5.993)
			(end -2.128 5.993)
			(stroke
				(width 0.15)
				(type solid)
			)
			(layer "F.Fab")
		)
		(fp_line
			(start -2.128 -5.995)
			(end -1.873 -5.995)
			(stroke
				(width 0.15)
				(type solid)
			)
			(layer "F.Fab")
		)
		(fp_line
			(start -2.128 -5.995)
			(end -2.128 -5.995)
			(stroke
				(width 0.15)
				(type solid)
			)
			(layer "F.Fab")
		)
		(fp_line
			(start -2.274 5.993)
			(end -2.274 5.993)
			(stroke
				(width 0.15)
				(type solid)
			)
			(layer "F.Fab")
		)
		(fp_line
			(start -2.274 5.993)
			(end -2.528 5.993)
			(stroke
				(width 0.15)
				(type solid)
			)
			(layer "F.Fab")
		)
		(fp_line
			(start -2.274 -5.995)
			(end -2.274 -5.995)
			(stroke
				(width 0.15)
				(type solid)
			)
			(layer "F.Fab")
		)
		(fp_line
			(start -2.274 -5.995)
			(end -2.528 -5.995)
			(stroke
				(width 0.15)
				(type solid)
			)
			(layer "F.Fab")
		)
		(fp_line
			(start -2.528 5.993)
			(end -2.274 5.993)
			(stroke
				(width 0.15)
				(type solid)
			)
			(layer "F.Fab")
		)
		(fp_line
			(start -2.528 5.993)
			(end -2.528 5.993)
			(stroke
				(width 0.15)
				(type solid)
			)
			(layer "F.Fab")
		)
		(fp_line
			(start -2.528 -5.995)
			(end -2.274 -5.995)
			(stroke
				(width 0.15)
				(type solid)
			)
			(layer "F.Fab")
		)
		(fp_line
			(start -2.528 -5.995)
			(end -2.528 -5.995)
			(stroke
				(width 0.15)
				(type solid)
			)
			(layer "F.Fab")
		)
		(fp_line
			(start -2.673 5.993)
			(end -2.673 5.993)
			(stroke
				(width 0.15)
				(type solid)
			)
			(layer "F.Fab")
		)
		(fp_line
			(start -2.673 5.993)
			(end -2.927 5.993)
			(stroke
				(width 0.15)
				(type solid)
			)
			(layer "F.Fab")
		)
		(fp_line
			(start -2.673 -5.995)
			(end -2.673 -5.995)
			(stroke
				(width 0.15)
				(type solid)
			)
			(layer "F.Fab")
		)
		(fp_line
			(start -2.673 -5.995)
			(end -2.927 -5.995)
			(stroke
				(width 0.15)
				(type solid)
			)
			(layer "F.Fab")
		)
		(fp_line
			(start -2.927 5.993)
			(end -2.673 5.993)
			(stroke
				(width 0.15)
				(type solid)
			)
			(layer "F.Fab")
		)
		(fp_line
			(start -2.927 5.993)
			(end -2.927 5.993)
			(stroke
				(width 0.15)
				(type solid)
			)
			(layer "F.Fab")
		)
		(fp_line
			(start -2.927 -5.995)
			(end -2.673 -5.995)
			(stroke
				(width 0.15)
				(type solid)
			)
			(layer "F.Fab")
		)
		(fp_line
			(start -2.927 -5.995)
			(end -2.927 -5.995)
			(stroke
				(width 0.15)
				(type solid)
			)
			(layer "F.Fab")
		)
		(fp_line
			(start -3.073 5.993)
			(end -3.073 5.993)
			(stroke
				(width 0.15)
				(type solid)
			)
			(layer "F.Fab")
		)
		(fp_line
			(start -3.073 5.993)
			(end -3.327 5.993)
			(stroke
				(width 0.15)
				(type solid)
			)
			(layer "F.Fab")
		)
		(fp_line
			(start -3.073 -5.995)
			(end -3.073 -5.995)
			(stroke
				(width 0.15)
				(type solid)
			)
			(layer "F.Fab")
		)
		(fp_line
			(start -3.073 -5.995)
			(end -3.327 -5.995)
			(stroke
				(width 0.15)
				(type solid)
			)
			(layer "F.Fab")
		)
		(fp_line
			(start -3.327 5.993)
			(end -3.073 5.993)
			(stroke
				(width 0.15)
				(type solid)
			)
			(layer "F.Fab")
		)
		(fp_line
			(start -3.327 5.993)
			(end -3.327 5.993)
			(stroke
				(width 0.15)
				(type solid)
			)
			(layer "F.Fab")
		)
		(fp_line
			(start -3.327 -5.995)
			(end -3.073 -5.995)
			(stroke
				(width 0.15)
				(type solid)
			)
			(layer "F.Fab")
		)
		(fp_line
			(start -3.327 -5.995)
			(end -3.327 -5.995)
			(stroke
				(width 0.15)
				(type solid)
			)
			(layer "F.Fab")
		)
		(fp_line
			(start -3.473 5.993)
			(end -3.473 5.993)
			(stroke
				(width 0.15)
				(type solid)
			)
			(layer "F.Fab")
		)
		(fp_line
			(start -3.473 5.993)
			(end -3.727 5.993)
			(stroke
				(width 0.15)
				(type solid)
			)
			(layer "F.Fab")
		)
		(fp_line
			(start -3.473 -5.995)
			(end -3.473 -5.995)
			(stroke
				(width 0.15)
				(type solid)
			)
			(layer "F.Fab")
		)
		(fp_line
			(start -3.473 -5.995)
			(end -3.727 -5.995)
			(stroke
				(width 0.15)
				(type solid)
			)
			(layer "F.Fab")
		)
		(fp_line
			(start -3.727 5.993)
			(end -3.473 5.993)
			(stroke
				(width 0.15)
				(type solid)
			)
			(layer "F.Fab")
		)
		(fp_line
			(start -3.727 5.993)
			(end -3.727 5.993)
			(stroke
				(width 0.15)
				(type solid)
			)
			(layer "F.Fab")
		)
		(fp_line
			(start -3.727 -5.995)
			(end -3.473 -5.995)
			(stroke
				(width 0.15)
				(type solid)
			)
			(layer "F.Fab")
		)
		(fp_line
			(start -3.727 -5.995)
			(end -3.727 -5.995)
			(stroke
				(width 0.15)
				(type solid)
			)
			(layer "F.Fab")
		)
		(fp_line
			(start -3.874 -5.995)
			(end -3.874 -5.995)
			(stroke
				(width 0.15)
				(type solid)
			)
			(layer "F.Fab")
		)
		(fp_line
			(start -3.874 -5.995)
			(end -4.127 -5.995)
			(stroke
				(width 0.15)
				(type solid)
			)
			(layer "F.Fab")
		)
		(fp_line
			(start -3.875 5.993)
			(end -3.875 5.993)
			(stroke
				(width 0.15)
				(type solid)
			)
			(layer "F.Fab")
		)
		(fp_line
			(start -3.875 5.993)
			(end -4.127 5.993)
			(stroke
				(width 0.15)
				(type solid)
			)
			(layer "F.Fab")
		)
		(fp_line
			(start -4.127 5.993)
			(end -3.875 5.993)
			(stroke
				(width 0.15)
				(type solid)
			)
			(layer "F.Fab")
		)
		(fp_line
			(start -4.127 5.993)
			(end -4.127 5.993)
			(stroke
				(width 0.15)
				(type solid)
			)
			(layer "F.Fab")
		)
		(fp_line
			(start -4.127 -5.995)
			(end -3.874 -5.995)
			(stroke
				(width 0.15)
				(type solid)
			)
			(layer "F.Fab")
		)
		(fp_line
			(start -4.127 -5.995)
			(end -4.127 -5.995)
			(stroke
				(width 0.15)
				(type solid)
			)
			(layer "F.Fab")
		)
		(fp_line
			(start -4.273 5.993)
			(end -4.273 5.993)
			(stroke
				(width 0.15)
				(type solid)
			)
			(layer "F.Fab")
		)
		(fp_line
			(start -4.273 5.993)
			(end -4.529 5.993)
			(stroke
				(width 0.15)
				(type solid)
			)
			(layer "F.Fab")
		)
		(fp_line
			(start -4.273 -5.995)
			(end -4.273 -5.995)
			(stroke
				(width 0.15)
				(type solid)
			)
			(layer "F.Fab")
		)
		(fp_line
			(start -4.273 -5.995)
			(end -4.528 -5.995)
			(stroke
				(width 0.15)
				(type solid)
			)
			(layer "F.Fab")
		)
		(fp_line
			(start -4.528 -5.995)
			(end -4.273 -5.995)
			(stroke
				(width 0.15)
				(type solid)
			)
			(layer "F.Fab")
		)
		(fp_line
			(start -4.528 -5.995)
			(end -4.528 -5.995)
			(stroke
				(width 0.15)
				(type solid)
			)
			(layer "F.Fab")
		)
		(fp_line
			(start -4.529 5.993)
			(end -4.273 5.993)
			(stroke
				(width 0.15)
				(type solid)
			)
			(layer "F.Fab")
		)
		(fp_line
			(start -4.529 5.993)
			(end -4.529 5.993)
			(stroke
				(width 0.15)
				(type solid)
			)
			(layer "F.Fab")
		)
		(fp_line
			(start -4.673 5.993)
			(end -4.673 5.993)
			(stroke
				(width 0.15)
				(type solid)
			)
			(layer "F.Fab")
		)
		(fp_line
			(start -4.673 5.993)
			(end -4.928 5.993)
			(stroke
				(width 0.15)
				(type solid)
			)
			(layer "F.Fab")
		)
		(fp_line
			(start -4.673 -5.995)
			(end -4.673 -5.995)
			(stroke
				(width 0.15)
				(type solid)
			)
			(layer "F.Fab")
		)
		(fp_line
			(start -4.673 -5.995)
			(end -4.928 -5.995)
			(stroke
				(width 0.15)
				(type solid)
			)
			(layer "F.Fab")
		)
		(fp_line
			(start -4.928 5.993)
			(end -4.673 5.993)
			(stroke
				(width 0.15)
				(type solid)
			)
			(layer "F.Fab")
		)
		(fp_line
			(start -4.928 5.993)
			(end -4.928 5.993)
			(stroke
				(width 0.15)
				(type solid)
			)
			(layer "F.Fab")
		)
		(fp_line
			(start -4.928 -5.995)
			(end -4.673 -5.995)
			(stroke
				(width 0.15)
				(type solid)
			)
			(layer "F.Fab")
		)
		(fp_line
			(start -4.928 -5.995)
			(end -4.928 -5.995)
			(stroke
				(width 0.15)
				(type solid)
			)
			(layer "F.Fab")
		)
		(fp_line
			(start -5.995 5.993)
			(end 5.993 5.993)
			(stroke
				(width 0.15)
				(type solid)
			)
			(layer "F.Fab")
		)
		(fp_line
			(start -5.995 5.993)
			(end -5.995 5.993)
			(stroke
				(width 0.15)
				(type solid)
			)
			(layer "F.Fab")
		)
		(fp_line
			(start -5.995 4.926)
			(end -5.995 4.926)
			(stroke
				(width 0.15)
				(type solid)
			)
			(layer "F.Fab")
		)
		(fp_line
			(start -5.995 4.926)
			(end -5.995 4.671)
			(stroke
				(width 0.15)
				(type solid)
			)
			(layer "F.Fab")
		)
		(fp_line
			(start -5.995 4.671)
			(end -5.995 4.926)
			(stroke
				(width 0.15)
				(type solid)
			)
			(layer "F.Fab")
		)
		(fp_line
			(start -5.995 4.671)
			(end -5.995 4.671)
			(stroke
				(width 0.15)
				(type solid)
			)
			(layer "F.Fab")
		)
		(fp_line
			(start -5.995 4.525)
			(end -5.995 4.525)
			(stroke
				(width 0.15)
				(type solid)
			)
			(layer "F.Fab")
		)
		(fp_line
			(start -5.995 4.525)
			(end -5.995 4.272)
			(stroke
				(width 0.15)
				(type solid)
			)
			(layer "F.Fab")
		)
		(fp_line
			(start -5.995 4.272)
			(end -5.995 4.525)
			(stroke
				(width 0.15)
				(type solid)
			)
			(layer "F.Fab")
		)
		(fp_line
			(start -5.995 4.272)
			(end -5.995 4.272)
			(stroke
				(width 0.15)
				(type solid)
			)
			(layer "F.Fab")
		)
		(fp_line
			(start -5.995 4.126)
			(end -5.995 4.126)
			(stroke
				(width 0.15)
				(type solid)
			)
			(layer "F.Fab")
		)
		(fp_line
			(start -5.995 4.126)
			(end -5.995 3.871)
			(stroke
				(width 0.15)
				(type solid)
			)
			(layer "F.Fab")
		)
		(fp_line
			(start -5.995 3.871)
			(end -5.995 4.126)
			(stroke
				(width 0.15)
				(type solid)
			)
			(layer "F.Fab")
		)
		(fp_line
			(start -5.995 3.871)
			(end -5.995 3.871)
			(stroke
				(width 0.15)
				(type solid)
			)
			(layer "F.Fab")
		)
		(fp_line
			(start -5.995 3.725)
			(end -5.995 3.725)
			(stroke
				(width 0.15)
				(type solid)
			)
			(layer "F.Fab")
		)
		(fp_line
			(start -5.995 3.725)
			(end -5.995 3.471)
			(stroke
				(width 0.15)
				(type solid)
			)
			(layer "F.Fab")
		)
		(fp_line
			(start -5.995 3.471)
			(end -5.995 3.725)
			(stroke
				(width 0.15)
				(type solid)
			)
			(layer "F.Fab")
		)
		(fp_line
			(start -5.995 3.471)
			(end -5.995 3.471)
			(stroke
				(width 0.15)
				(type solid)
			)
			(layer "F.Fab")
		)
		(fp_line
			(start -5.995 3.325)
			(end -5.995 3.325)
			(stroke
				(width 0.15)
				(type solid)
			)
			(layer "F.Fab")
		)
		(fp_line
			(start -5.995 3.325)
			(end -5.995 3.072)
			(stroke
				(width 0.15)
				(type solid)
			)
			(layer "F.Fab")
		)
		(fp_line
			(start -5.995 3.072)
			(end -5.995 3.325)
			(stroke
				(width 0.15)
				(type solid)
			)
			(layer "F.Fab")
		)
		(fp_line
			(start -5.995 3.072)
			(end -5.995 3.072)
			(stroke
				(width 0.15)
				(type solid)
			)
			(layer "F.Fab")
		)
		(fp_line
			(start -5.995 2.926)
			(end -5.995 2.926)
			(stroke
				(width 0.15)
				(type solid)
			)
			(layer "F.Fab")
		)
		(fp_line
			(start -5.995 2.926)
			(end -5.995 2.672)
			(stroke
				(width 0.15)
				(type solid)
			)
			(layer "F.Fab")
		)
		(fp_line
			(start -5.995 2.672)
			(end -5.995 2.926)
			(stroke
				(width 0.15)
				(type solid)
			)
			(layer "F.Fab")
		)
		(fp_line
			(start -5.995 2.672)
			(end -5.995 2.672)
			(stroke
				(width 0.15)
				(type solid)
			)
			(layer "F.Fab")
		)
		(fp_line
			(start -5.995 2.527)
			(end -5.995 2.527)
			(stroke
				(width 0.15)
				(type solid)
			)
			(layer "F.Fab")
		)
		(fp_line
			(start -5.995 2.527)
			(end -5.995 2.273)
			(stroke
				(width 0.15)
				(type solid)
			)
			(layer "F.Fab")
		)
		(fp_line
			(start -5.995 2.273)
			(end -5.995 2.527)
			(stroke
				(width 0.15)
				(type solid)
			)
			(layer "F.Fab")
		)
		(fp_line
			(start -5.995 2.273)
			(end -5.995 2.273)
			(stroke
				(width 0.15)
				(type solid)
			)
			(layer "F.Fab")
		)
		(fp_line
			(start -5.995 2.125)
			(end -5.995 2.125)
			(stroke
				(width 0.15)
				(type solid)
			)
			(layer "F.Fab")
		)
		(fp_line
			(start -5.995 2.125)
			(end -5.995 1.872)
			(stroke
				(width 0.15)
				(type solid)
			)
			(layer "F.Fab")
		)
		(fp_line
			(start -5.995 1.872)
			(end -5.995 2.125)
			(stroke
				(width 0.15)
				(type solid)
			)
			(layer "F.Fab")
		)
		(fp_line
			(start -5.995 1.872)
			(end -5.995 1.872)
			(stroke
				(width 0.15)
				(type solid)
			)
			(layer "F.Fab")
		)
		(fp_line
			(start -5.995 1.727)
			(end -5.995 1.727)
			(stroke
				(width 0.15)
				(type solid)
			)
			(layer "F.Fab")
		)
		(fp_line
			(start -5.995 1.727)
			(end -5.995 1.473)
			(stroke
				(width 0.15)
				(type solid)
			)
			(layer "F.Fab")
		)
		(fp_line
			(start -5.995 1.473)
			(end -5.995 1.727)
			(stroke
				(width 0.15)
				(type solid)
			)
			(layer "F.Fab")
		)
		(fp_line
			(start -5.995 1.473)
			(end -5.995 1.473)
			(stroke
				(width 0.15)
				(type solid)
			)
			(layer "F.Fab")
		)
		(fp_line
			(start -5.995 1.326)
			(end -5.995 1.326)
			(stroke
				(width 0.15)
				(type solid)
			)
			(layer "F.Fab")
		)
		(fp_line
			(start -5.995 1.326)
			(end -5.995 1.072)
			(stroke
				(width 0.15)
				(type solid)
			)
			(layer "F.Fab")
		)
		(fp_line
			(start -5.995 1.072)
			(end -5.995 1.326)
			(stroke
				(width 0.15)
				(type solid)
			)
			(layer "F.Fab")
		)
		(fp_line
			(start -5.995 1.072)
			(end -5.995 1.072)
			(stroke
				(width 0.15)
				(type solid)
			)
			(layer "F.Fab")
		)
		(fp_line
			(start -5.995 0.927)
			(end -5.995 0.927)
			(stroke
				(width 0.15)
				(type solid)
			)
			(layer "F.Fab")
		)
		(fp_line
			(start -5.995 0.927)
			(end -5.995 0.673)
			(stroke
				(width 0.15)
				(type solid)
			)
			(layer "F.Fab")
		)
		(fp_line
			(start -5.995 0.673)
			(end -5.995 0.927)
			(stroke
				(width 0.15)
				(type solid)
			)
			(layer "F.Fab")
		)
		(fp_line
			(start -5.995 0.673)
			(end -5.995 0.673)
			(stroke
				(width 0.15)
				(type solid)
			)
			(layer "F.Fab")
		)
		(fp_line
			(start -5.995 0.527)
			(end -5.995 0.527)
			(stroke
				(width 0.15)
				(type solid)
			)
			(layer "F.Fab")
		)
		(fp_line
			(start -5.995 0.527)
			(end -5.995 0.273)
			(stroke
				(width 0.15)
				(type solid)
			)
			(layer "F.Fab")
		)
		(fp_line
			(start -5.995 0.273)
			(end -5.995 0.527)
			(stroke
				(width 0.15)
				(type solid)
			)
			(layer "F.Fab")
		)
		(fp_line
			(start -5.995 0.273)
			(end -5.995 0.273)
			(stroke
				(width 0.15)
				(type solid)
			)
			(layer "F.Fab")
		)
		(fp_line
			(start -5.995 0.125)
			(end -5.995 0.125)
			(stroke
				(width 0.15)
				(type solid)
			)
			(layer "F.Fab")
		)
		(fp_line
			(start -5.995 0.125)
			(end -5.995 -0.127)
			(stroke
				(width 0.15)
				(type solid)
			)
			(layer "F.Fab")
		)
		(fp_line
			(start -5.995 -0.127)
			(end -5.995 0.125)
			(stroke
				(width 0.15)
				(type solid)
			)
			(layer "F.Fab")
		)
		(fp_line
			(start -5.995 -0.127)
			(end -5.995 -0.127)
			(stroke
				(width 0.15)
				(type solid)
			)
			(layer "F.Fab")
		)
		(fp_line
			(start -5.995 -0.275)
			(end -5.995 -0.275)
			(stroke
				(width 0.15)
				(type solid)
			)
			(layer "F.Fab")
		)
		(fp_line
			(start -5.995 -0.275)
			(end -5.995 -0.529)
			(stroke
				(width 0.15)
				(type solid)
			)
			(layer "F.Fab")
		)
		(fp_line
			(start -5.995 -0.529)
			(end -5.995 -0.275)
			(stroke
				(width 0.15)
				(type solid)
			)
			(layer "F.Fab")
		)
		(fp_line
			(start -5.995 -0.529)
			(end -5.995 -0.529)
			(stroke
				(width 0.15)
				(type solid)
			)
			(layer "F.Fab")
		)
		(fp_line
			(start -5.995 -0.675)
			(end -5.995 -0.675)
			(stroke
				(width 0.15)
				(type solid)
			)
			(layer "F.Fab")
		)
		(fp_line
			(start -5.995 -0.675)
			(end -5.995 -0.929)
			(stroke
				(width 0.15)
				(type solid)
			)
			(layer "F.Fab")
		)
		(fp_line
			(start -5.995 -0.929)
			(end -5.995 -0.675)
			(stroke
				(width 0.15)
				(type solid)
			)
			(layer "F.Fab")
		)
		(fp_line
			(start -5.995 -0.929)
			(end -5.995 -0.929)
			(stroke
				(width 0.15)
				(type solid)
			)
			(layer "F.Fab")
		)
		(fp_line
			(start -5.995 -1.073)
			(end -5.995 -1.073)
			(stroke
				(width 0.15)
				(type solid)
			)
			(layer "F.Fab")
		)
		(fp_line
			(start -5.995 -1.073)
			(end -5.995 -1.327)
			(stroke
				(width 0.15)
				(type solid)
			)
			(layer "F.Fab")
		)
		(fp_line
			(start -5.995 -1.327)
			(end -5.995 -1.073)
			(stroke
				(width 0.15)
				(type solid)
			)
			(layer "F.Fab")
		)
		(fp_line
			(start -5.995 -1.327)
			(end -5.995 -1.327)
			(stroke
				(width 0.15)
				(type solid)
			)
			(layer "F.Fab")
		)
		(fp_line
			(start -5.995 -1.474)
			(end -5.995 -1.474)
			(stroke
				(width 0.15)
				(type solid)
			)
			(layer "F.Fab")
		)
		(fp_line
			(start -5.995 -1.474)
			(end -5.995 -1.728)
			(stroke
				(width 0.15)
				(type solid)
			)
			(layer "F.Fab")
		)
		(fp_line
			(start -5.995 -1.728)
			(end -5.995 -1.474)
			(stroke
				(width 0.15)
				(type solid)
			)
			(layer "F.Fab")
		)
		(fp_line
			(start -5.995 -1.728)
			(end -5.995 -1.728)
			(stroke
				(width 0.15)
				(type solid)
			)
			(layer "F.Fab")
		)
		(fp_line
			(start -5.995 -1.873)
			(end -5.995 -1.873)
			(stroke
				(width 0.15)
				(type solid)
			)
			(layer "F.Fab")
		)
		(fp_line
			(start -5.995 -1.873)
			(end -5.995 -2.128)
			(stroke
				(width 0.15)
				(type solid)
			)
			(layer "F.Fab")
		)
		(fp_line
			(start -5.995 -2.128)
			(end -5.995 -1.873)
			(stroke
				(width 0.15)
				(type solid)
			)
			(layer "F.Fab")
		)
		(fp_line
			(start -5.995 -2.128)
			(end -5.995 -2.128)
			(stroke
				(width 0.15)
				(type solid)
			)
			(layer "F.Fab")
		)
		(fp_line
			(start -5.995 -2.274)
			(end -5.995 -2.274)
			(stroke
				(width 0.15)
				(type solid)
			)
			(layer "F.Fab")
		)
		(fp_line
			(start -5.995 -2.274)
			(end -5.995 -2.528)
			(stroke
				(width 0.15)
				(type solid)
			)
			(layer "F.Fab")
		)
		(fp_line
			(start -5.995 -2.528)
			(end -5.995 -2.274)
			(stroke
				(width 0.15)
				(type solid)
			)
			(layer "F.Fab")
		)
		(fp_line
			(start -5.995 -2.528)
			(end -5.995 -2.528)
			(stroke
				(width 0.15)
				(type solid)
			)
			(layer "F.Fab")
		)
		(fp_line
			(start -5.995 -2.673)
			(end -5.995 -2.673)
			(stroke
				(width 0.15)
				(type solid)
			)
			(layer "F.Fab")
		)
		(fp_line
			(start -5.995 -2.673)
			(end -5.995 -2.927)
			(stroke
				(width 0.15)
				(type solid)
			)
			(layer "F.Fab")
		)
		(fp_line
			(start -5.995 -2.927)
			(end -5.995 -2.673)
			(stroke
				(width 0.15)
				(type solid)
			)
			(layer "F.Fab")
		)
		(fp_line
			(start -5.995 -2.927)
			(end -5.995 -2.927)
			(stroke
				(width 0.15)
				(type solid)
			)
			(layer "F.Fab")
		)
		(fp_line
			(start -5.995 -3.073)
			(end -5.995 -3.073)
			(stroke
				(width 0.15)
				(type solid)
			)
			(layer "F.Fab")
		)
		(fp_line
			(start -5.995 -3.073)
			(end -5.995 -3.327)
			(stroke
				(width 0.15)
				(type solid)
			)
			(layer "F.Fab")
		)
		(fp_line
			(start -5.995 -3.327)
			(end -5.995 -3.073)
			(stroke
				(width 0.15)
				(type solid)
			)
			(layer "F.Fab")
		)
		(fp_line
			(start -5.995 -3.327)
			(end -5.995 -3.327)
			(stroke
				(width 0.15)
				(type solid)
			)
			(layer "F.Fab")
		)
		(fp_line
			(start -5.995 -3.473)
			(end -5.995 -3.473)
			(stroke
				(width 0.15)
				(type solid)
			)
			(layer "F.Fab")
		)
		(fp_line
			(start -5.995 -3.473)
			(end -5.995 -3.727)
			(stroke
				(width 0.15)
				(type solid)
			)
			(layer "F.Fab")
		)
		(fp_line
			(start -5.995 -3.727)
			(end -5.995 -3.473)
			(stroke
				(width 0.15)
				(type solid)
			)
			(layer "F.Fab")
		)
		(fp_line
			(start -5.995 -3.727)
			(end -5.995 -3.727)
			(stroke
				(width 0.15)
				(type solid)
			)
			(layer "F.Fab")
		)
		(fp_line
			(start -5.995 -3.875)
			(end -5.995 -3.875)
			(stroke
				(width 0.15)
				(type solid)
			)
			(layer "F.Fab")
		)
		(fp_line
			(start -5.995 -3.875)
			(end -5.995 -4.127)
			(stroke
				(width 0.15)
				(type solid)
			)
			(layer "F.Fab")
		)
		(fp_line
			(start -5.995 -4.127)
			(end -5.995 -3.875)
			(stroke
				(width 0.15)
				(type solid)
			)
			(layer "F.Fab")
		)
		(fp_line
			(start -5.995 -4.127)
			(end -5.995 -4.127)
			(stroke
				(width 0.15)
				(type solid)
			)
			(layer "F.Fab")
		)
		(fp_line
			(start -5.995 -4.273)
			(end -5.995 -4.273)
			(stroke
				(width 0.15)
				(type solid)
			)
			(layer "F.Fab")
		)
		(fp_line
			(start -5.995 -4.273)
			(end -5.995 -4.529)
			(stroke
				(width 0.15)
				(type solid)
			)
			(layer "F.Fab")
		)
		(fp_line
			(start -5.995 -4.529)
			(end -5.995 -4.273)
			(stroke
				(width 0.15)
				(type solid)
			)
			(layer "F.Fab")
		)
		(fp_line
			(start -5.995 -4.529)
			(end -5.995 -4.529)
			(stroke
				(width 0.15)
				(type solid)
			)
			(layer "F.Fab")
		)
		(fp_line
			(start -5.995 -4.673)
			(end -5.995 -4.673)
			(stroke
				(width 0.15)
				(type solid)
			)
			(layer "F.Fab")
		)
		(fp_line
			(start -5.995 -4.673)
			(end -5.995 -4.928)
			(stroke
				(width 0.15)
				(type solid)
			)
			(layer "F.Fab")
		)
		(fp_line
			(start -5.995 -4.726)
			(end -4.726 -5.995)
			(stroke
				(width 0.15)
				(type solid)
			)
			(layer "F.Fab")
		)
		(fp_line
			(start -5.995 -4.928)
			(end -5.995 -4.673)
			(stroke
				(width 0.15)
				(type solid)
			)
			(layer "F.Fab")
		)
		(fp_line
			(start -5.995 -4.928)
			(end -5.995 -4.928)
			(stroke
				(width 0.15)
				(type solid)
			)
			(layer "F.Fab")
		)
		(fp_line
			(start -5.995 -5.995)
			(end -5.995 5.993)
			(stroke
				(width 0.15)
				(type solid)
			)
			(layer "F.Fab")
		)
		(fp_line
			(start -5.995 -5.995)
			(end -5.995 -5.995)
			(stroke
				(width 0.15)
				(type solid)
			)
			(layer "F.Fab")
		)
		(fp_text user "${REFERENCE}"
			(at -7.101 8.121 0)
			(layer "F.Fab")
			(effects
				(font
					(size 0.7 0.7)
					(thickness 0.15)
				)
				(justify right top)
			)
		)
		(fp_text user "Author: Antmicro"
			(at -7.101 9.121 0)
			(layer "F.Fab")
			(effects
				(font
					(size 0.7 0.7)
					(thickness 0.15)
				)
				(justify right top)
			)
		)
		(fp_text user "License: Apache-2.0"
			(at -7.101 10.121 0)
			(layer "F.Fab")
			(effects
				(font
					(size 0.7 0.7)
					(thickness 0.15)
				)
				(justify right top)
			)
		)
		(pad "1" smd roundrect
			(at -5.789 -4.802 270)
			(size 0.204 1.011199)
			(layers "F.Cu" "F.Mask" "F.Paste")
			(roundrect_rratio 0.25)
			(net 527 "/USB Hub/~{RESET}")
			(pinfunction "RESET_N")
			(pintype "input")
		)
		(pad "2" smd roundrect
			(at -5.789 -4.401 270)
			(size 0.204 1.011199)
			(layers "F.Cu" "F.Mask" "F.Paste")
			(roundrect_rratio 0.25)
			(net 1094 "unconnected-(U21-PF30-Pad2)")
			(pinfunction "PF30")
			(pintype "bidirectional+no_connect")
		)
		(pad "3" smd roundrect
			(at -5.789 -4 270)
			(size 0.204 1.011199)
			(layers "F.Cu" "F.Mask" "F.Paste")
			(roundrect_rratio 0.25)
			(net 1090 "unconnected-(U21-PF31-Pad3)")
			(pinfunction "PF31")
			(pintype "bidirectional+no_connect")
		)
		(pad "4" smd roundrect
			(at -5.789 -3.601 270)
			(size 0.204 1.011199)
			(layers "F.Cu" "F.Mask" "F.Paste")
			(roundrect_rratio 0.25)
			(net 932 "/USB Hub/USBC4_VBUS_MON")
			(pinfunction "DP1_VBUS_MON")
			(pintype "bidirectional")
		)
		(pad "5" smd roundrect
			(at -5.789 -3.201 270)
			(size 0.204 1.011199)
			(layers "F.Cu" "F.Mask" "F.Paste")
			(roundrect_rratio 0.25)
			(net 505 "/USB Hub/USBC4_D+")
			(pinfunction "USB2DN_DP1")
			(pintype "bidirectional")
		)
		(pad "6" smd roundrect
			(at -5.789 -2.801 270)
			(size 0.204 1.011199)
			(layers "F.Cu" "F.Mask" "F.Paste")
			(roundrect_rratio 0.25)
			(net 499 "/USB Hub/USBC4_D-")
			(pinfunction "USB2DN_DM1")
			(pintype "bidirectional")
		)
		(pad "7" smd roundrect
			(at -5.789 -2.4 270)
			(size 0.204 1.011199)
			(layers "F.Cu" "F.Mask" "F.Paste")
			(roundrect_rratio 0.25)
			(net 40 "/USB Hub/USBC4_TX_{1}+")
			(pinfunction "USB3DN_TXDP1A")
			(pintype "bidirectional")
		)
		(pad "8" smd roundrect
			(at -5.789 -2.001 270)
			(size 0.204 1.011199)
			(layers "F.Cu" "F.Mask" "F.Paste")
			(roundrect_rratio 0.25)
			(net 44 "/USB Hub/USBC4_TX_{1}-")
			(pinfunction "USB3DN_TXDM1A")
			(pintype "bidirectional")
		)
		(pad "9" smd roundrect
			(at -5.789 -1.601 270)
			(size 0.204 1.011199)
			(layers "F.Cu" "F.Mask" "F.Paste")
			(roundrect_rratio 0.25)
			(net 282 "+1V15")
			(pinfunction "VCORE")
			(pintype "power_in")
		)
		(pad "10" smd roundrect
			(at -5.789 -1.2 270)
			(size 0.204 1.011199)
			(layers "F.Cu" "F.Mask" "F.Paste")
			(roundrect_rratio 0.25)
			(net 504 "/USB Hub/USBC4_RX_{1}+")
			(pinfunction "USB3DN_RXDP1A")
			(pintype "bidirectional")
		)
		(pad "11" smd roundrect
			(at -5.789 -0.802 270)
			(size 0.204 1.011199)
			(layers "F.Cu" "F.Mask" "F.Paste")
			(roundrect_rratio 0.25)
			(net 501 "/USB Hub/USBC4_RX_{1}-")
			(pinfunction "USB3DN_RXDM1A")
			(pintype "bidirectional")
		)
		(pad "12" smd roundrect
			(at -5.789 -0.401 270)
			(size 0.204 1.011199)
			(layers "F.Cu" "F.Mask" "F.Paste")
			(roundrect_rratio 0.25)
			(net 503 "/USB Hub/USBC4_CC_{1}")
			(pinfunction "DP1_CC1")
			(pintype "bidirectional")
		)
		(pad "13" smd roundrect
			(at -5.789 0 270)
			(size 0.204 1.011199)
			(layers "F.Cu" "F.Mask" "F.Paste")
			(roundrect_rratio 0.25)
			(net 502 "/USB Hub/USBC4_CC_{2}")
			(pinfunction "DP1_CC2")
			(pintype "bidirectional")
		)
		(pad "14" smd roundrect
			(at -5.789 0.399 270)
			(size 0.204 1.011199)
			(layers "F.Cu" "F.Mask" "F.Paste")
			(roundrect_rratio 0.25)
			(net 1138 "Net-(U21-USB2DN_DP4)")
			(pinfunction "USB2DN_DP4")
			(pintype "bidirectional")
		)
		(pad "15" smd roundrect
			(at -5.789 0.8 270)
			(size 0.204 1.011199)
			(layers "F.Cu" "F.Mask" "F.Paste")
			(roundrect_rratio 0.25)
			(net 1141 "Net-(U21-USB2DN_DM4)")
			(pinfunction "USB2DN_DM4")
			(pintype "bidirectional")
		)
		(pad "16" smd roundrect
			(at -5.789 1.199 270)
			(size 0.204 1.011199)
			(layers "F.Cu" "F.Mask" "F.Paste")
			(roundrect_rratio 0.25)
			(net 41 "/USB Hub/USBC4_TX_{2}+")
			(pinfunction "USB3DN_TXDP1B")
			(pintype "bidirectional")
		)
		(pad "17" smd roundrect
			(at -5.789 1.598 270)
			(size 0.204 1.011199)
			(layers "F.Cu" "F.Mask" "F.Paste")
			(roundrect_rratio 0.25)
			(net 214 "/USB Hub/USBC4_TX_{2}-")
			(pinfunction "USB3DN_TXDM1B")
			(pintype "bidirectional")
		)
		(pad "18" smd roundrect
			(at -5.789 1.999 270)
			(size 0.204 1.011199)
			(layers "F.Cu" "F.Mask" "F.Paste")
			(roundrect_rratio 0.25)
			(net 282 "+1V15")
			(pinfunction "VCORE")
			(pintype "power_in")
		)
		(pad "19" smd roundrect
			(at -5.789 2.398 270)
			(size 0.204 1.011199)
			(layers "F.Cu" "F.Mask" "F.Paste")
			(roundrect_rratio 0.25)
			(net 498 "/USB Hub/USBC4_RX_{2}+")
			(pinfunction "USB3DN_RXDP1B")
			(pintype "bidirectional")
		)
		(pad "20" smd roundrect
			(at -5.789 2.798 270)
			(size 0.204 1.011199)
			(layers "F.Cu" "F.Mask" "F.Paste")
			(roundrect_rratio 0.25)
			(net 500 "/USB Hub/USBC4_RX_{2}-")
			(pinfunction "USB3DN_RXDM1B")
			(pintype "bidirectional")
		)
		(pad "21" smd roundrect
			(at -5.789 3.199 270)
			(size 0.204 1.011199)
			(layers "F.Cu" "F.Mask" "F.Paste")
			(roundrect_rratio 0.25)
			(net 913 "/USB Hub/CFG_STRAP1")
			(pinfunction "CFG_STRAP1")
			(pintype "input")
		)
		(pad "22" smd roundrect
			(at -5.789 3.6 270)
			(size 0.204 1.011199)
			(layers "F.Cu" "F.Mask" "F.Paste")
			(roundrect_rratio 0.25)
			(net 915 "/USB Hub/CFG_STRAP2")
			(pinfunction "CFG_STRAP2")
			(pintype "input")
		)
		(pad "23" smd roundrect
			(at -5.789 3.999 270)
			(size 0.204 1.011199)
			(layers "F.Cu" "F.Mask" "F.Paste")
			(roundrect_rratio 0.25)
			(net 931 "/USB Hub/CFG_STRAP3")
			(pinfunction "CFG_STRAP3")
			(pintype "input")
		)
		(pad "24" smd roundrect
			(at -5.789 4.398 270)
			(size 0.204 1.011199)
			(layers "F.Cu" "F.Mask" "F.Paste")
			(roundrect_rratio 0.25)
			(net 1 "GND")
			(pinfunction "TESTEN")
			(pintype "bidirectional")
		)
		(pad "25" smd roundrect
			(at -5.789 4.799 270)
			(size 0.204 1.011199)
			(layers "F.Cu" "F.Mask" "F.Paste")
			(roundrect_rratio 0.25)
			(net 282 "+1V15")
			(pinfunction "VCORE")
			(pintype "power_in")
		)
		(pad "26" smd roundrect
			(at -4.802 5.788 180)
			(size 0.204 1.011199)
			(layers "F.Cu" "F.Mask" "F.Paste")
			(roundrect_rratio 0.25)
			(net 2 "+3V3")
			(pinfunction "VDD33")
			(pintype "power_in")
		)
		(pad "27" smd roundrect
			(at -4.401 5.788 180)
			(size 0.204 1.011199)
			(layers "F.Cu" "F.Mask" "F.Paste")
			(roundrect_rratio 0.25)
			(net 510 "/USB Hub/USBC3_CC_{1}")
			(pinfunction "DP2_CC1")
			(pintype "bidirectional")
		)
		(pad "28" smd roundrect
			(at -4 5.788 180)
			(size 0.204 1.011199)
			(layers "F.Cu" "F.Mask" "F.Paste")
			(roundrect_rratio 0.25)
			(net 509 "/USB Hub/USBC3_CC_{2}")
			(pinfunction "DP2_CC2")
			(pintype "bidirectional")
		)
		(pad "29" smd roundrect
			(at -3.601 5.788 180)
			(size 0.204 1.011199)
			(layers "F.Cu" "F.Mask" "F.Paste")
			(roundrect_rratio 0.25)
			(net 506 "/USB Hub/USBC3_D+")
			(pinfunction "USB2DN_DP2")
			(pintype "bidirectional")
		)
		(pad "30" smd roundrect
			(at -3.201 5.788 180)
			(size 0.204 1.011199)
			(layers "F.Cu" "F.Mask" "F.Paste")
			(roundrect_rratio 0.25)
			(net 508 "/USB Hub/USBC3_D-")
			(pinfunction "USB2DN_DM2")
			(pintype "bidirectional")
		)
		(pad "31" smd roundrect
			(at -2.801 5.788 180)
			(size 0.204 1.011199)
			(layers "F.Cu" "F.Mask" "F.Paste")
			(roundrect_rratio 0.25)
			(net 45 "/USB Hub/USBC3_TX_{1}+")
			(pinfunction "USB3DN_TXDP2A")
			(pintype "bidirectional")
		)
		(pad "32" smd roundrect
			(at -2.4 5.788 180)
			(size 0.204 1.011199)
			(layers "F.Cu" "F.Mask" "F.Paste")
			(roundrect_rratio 0.25)
			(net 283 "/USB Hub/USBC3_TX_{1}-")
			(pinfunction "USB3DN_TXDM2A")
			(pintype "bidirectional")
		)
		(pad "33" smd roundrect
			(at -2.001 5.788 180)
			(size 0.204 1.011199)
			(layers "F.Cu" "F.Mask" "F.Paste")
			(roundrect_rratio 0.25)
			(net 282 "+1V15")
			(pinfunction "VCORE")
			(pintype "power_in")
		)
		(pad "34" smd roundrect
			(at -1.601 5.788 180)
			(size 0.204 1.011199)
			(layers "F.Cu" "F.Mask" "F.Paste")
			(roundrect_rratio 0.25)
			(net 513 "/USB Hub/USBC3_RX_{1}+")
			(pinfunction "USB3DN_RXDP2A")
			(pintype "bidirectional")
		)
		(pad "35" smd roundrect
			(at -1.2 5.788 180)
			(size 0.204 1.011199)
			(layers "F.Cu" "F.Mask" "F.Paste")
			(roundrect_rratio 0.25)
			(net 507 "/USB Hub/USBC3_RX_{1}-")
			(pinfunction "USB3DN_RXDM2A")
			(pintype "bidirectional")
		)
		(pad "36" smd roundrect
			(at -0.802 5.788 180)
			(size 0.204 1.011199)
			(layers "F.Cu" "F.Mask" "F.Paste")
			(roundrect_rratio 0.25)
			(net 1016 "/USB Hub/USBC3_VBUS_MON")
			(pinfunction "DP2_VBUS_MON")
			(pintype "bidirectional")
		)
		(pad "37" smd roundrect
			(at -0.401 5.788 180)
			(size 0.204 1.011199)
			(layers "F.Cu" "F.Mask" "F.Paste")
			(roundrect_rratio 0.25)
			(net 212 "/USB Hub/USBC3_TX_{2}+")
			(pinfunction "USB3DN_TXDP2B")
			(pintype "bidirectional")
		)
		(pad "38" smd roundrect
			(at 0 5.788 180)
			(size 0.204 1.011199)
			(layers "F.Cu" "F.Mask" "F.Paste")
			(roundrect_rratio 0.25)
			(net 285 "/USB Hub/USBC3_TX_{2}-")
			(pinfunction "USB3DN_TXDM2B")
			(pintype "bidirectional")
		)
		(pad "39" smd roundrect
			(at 0.399 5.788 180)
			(size 0.204 1.011199)
			(layers "F.Cu" "F.Mask" "F.Paste")
			(roundrect_rratio 0.25)
			(net 282 "+1V15")
			(pinfunction "VCORE")
			(pintype "power_in")
		)
		(pad "40" smd roundrect
			(at 0.8 5.788 180)
			(size 0.204 1.011199)
			(layers "F.Cu" "F.Mask" "F.Paste")
			(roundrect_rratio 0.25)
			(net 512 "/USB Hub/USBC3_RX_{2}+")
			(pinfunction "USB3DN_RXDP2B")
			(pintype "bidirectional")
		)
		(pad "41" smd roundrect
			(at 1.199 5.788 180)
			(size 0.204 1.011199)
			(layers "F.Cu" "F.Mask" "F.Paste")
			(roundrect_rratio 0.25)
			(net 511 "/USB Hub/USBC3_RX_{2}-")
			(pinfunction "USB3DN_RXDM2B")
			(pintype "bidirectional")
		)
		(pad "42" smd roundrect
			(at 1.598 5.788 180)
			(size 0.204 1.011199)
			(layers "F.Cu" "F.Mask" "F.Paste")
			(roundrect_rratio 0.25)
			(net 2 "+3V3")
			(pinfunction "VDD33")
			(pintype "power_in")
		)
		(pad "43" smd roundrect
			(at 1.999 5.788 180)
			(size 0.204 1.011199)
			(layers "F.Cu" "F.Mask" "F.Paste")
			(roundrect_rratio 0.25)
			(net 1084 "/USB Hub/DP1_VCONN1")
			(pinfunction "PF2")
			(pintype "bidirectional")
		)
		(pad "44" smd roundrect
			(at 2.398 5.788 180)
			(size 0.204 1.011199)
			(layers "F.Cu" "F.Mask" "F.Paste")
			(roundrect_rratio 0.25)
			(net 1095 "/USB Hub/DP1_VCONN2")
			(pinfunction "PF3")
			(pintype "bidirectional")
		)
		(pad "45" smd roundrect
			(at 2.798 5.788 180)
			(size 0.204 1.011199)
			(layers "F.Cu" "F.Mask" "F.Paste")
			(roundrect_rratio 0.25)
			(net 1085 "/USB Hub/DP2_DISCH")
			(pinfunction "PF4")
			(pintype "bidirectional")
		)
		(pad "46" smd roundrect
			(at 3.199 5.788 180)
			(size 0.204 1.011199)
			(layers "F.Cu" "F.Mask" "F.Paste")
			(roundrect_rratio 0.25)
			(net 1103 "/USB Hub/DP1_DISCH")
			(pinfunction "PF5")
			(pintype "bidirectional")
		)
		(pad "47" smd roundrect
			(at 3.6 5.788 180)
			(size 0.204 1.011199)
			(layers "F.Cu" "F.Mask" "F.Paste")
			(roundrect_rratio 0.25)
			(net 1097 "unconnected-(U21-PF6-Pad47)")
			(pinfunction "PF6")
			(pintype "bidirectional+no_connect")
		)
		(pad "48" smd roundrect
			(at 3.999 5.788 180)
			(size 0.204 1.011199)
			(layers "F.Cu" "F.Mask" "F.Paste")
			(roundrect_rratio 0.25)
			(net 1082 "unconnected-(U21-PF7-Pad48)")
			(pinfunction "PF7")
			(pintype "bidirectional+no_connect")
		)
		(pad "49" smd roundrect
			(at 4.398 5.788 180)
			(size 0.204 1.011199)
			(layers "F.Cu" "F.Mask" "F.Paste")
			(roundrect_rratio 0.25)
			(net 1098 "unconnected-(U21-PF8-Pad49)")
			(pinfunction "PF8")
			(pintype "bidirectional+no_connect")
		)
		(pad "50" smd roundrect
			(at 4.799 5.788 180)
			(size 0.204 1.011199)
			(layers "F.Cu" "F.Mask" "F.Paste")
			(roundrect_rratio 0.25)
			(net 1092 "unconnected-(U21-PF9-Pad50)")
			(pinfunction "PF9")
			(pintype "bidirectional+no_connect")
		)
		(pad "51" smd roundrect
			(at 5.788 4.799 270)
			(size 0.204 1.011199)
			(layers "F.Cu" "F.Mask" "F.Paste")
			(roundrect_rratio 0.25)
			(net 1099 "/USB Hub/DP2_VCONN1")
			(pinfunction "PF10")
			(pintype "bidirectional")
		)
		(pad "52" smd roundrect
			(at 5.788 4.398 270)
			(size 0.204 1.011199)
			(layers "F.Cu" "F.Mask" "F.Paste")
			(roundrect_rratio 0.25)
			(net 1106 "/USB Hub/DP2_VCONN2")
			(pinfunction "PF11")
			(pintype "bidirectional")
		)
		(pad "53" smd roundrect
			(at 5.788 3.999 270)
			(size 0.204 1.011199)
			(layers "F.Cu" "F.Mask" "F.Paste")
			(roundrect_rratio 0.25)
			(net 2 "+3V3")
			(pinfunction "VDD33")
			(pintype "power_in")
		)
		(pad "54" smd roundrect
			(at 5.788 3.6 270)
			(size 0.204 1.011199)
			(layers "F.Cu" "F.Mask" "F.Paste")
			(roundrect_rratio 0.25)
			(net 1175 "unconnected-(U21-PF12-Pad54)")
			(pinfunction "PF12")
			(pintype "bidirectional+no_connect")
		)
		(pad "55" smd roundrect
			(at 5.788 3.199 270)
			(size 0.204 1.011199)
			(layers "F.Cu" "F.Mask" "F.Paste")
			(roundrect_rratio 0.25)
			(net 282 "+1V15")
			(pinfunction "VCORE")
			(pintype "power_in")
		)
		(pad "56" smd roundrect
			(at 5.788 2.798 270)
			(size 0.204 1.011199)
			(layers "F.Cu" "F.Mask" "F.Paste")
			(roundrect_rratio 0.25)
			(net 910 "/USB Hub/PRT_CTL3")
			(pinfunction "PF13")
			(pintype "bidirectional")
		)
		(pad "57" smd roundrect
			(at 5.788 2.398 270)
			(size 0.204 1.011199)
			(layers "F.Cu" "F.Mask" "F.Paste")
			(roundrect_rratio 0.25)
			(net 1173 "unconnected-(U21-PF14-Pad57)")
			(pinfunction "PF14")
			(pintype "bidirectional+no_connect")
		)
		(pad "58" smd roundrect
			(at 5.788 1.999 270)
			(size 0.204 1.011199)
			(layers "F.Cu" "F.Mask" "F.Paste")
			(roundrect_rratio 0.25)
			(net 911 "/USB Hub/PRT_CTL2")
			(pinfunction "PF15")
			(pintype "bidirectional")
		)
		(pad "59" smd roundrect
			(at 5.788 1.598 270)
			(size 0.204 1.011199)
			(layers "F.Cu" "F.Mask" "F.Paste")
			(roundrect_rratio 0.25)
			(net 912 "/USB Hub/PRT_CTL4")
			(pinfunction "PF16")
			(pintype "bidirectional")
		)
		(pad "60" smd roundrect
			(at 5.788 1.199 270)
			(size 0.204 1.011199)
			(layers "F.Cu" "F.Mask" "F.Paste")
			(roundrect_rratio 0.25)
			(net 914 "/USB Hub/PRT_CTL1")
			(pinfunction "PF17")
			(pintype "bidirectional")
		)
		(pad "61" smd roundrect
			(at 5.788 0.8 270)
			(size 0.204 1.011199)
			(layers "F.Cu" "F.Mask" "F.Paste")
			(roundrect_rratio 0.25)
			(net 1174 "unconnected-(U21-PF18-Pad61)")
			(pinfunction "PF18")
			(pintype "bidirectional+no_connect")
		)
		(pad "62" smd roundrect
			(at 5.788 0.399 270)
			(size 0.204 1.011199)
			(layers "F.Cu" "F.Mask" "F.Paste")
			(roundrect_rratio 0.25)
			(net 2 "+3V3")
			(pinfunction "VDD33")
			(pintype "power_in")
		)
		(pad "63" smd roundrect
			(at 5.788 0 270)
			(size 0.204 1.011199)
			(layers "F.Cu" "F.Mask" "F.Paste")
			(roundrect_rratio 0.25)
			(net 920 "/USB Hub/TEST1")
			(pinfunction "TEST1")
			(pintype "passive")
		)
		(pad "64" smd roundrect
			(at 5.788 -0.401 270)
			(size 0.204 1.011199)
			(layers "F.Cu" "F.Mask" "F.Paste")
			(roundrect_rratio 0.25)
			(net 917 "/USB Hub/TEST2")
			(pinfunction "TEST2")
			(pintype "passive")
		)
		(pad "65" smd roundrect
			(at 5.788 -0.802 270)
			(size 0.204 1.011199)
			(layers "F.Cu" "F.Mask" "F.Paste")
			(roundrect_rratio 0.25)
			(net 916 "/USB Hub/TEST3")
			(pinfunction "TEST3")
			(pintype "passive")
		)
		(pad "66" smd roundrect
			(at 5.788 -1.2 270)
			(size 0.204 1.011199)
			(layers "F.Cu" "F.Mask" "F.Paste")
			(roundrect_rratio 0.25)
			(net 1233 "Net-(U21-PF19)")
			(pinfunction "PF19")
			(pintype "bidirectional")
		)
		(pad "67" smd roundrect
			(at 5.788 -1.601 270)
			(size 0.204 1.011199)
			(layers "F.Cu" "F.Mask" "F.Paste")
			(roundrect_rratio 0.25)
			(net 2 "+3V3")
			(pinfunction "VDD33")
			(pintype "power_in")
		)
		(pad "68" smd roundrect
			(at 5.788 -2 270)
			(size 0.204 1.011199)
			(layers "F.Cu" "F.Mask" "F.Paste")
			(roundrect_rratio 0.25)
			(net 927 "/USB Hub/HUB_SPI_CLK")
			(pinfunction "SPI_CLK")
			(pintype "bidirectional")
		)
		(pad "69" smd roundrect
			(at 5.788 -2.4 270)
			(size 0.204 1.011199)
			(layers "F.Cu" "F.Mask" "F.Paste")
			(roundrect_rratio 0.25)
			(net 930 "/USB Hub/HUB_SPI_CE_N")
			(pinfunction "SPI_CE_N")
			(pintype "bidirectional")
		)
		(pad "70" smd roundrect
			(at 5.788 -2.801 270)
			(size 0.204 1.011199)
			(layers "F.Cu" "F.Mask" "F.Paste")
			(roundrect_rratio 0.25)
			(net 925 "/USB Hub/HUB_SPI_D0")
			(pinfunction "SPI_D0")
			(pintype "bidirectional")
		)
		(pad "71" smd roundrect
			(at 5.788 -3.201 270)
			(size 0.204 1.011199)
			(layers "F.Cu" "F.Mask" "F.Paste")
			(roundrect_rratio 0.25)
			(net 922 "/USB Hub/HUB_SPI_D1")
			(pinfunction "SPI_D1")
			(pintype "bidirectional")
		)
		(pad "72" smd roundrect
			(at 5.788 -3.601 270)
			(size 0.204 1.011199)
			(layers "F.Cu" "F.Mask" "F.Paste")
			(roundrect_rratio 0.25)
			(net 921 "/USB Hub/HUB_SPI_D2")
			(pinfunction "SPI_D2")
			(pintype "bidirectional")
		)
		(pad "73" smd roundrect
			(at 5.788 -4 270)
			(size 0.204 1.011199)
			(layers "F.Cu" "F.Mask" "F.Paste")
			(roundrect_rratio 0.25)
			(net 924 "/USB Hub/HUB_SPI_D3")
			(pinfunction "SPI_D3")
			(pintype "bidirectional")
		)
		(pad "74" smd roundrect
			(at 5.788 -4.401 270)
			(size 0.204 1.011199)
			(layers "F.Cu" "F.Mask" "F.Paste")
			(roundrect_rratio 0.25)
			(net 1083 "unconnected-(U21-PF29-Pad74)")
			(pinfunction "PF29")
			(pintype "bidirectional+no_connect")
		)
		(pad "75" smd roundrect
			(at 5.788 -4.8 270)
			(size 0.204 1.011199)
			(layers "F.Cu" "F.Mask" "F.Paste")
			(roundrect_rratio 0.25)
			(net 1234 "Net-(U21-PF26)")
			(pinfunction "PF26")
			(pintype "bidirectional")
		)
		(pad "76" smd roundrect
			(at 4.799 -5.789 180)
			(size 0.204 1.011199)
			(layers "F.Cu" "F.Mask" "F.Paste")
			(roundrect_rratio 0.25)
			(net 1093 "unconnected-(U21-PF27-Pad76)")
			(pinfunction "PF27")
			(pintype "bidirectional+no_connect")
		)
		(pad "77" smd roundrect
			(at 4.398 -5.789 180)
			(size 0.204 1.011199)
			(layers "F.Cu" "F.Mask" "F.Paste")
			(roundrect_rratio 0.25)
			(net 1102 "unconnected-(U21-PF28-Pad77)")
			(pinfunction "PF28")
			(pintype "bidirectional+no_connect")
		)
		(pad "78" smd roundrect
			(at 3.999 -5.789 180)
			(size 0.204 1.011199)
			(layers "F.Cu" "F.Mask" "F.Paste")
			(roundrect_rratio 0.25)
			(net 282 "+1V15")
			(pinfunction "VCORE")
			(pintype "power_in")
		)
		(pad "79" smd roundrect
			(at 3.6 -5.789 180)
			(size 0.204 1.011199)
			(layers "F.Cu" "F.Mask" "F.Paste")
			(roundrect_rratio 0.25)
			(net 2 "+3V3")
			(pinfunction "VDD33")
			(pintype "power_in")
		)
		(pad "80" smd roundrect
			(at 3.199 -5.789 180)
			(size 0.204 1.011199)
			(layers "F.Cu" "F.Mask" "F.Paste")
			(roundrect_rratio 0.25)
			(net 1164 "/USB Hub/VBUS_MON_UP")
			(pinfunction "VBUS_MON_UP")
			(pintype "bidirectional")
		)
		(pad "81" smd roundrect
			(at 2.798 -5.789 180)
			(size 0.204 1.011199)
			(layers "F.Cu" "F.Mask" "F.Paste")
			(roundrect_rratio 0.25)
			(net 1111 "Net-(U21-USB2DN_DP3)")
			(pinfunction "USB2DN_DP3")
			(pintype "bidirectional")
		)
		(pad "82" smd roundrect
			(at 2.398 -5.789 180)
			(size 0.204 1.011199)
			(layers "F.Cu" "F.Mask" "F.Paste")
			(roundrect_rratio 0.25)
			(net 1126 "Net-(U21-USB2DN_DM3)")
			(pinfunction "USB2DN_DM3")
			(pintype "bidirectional")
		)
		(pad "83" smd roundrect
			(at 1.999 -5.789 180)
			(size 0.204 1.011199)
			(layers "F.Cu" "F.Mask" "F.Paste")
			(roundrect_rratio 0.25)
			(net 1091 "unconnected-(U21-USB3DN_TXDP3-Pad83)")
			(pinfunction "USB3DN_TXDP3")
			(pintype "bidirectional+no_connect")
		)
		(pad "84" smd roundrect
			(at 1.598 -5.789 180)
			(size 0.204 1.011199)
			(layers "F.Cu" "F.Mask" "F.Paste")
			(roundrect_rratio 0.25)
			(net 1080 "unconnected-(U21-USB3DN_TXDM3-Pad84)")
			(pinfunction "USB3DN_TXDM3")
			(pintype "bidirectional+no_connect")
		)
		(pad "85" smd roundrect
			(at 1.199 -5.789 180)
			(size 0.204 1.011199)
			(layers "F.Cu" "F.Mask" "F.Paste")
			(roundrect_rratio 0.25)
			(net 282 "+1V15")
			(pinfunction "VCORE")
			(pintype "power_in")
		)
		(pad "86" smd roundrect
			(at 0.8 -5.789 180)
			(size 0.204 1.011199)
			(layers "F.Cu" "F.Mask" "F.Paste")
			(roundrect_rratio 0.25)
			(net 1142 "Net-(U21-USB3DN_RXDP3)")
			(pinfunction "USB3DN_RXDP3")
			(pintype "bidirectional")
		)
		(pad "87" smd roundrect
			(at 0.399 -5.789 180)
			(size 0.204 1.011199)
			(layers "F.Cu" "F.Mask" "F.Paste")
			(roundrect_rratio 0.25)
			(net 1163 "Net-(U21-USB3DN_RXDM3)")
			(pinfunction "USB3DN_RXDM3")
			(pintype "bidirectional")
		)
		(pad "88" smd roundrect
			(at 0 -5.789 180)
			(size 0.204 1.011199)
			(layers "F.Cu" "F.Mask" "F.Paste")
			(roundrect_rratio 0.25)
			(net 2 "+3V3")
			(pinfunction "VDD33")
			(pintype "power_in")
		)
		(pad "89" smd roundrect
			(at -0.401 -5.789 180)
			(size 0.204 1.011199)
			(layers "F.Cu" "F.Mask" "F.Paste")
			(roundrect_rratio 0.25)
			(net 492 "/SoM_IO2/USB2.D+")
			(pinfunction "USB2UP_DP")
			(pintype "bidirectional")
		)
		(pad "90" smd roundrect
			(at -0.802 -5.789 180)
			(size 0.204 1.011199)
			(layers "F.Cu" "F.Mask" "F.Paste")
			(roundrect_rratio 0.25)
			(net 493 "/SoM_IO2/USB2.D-")
			(pinfunction "USB2UP_DM")
			(pintype "bidirectional")
		)
		(pad "91" smd roundrect
			(at -1.2 -5.789 180)
			(size 0.204 1.011199)
			(layers "F.Cu" "F.Mask" "F.Paste")
			(roundrect_rratio 0.25)
			(net 1132 "/USB Hub/USBSS_TX_P")
			(pinfunction "USB3UP_TXDP")
			(pintype "bidirectional")
		)
		(pad "92" smd roundrect
			(at -1.601 -5.789 180)
			(size 0.204 1.011199)
			(layers "F.Cu" "F.Mask" "F.Paste")
			(roundrect_rratio 0.25)
			(net 1134 "/USB Hub/USBSS_TX_N")
			(pinfunction "USB3UP_TXDM")
			(pintype "bidirectional")
		)
		(pad "93" smd roundrect
			(at -2 -5.789 180)
			(size 0.204 1.011199)
			(layers "F.Cu" "F.Mask" "F.Paste")
			(roundrect_rratio 0.25)
			(net 282 "+1V15")
			(pinfunction "VCORE")
			(pintype "power_in")
		)
		(pad "94" smd roundrect
			(at -2.4 -5.789 180)
			(size 0.204 1.011199)
			(layers "F.Cu" "F.Mask" "F.Paste")
			(roundrect_rratio 0.25)
			(net 1133 "/USB Hub/USBSS_RX_P")
			(pinfunction "USB3UP_RXDP")
			(pintype "bidirectional")
		)
		(pad "95" smd roundrect
			(at -2.801 -5.789 180)
			(size 0.204 1.011199)
			(layers "F.Cu" "F.Mask" "F.Paste")
			(roundrect_rratio 0.25)
			(net 1135 "/USB Hub/USBSS_RX_N")
			(pinfunction "USB3UP_RXDM")
			(pintype "bidirectional")
		)
		(pad "96" smd roundrect
			(at -3.201 -5.789 180)
			(size 0.204 1.011199)
			(layers "F.Cu" "F.Mask" "F.Paste")
			(roundrect_rratio 0.25)
			(net 1079 "unconnected-(U21-ATEST-Pad96)")
			(pinfunction "ATEST")
			(pintype "no_connect")
		)
		(pad "97" smd roundrect
			(at -3.601 -5.789 180)
			(size 0.204 1.011199)
			(layers "F.Cu" "F.Mask" "F.Paste")
			(roundrect_rratio 0.25)
			(net 1087 "unconnected-(U21-XTALO-Pad97)")
			(pinfunction "XTALO")
			(pintype "output+no_connect")
		)
		(pad "98" smd roundrect
			(at -4 -5.789 180)
			(size 0.204 1.011199)
			(layers "F.Cu" "F.Mask" "F.Paste")
			(roundrect_rratio 0.25)
			(net 1078 "Net-(U21-XTALI)")
			(pinfunction "XTALI")
			(pintype "input")
		)
		(pad "99" smd roundrect
			(at -4.401 -5.789 180)
			(size 0.204 1.011199)
			(layers "F.Cu" "F.Mask" "F.Paste")
			(roundrect_rratio 0.25)
			(net 2 "+3V3")
			(pinfunction "VDD33")
			(pintype "power_in")
		)
		(pad "100" smd roundrect
			(at -4.8 -5.789 180)
			(size 0.204 1.011199)
			(layers "F.Cu" "F.Mask" "F.Paste")
			(roundrect_rratio 0.25)
			(net 919 "Net-(U21-RBIAS)")
			(pinfunction "RBIAS")
			(pintype "input")
		)
		(pad "101" smd roundrect
			(at 0 0 180)
			(size 8.1026 8.1026)
			(layers "F.Cu" "F.Mask")
			(roundrect_rratio 0.05)
			(net 1 "GND")
			(pinfunction "VSS")
			(pintype "power_in")
		)
	)
	(footprint "antmicro-footprints:C_0402_1005Metric"
		(layer "F.Cu")
		(at 89.1 99.8)
		(descr "Capacitor SMD 0402")
		(tags "capacitor SMD 0402")
		(property "Reference" "C337"
			(at -3.82 0.449999 0)
			(layer "F.SilkS")
			(effects
				(font
					(size 0.7 0.7)
					(thickness 0.15)
				)
				(justify left bottom)
			)
		)
		(property "Value" "C_100n_0402"
			(at -1.022927 2.155213 0)
			(layer "F.Fab")
			(effects
				(font
					(size 0.7 0.7)
					(thickness 0.15)
				)
				(justify left bottom)
			)
		)
		(property "Datasheet" "https://www.murata.com/products/productdetail?partno=GRM155R61H104KE14%23"
			(at 0 0 0)
			(layer "F.Fab")
			(hide yes)
			(effects
				(font
					(size 1.27 1.27)
					(thickness 0.15)
				)
			)
		)
		(property "Description" "SMD Multilayer Ceramic Capacitor, 0.1 µF, 50 V, 0402 [1005 Metric], ± 10%, X5R, GRM Series"
			(at 0 0 0)
			(layer "F.Fab")
			(hide yes)
			(effects
				(font
					(size 1.27 1.27)
					(thickness 0.15)
				)
			)
		)
		(property "Manufacturer" "Murata"
			(at 0 0 0)
			(unlocked yes)
			(layer "F.Fab")
			(hide yes)
			(effects
				(font
					(size 1 1)
					(thickness 0.15)
				)
			)
		)
		(property "MPN" "GRM155R61H104KE14D"
			(at 0 0 0)
			(unlocked yes)
			(layer "F.Fab")
			(hide yes)
			(effects
				(font
					(size 1 1)
					(thickness 0.15)
				)
			)
		)
		(property "Val" "100n"
			(at 0 0 0)
			(unlocked yes)
			(layer "F.Fab")
			(hide yes)
			(effects
				(font
					(size 1 1)
					(thickness 0.15)
				)
			)
		)
		(property "License" "Apache-2.0"
			(at 0 0 0)
			(unlocked yes)
			(layer "F.Fab")
			(hide yes)
			(effects
				(font
					(size 1 1)
					(thickness 0.15)
				)
			)
		)
		(property "Author" "Antmicro"
			(at 0 0 0)
			(unlocked yes)
			(layer "F.Fab")
			(hide yes)
			(effects
				(font
					(size 1 1)
					(thickness 0.15)
				)
			)
		)
		(property "Voltage" "50V"
			(at 0 0 0)
			(unlocked yes)
			(layer "F.Fab")
			(hide yes)
			(effects
				(font
					(size 1 1)
					(thickness 0.15)
				)
			)
		)
		(property "Dielectric" "X5R"
			(at 0 0 0)
			(unlocked yes)
			(layer "F.Fab")
			(hide yes)
			(effects
				(font
					(size 1 1)
					(thickness 0.15)
				)
			)
		)
		(sheetname "/SoM_IO2/")
		(sheetfile "som_io2.kicad_sch")
		(attr smd)
		(fp_poly
			(pts
				(xy -0.925 -0.47) (xy 0.925 -0.47) (xy 0.925 0.47) (xy -0.925 0.47)
			)
			(stroke
				(width 0.05)
				(type default)
			)
			(fill no)
			(layer "F.CrtYd")
		)
		(fp_line
			(start -0.494 -0.25)
			(end 0.504 -0.25)
			(stroke
				(width 0.15)
				(type solid)
			)
			(layer "F.Fab")
		)
		(fp_line
			(start -0.494 0.248)
			(end -0.494 -0.25)
			(stroke
				(width 0.15)
				(type solid)
			)
			(layer "F.Fab")
		)
		(fp_line
			(start 0.504 -0.25)
			(end 0.504 0.248)
			(stroke
				(width 0.15)
				(type solid)
			)
			(layer "F.Fab")
		)
		(fp_line
			(start 0.504 0.248)
			(end -0.494 0.248)
			(stroke
				(width 0.15)
				(type solid)
			)
			(layer "F.Fab")
		)
		(fp_text user "Author: Antmicro"
			(at -0.939 3.399 0)
			(layer "F.Fab")
			(effects
				(font
					(size 0.7 0.7)
					(thickness 0.15)
				)
				(justify left bottom)
			)
		)
		(fp_text user "License: Apache-2.0"
			(at -0.939 5.799 0)
			(layer "F.Fab")
			(effects
				(font
					(size 0.7 0.7)
					(thickness 0.15)
				)
				(justify left bottom)
			)
		)
		(fp_text user "${REFERENCE}"
			(at -0.939 4.599 0)
			(layer "F.Fab")
			(effects
				(font
					(size 0.7 0.7)
					(thickness 0.15)
				)
				(justify left bottom)
			)
		)
		(pad "1" smd roundrect
			(at -0.48 0)
			(size 0.59 0.64)
			(layers "F.Cu" "F.Mask" "F.Paste")
			(roundrect_rratio 0.25)
			(net 640 "/Expansion connector/DP2.TX3+")
			(pintype "passive")
		)
		(pad "2" smd roundrect
			(at 0.48 0)
			(size 0.59 0.64)
			(layers "F.Cu" "F.Mask" "F.Paste")
			(roundrect_rratio 0.25)
			(net 1257 "/SoM_IO2/DP2.TX3_C+")
			(pintype "passive")
		)
	)
	(footprint "antmicro-footprints:R_0402_1005Metric"
		(layer "F.Cu")
		(at 111.22 61.79 90)
		(descr "Resistor SMD 0402")
		(tags "resistor SMD 0402")
		(property "Reference" "R68"
			(at -4.89 0.14 90)
			(layer "F.SilkS")
			(effects
				(font
					(size 0.7 0.7)
					(thickness 0.15)
				)
				(justify left bottom)
			)
		)
		(property "Value" "R_10k_0402"
			(at -1.011843 1.772046 90)
			(layer "F.Fab")
			(effects
				(font
					(size 0.7 0.7)
					(thickness 0.15)
				)
				(justify left bottom)
			)
		)
		(property "Datasheet" "https://www.bourns.com/docs/product-datasheets/cr.pdf"
			(at 0 0 90)
			(layer "F.Fab")
			(hide yes)
			(effects
				(font
					(size 1.27 1.27)
					(thickness 0.15)
				)
			)
		)
		(property "Description" "SMD Chip Resistor, 10 kohm, ± 1%, 62.5 mW, 0402 [1005 Metric], Thick Film, General Purpose"
			(at 0 0 90)
			(layer "F.Fab")
			(hide yes)
			(effects
				(font
					(size 1.27 1.27)
					(thickness 0.15)
				)
			)
		)
		(property "Manufacturer" "Bourns"
			(at 0 0 90)
			(unlocked yes)
			(layer "F.Fab")
			(hide yes)
			(effects
				(font
					(size 1 1)
					(thickness 0.15)
				)
			)
		)
		(property "MPN" "CR0402-FX-1002GLF"
			(at 0 0 90)
			(unlocked yes)
			(layer "F.Fab")
			(hide yes)
			(effects
				(font
					(size 1 1)
					(thickness 0.15)
				)
			)
		)
		(property "Val" "10k"
			(at 0 0 90)
			(unlocked yes)
			(layer "F.Fab")
			(hide yes)
			(effects
				(font
					(size 1 1)
					(thickness 0.15)
				)
			)
		)
		(property "License" "Apache-2.0"
			(at 0 0 90)
			(unlocked yes)
			(layer "F.Fab")
			(hide yes)
			(effects
				(font
					(size 1 1)
					(thickness 0.15)
				)
			)
		)
		(property "Author" "Antmicro"
			(at 0 0 90)
			(unlocked yes)
			(layer "F.Fab")
			(hide yes)
			(effects
				(font
					(size 1 1)
					(thickness 0.15)
				)
			)
		)
		(property "Tolerance" "1%"
			(at 0 0 90)
			(unlocked yes)
			(layer "F.Fab")
			(hide yes)
			(effects
				(font
					(size 1 1)
					(thickness 0.15)
				)
			)
		)
		(sheetname "/SoM_Power/")
		(sheetfile "som_power.kicad_sch")
		(attr smd)
		(fp_poly
			(pts
				(xy -0.925 -0.47) (xy 0.925 -0.47) (xy 0.925 0.47) (xy -0.925 0.47)
			)
			(stroke
				(width 0.05)
				(type default)
			)
			(fill no)
			(layer "F.CrtYd")
		)
		(fp_poly
			(pts
				(xy -0.5 -0.25) (xy 0.5 -0.25) (xy 0.5 0.25) (xy -0.5 0.25)
			)
			(stroke
				(width 0.15)
				(type solid)
			)
			(fill no)
			(layer "F.Fab")
		)
		(fp_text user "License: Apache-2.0"
			(at -0.949999 5.169 90)
			(layer "F.Fab")
			(effects
				(font
					(size 0.7 0.7)
					(thickness 0.15)
				)
				(justify left bottom)
			)
		)
		(fp_text user "${REFERENCE}"
			(at -0.95 3.168 90)
			(layer "F.Fab")
			(effects
				(font
					(size 0.7 0.7)
					(thickness 0.15)
				)
				(justify left bottom)
			)
		)
		(fp_text user "Author: Antmicro"
			(at -0.95 4.169 90)
			(layer "F.Fab")
			(effects
				(font
					(size 0.7 0.7)
					(thickness 0.15)
				)
				(justify left bottom)
			)
		)
		(pad "1" smd roundrect
			(at -0.48 0 90)
			(size 0.59 0.64)
			(layers "F.Cu" "F.Mask" "F.Paste")
			(roundrect_rratio 0.25)
			(net 1392 "Net-(Q6-D)")
			(pintype "passive")
		)
		(pad "2" smd roundrect
			(at 0.48 0 90)
			(size 0.59 0.64)
			(layers "F.Cu" "F.Mask" "F.Paste")
			(roundrect_rratio 0.25)
			(net 491 "+5V_AON")
			(pintype "passive")
		)
	)
	(footprint "antmicro-footprints:SOT-523"
		(layer "F.Cu")
		(at 70.75 55.75)
		(property "Reference" "Q20"
			(at 3.25 -1.45 0)
			(layer "F.SilkS")
			(effects
				(font
					(size 0.7 0.7)
					(thickness 0.15)
				)
				(justify right top)
			)
		)
		(property "Value" "DMG1012T-7"
			(at 0.1 1.824 0)
			(layer "F.Fab")
			(effects
				(font
					(size 0.7 0.7)
					(thickness 0.15)
				)
				(justify left bottom)
			)
		)
		(property "Datasheet" "https://www.diodes.com/assets/Datasheets/ds31783.pdf"
			(at 0 0 0)
			(layer "F.Fab")
			(hide yes)
			(effects
				(font
					(size 1.27 1.27)
					(thickness 0.15)
				)
			)
		)
		(property "Description" "Power MOSFET, N Channel, 20 V, 630 mA, 0.3 ohm, SOT-523, Surface Mount"
			(at 0 0 0)
			(layer "F.Fab")
			(hide yes)
			(effects
				(font
					(size 1.27 1.27)
					(thickness 0.15)
				)
			)
		)
		(property "MPN" "DMG1012T-7"
			(at 0 0 0)
			(unlocked yes)
			(layer "F.Fab")
			(hide yes)
			(effects
				(font
					(size 1 1)
					(thickness 0.15)
				)
			)
		)
		(property "Manufacturer" "Diodes Incorporated"
			(at 0 0 0)
			(unlocked yes)
			(layer "F.Fab")
			(hide yes)
			(effects
				(font
					(size 1 1)
					(thickness 0.15)
				)
			)
		)
		(property "Author" "Antmicro"
			(at 0 0 0)
			(unlocked yes)
			(layer "F.Fab")
			(hide yes)
			(effects
				(font
					(size 1 1)
					(thickness 0.15)
				)
			)
		)
		(property "License" "Apache-2.0"
			(at 0 0 0)
			(unlocked yes)
			(layer "F.Fab")
			(hide yes)
			(effects
				(font
					(size 1 1)
					(thickness 0.15)
				)
			)
		)
		(sheetname "/SoM_Power/")
		(sheetfile "som_power.kicad_sch")
		(attr smd)
		(fp_line
			(start -0.927 -0.351)
			(end -0.725 -0.551)
			(stroke
				(width 0.15)
				(type solid)
			)
			(layer "F.SilkS")
		)
		(fp_line
			(start -0.927 -0.051)
			(end -0.927 -0.351)
			(stroke
				(width 0.15)
				(type solid)
			)
			(layer "F.SilkS")
		)
		(fp_line
			(start -0.725 -0.551)
			(end -0.277 -0.551)
			(stroke
				(width 0.15)
				(type solid)
			)
			(layer "F.SilkS")
		)
		(fp_line
			(start -0.277 -0.551)
			(end -0.277 -0.75)
			(stroke
				(width 0.15)
				(type solid)
			)
			(layer "F.SilkS")
		)
		(fp_circle
			(center -0.9652 0.9652)
			(end -0.9152 0.9652)
			(stroke
				(width 0.15)
				(type solid)
			)
			(fill yes)
			(layer "F.SilkS")
		)
		(fp_line
			(start -1.12 -1.16)
			(end -1.12 1.15)
			(stroke
				(width 0.05)
				(type solid)
			)
			(layer "F.CrtYd")
		)
		(fp_line
			(start -1.12 -1.16)
			(end 1.1 -1.16)
			(stroke
				(width 0.05)
				(type solid)
			)
			(layer "F.CrtYd")
		)
		(fp_line
			(start -1.12 1.15)
			(end 1.1 1.15)
			(stroke
				(width 0.05)
				(type solid)
			)
			(layer "F.CrtYd")
		)
		(fp_line
			(start 1.1 -1.16)
			(end 1.1 1.15)
			(stroke
				(width 0.05)
				(type solid)
			)
			(layer "F.CrtYd")
		)
		(fp_line
			(start -0.802 -0.276)
			(end -0.802 0.424)
			(stroke
				(width 0.15)
				(type solid)
			)
			(layer "F.Fab")
		)
		(fp_line
			(start -0.652 -0.425)
			(end -0.802 -0.276)
			(stroke
				(width 0.15)
				(type solid)
			)
			(layer "F.Fab")
		)
		(fp_line
			(start 0.8 -0.425)
			(end -0.652 -0.425)
			(stroke
				(width 0.15)
				(type solid)
			)
			(layer "F.Fab")
		)
		(fp_line
			(start 0.8 -0.425)
			(end 0.8 0.424)
			(stroke
				(width 0.15)
				(type solid)
			)
			(layer "F.Fab")
		)
		(fp_line
			(start 0.8 0.424)
			(end -0.802 0.424)
			(stroke
				(width 0.15)
				(type solid)
			)
			(layer "F.Fab")
		)
		(fp_circle
			(center -0.9652 0.9652)
			(end -0.9144 0.9652)
			(stroke
				(width 0.15)
				(type solid)
			)
			(fill no)
			(layer "F.Fab")
		)
		(fp_text user "Author: Antmicro"
			(at -1.12 6.224 0)
			(layer "F.Fab")
			(effects
				(font
					(size 0.7 0.7)
					(thickness 0.15)
				)
				(justify left bottom)
			)
		)
		(fp_text user "License: Apache-2.0"
			(at -1.12 5.024 0)
			(layer "F.Fab")
			(effects
				(font
					(size 0.7 0.7)
					(thickness 0.15)
				)
				(justify left bottom)
			)
		)
		(fp_text user "${REFERENCE}"
			(at -1.12 3.824 0)
			(layer "F.Fab")
			(effects
				(font
					(size 0.7 0.7)
					(thickness 0.15)
				)
				(justify left bottom)
			)
		)
		(pad "1" smd rect
			(at -0.5 0.65)
			(size 0.4 0.51)
			(layers "F.Cu" "F.Mask" "F.Paste")
			(net 1285 "/SoM_Power/VIN_PWR_ON")
			(pinfunction "G")
			(pintype "input")
		)
		(pad "2" smd rect
			(at 0.498 0.65)
			(size 0.4 0.51)
			(layers "F.Cu" "F.Mask" "F.Paste")
			(net 1 "GND")
			(pinfunction "S")
			(pintype "passive")
		)
		(pad "3" smd rect
			(at 0 -0.652)
			(size 0.4 0.51)
			(layers "F.Cu" "F.Mask" "F.Paste")
			(net 550 "Net-(D52-C)")
			(pinfunction "D")
			(pintype "passive")
		)
	)
	(footprint "antmicro-footprints:C_0805_2012Metric"
		(layer "F.Cu")
		(at 170.9 142.39 90)
		(descr "Capacitor SMD 0805")
		(tags "capacitor SMD 0805")
		(property "Reference" "C28"
			(at 1.99 -1.2 180)
			(layer "F.SilkS")
			(effects
				(font
					(size 0.7 0.7)
					(thickness 0.15)
				)
				(justify left bottom)
			)
		)
		(property "Value" "C_22u_25V_0805"
			(at -2.055717 1.963152 90)
			(layer "F.Fab")
			(effects
				(font
					(size 0.7 0.7)
					(thickness 0.15)
				)
				(justify left bottom)
			)
		)
		(property "Datasheet" "https://product.samsungsem.com/mlcc/CL21A226MAYNNN.do"
			(at 0 0 90)
			(layer "F.Fab")
			(hide yes)
			(effects
				(font
					(size 1.27 1.27)
					(thickness 0.15)
				)
			)
		)
		(property "Description" "SMT Multilayer Ceramic Capacitor, 22uF, +/-20%, 25V, X5R, 0805 [2012 Metric]"
			(at 0 0 90)
			(layer "F.Fab")
			(hide yes)
			(effects
				(font
					(size 1.27 1.27)
					(thickness 0.15)
				)
			)
		)
		(property "Manufacturer" "Samsung Electro-Mechanics"
			(at 0 0 90)
			(unlocked yes)
			(layer "F.Fab")
			(hide yes)
			(effects
				(font
					(size 1 1)
					(thickness 0.15)
				)
			)
		)
		(property "MPN" "CL21A226MAYNNNE"
			(at 0 0 90)
			(unlocked yes)
			(layer "F.Fab")
			(hide yes)
			(effects
				(font
					(size 1 1)
					(thickness 0.15)
				)
			)
		)
		(property "Val" "22u"
			(at 0 0 90)
			(unlocked yes)
			(layer "F.Fab")
			(hide yes)
			(effects
				(font
					(size 1 1)
					(thickness 0.15)
				)
			)
		)
		(property "License" "Apache-2.0"
			(at 0 0 90)
			(unlocked yes)
			(layer "F.Fab")
			(hide yes)
			(effects
				(font
					(size 1 1)
					(thickness 0.15)
				)
			)
		)
		(property "Author" "Antmicro"
			(at 0 0 90)
			(unlocked yes)
			(layer "F.Fab")
			(hide yes)
			(effects
				(font
					(size 1 1)
					(thickness 0.15)
				)
			)
		)
		(property "Voltage" "25V"
			(at 0 0 90)
			(unlocked yes)
			(layer "F.Fab")
			(hide yes)
			(effects
				(font
					(size 1 1)
					(thickness 0.15)
				)
			)
		)
		(property "Dielectric" "X5R"
			(at 0 0 90)
			(unlocked yes)
			(layer "F.Fab")
			(hide yes)
			(effects
				(font
					(size 1 1)
					(thickness 0.15)
				)
			)
		)
		(property "Public" "False"
			(at 0 0 90)
			(unlocked yes)
			(layer "F.Fab")
			(hide yes)
			(effects
				(font
					(size 1 1)
					(thickness 0.15)
				)
			)
		)
		(sheetname "/DCDC/")
		(sheetfile "dcdc.kicad_sch")
		(attr smd)
		(fp_line
			(start -0.3 -0.7)
			(end 0.3 -0.7)
			(stroke
				(width 0.15)
				(type solid)
			)
			(layer "F.SilkS")
		)
		(fp_line
			(start -0.3 0.7)
			(end 0.3 0.7)
			(stroke
				(width 0.15)
				(type solid)
			)
			(layer "F.SilkS")
		)
		(fp_rect
			(start 1.95 -0.9)
			(end -1.95 0.9)
			(stroke
				(width 0.05)
				(type default)
			)
			(fill no)
			(layer "F.CrtYd")
		)
		(fp_rect
			(start -0.95 -0.675)
			(end 0.95 0.675)
			(stroke
				(width 0.15)
				(type solid)
			)
			(fill no)
			(layer "F.Fab")
		)
		(fp_text user "License: Apache-2.0"
			(at -1.9 4.947 90)
			(layer "F.Fab")
			(effects
				(font
					(size 0.7 0.7)
					(thickness 0.15)
				)
				(justify left bottom)
			)
		)
		(fp_text user "${REFERENCE}"
			(at -1.9 3.947 90)
			(layer "F.Fab")
			(effects
				(font
					(size 0.7 0.7)
					(thickness 0.15)
				)
				(justify left bottom)
			)
		)
		(fp_text user "Author: Antmicro"
			(at -1.9 5.947 90)
			(layer "F.Fab")
			(effects
				(font
					(size 0.7 0.7)
					(thickness 0.15)
				)
				(justify left bottom)
			)
		)
		(pad "1" smd roundrect
			(at -1.1 0 90)
			(size 1.2 1.3)
			(layers "F.Cu" "F.Mask" "F.Paste")
			(roundrect_rratio 0.25)
			(net 1 "GND")
			(pintype "passive")
		)
		(pad "2" smd roundrect
			(at 1.1 0 90)
			(size 1.2 1.3)
			(layers "F.Cu" "F.Mask" "F.Paste")
			(roundrect_rratio 0.25)
			(net 13 "VCC")
			(pintype "passive")
		)
	)
	(footprint "antmicro-footprints:QFN-2L_1.6x1x0.55mm"
		(layer "F.Cu")
		(at 167.6 142.3 90)
		(property "Reference" "D64"
			(at -1.1 1.5 90)
			(layer "F.SilkS")
			(effects
				(font
					(size 0.7 0.7)
					(thickness 0.15)
				)
				(justify left bottom)
			)
		)
		(property "Value" "ESDA25P35-1U1M"
			(at 0 1.7 90)
			(layer "F.Fab")
			(effects
				(font
					(size 0.7 0.7)
					(thickness 0.15)
				)
				(justify left bottom)
			)
		)
		(property "Datasheet" "https://www.st.com/resource/en/datasheet/esda25p35-1u1m.pdf"
			(at 0 0 90)
			(layer "F.Fab")
			(hide yes)
			(effects
				(font
					(size 1.27 1.27)
					(thickness 0.15)
				)
			)
		)
		(property "Description" "Unidirectional TVS, 30 kV, QFN-2L, 22 V, 195 pF"
			(at 0 0 90)
			(layer "F.Fab")
			(hide yes)
			(effects
				(font
					(size 1.27 1.27)
					(thickness 0.15)
				)
			)
		)
		(property "MPN" "ESDA25P35-1U1M"
			(at 0 0 90)
			(unlocked yes)
			(layer "F.Fab")
			(hide yes)
			(effects
				(font
					(size 1 1)
					(thickness 0.15)
				)
			)
		)
		(property "Manufacturer" "STMicroelectronics"
			(at 0 0 90)
			(unlocked yes)
			(layer "F.Fab")
			(hide yes)
			(effects
				(font
					(size 1 1)
					(thickness 0.15)
				)
			)
		)
		(property "Author" "Antmicro"
			(at 0 0 90)
			(unlocked yes)
			(layer "F.Fab")
			(hide yes)
			(effects
				(font
					(size 1 1)
					(thickness 0.15)
				)
			)
		)
		(property "License" "Apache-2.0"
			(at 0 0 90)
			(unlocked yes)
			(layer "F.Fab")
			(hide yes)
			(effects
				(font
					(size 1 1)
					(thickness 0.15)
				)
			)
		)
		(sheetname "/Peripherals/")
		(sheetfile "peripherals.kicad_sch")
		(attr smd)
		(fp_line
			(start 0.23 -0.45)
			(end -0.23 -0.45)
			(stroke
				(width 0.15)
				(type solid)
			)
			(layer "F.SilkS")
		)
		(fp_line
			(start -1.2 -0.4)
			(end -1.2 0.4)
			(stroke
				(width 0.15)
				(type solid)
			)
			(layer "F.SilkS")
		)
		(fp_line
			(start 0.23 0.45)
			(end -0.23 0.45)
			(stroke
				(width 0.15)
				(type solid)
			)
			(layer "F.SilkS")
		)
		(fp_rect
			(start 1.25 0.65)
			(end -1.25 -0.65)
			(stroke
				(width 0.05)
				(type solid)
			)
			(fill no)
			(layer "F.CrtYd")
		)
		(fp_line
			(start 0.201 -0.202)
			(end -0.101 0)
			(stroke
				(width 0.15)
				(type solid)
			)
			(layer "F.Fab")
		)
		(fp_line
			(start -0.199 -0.202)
			(end -0.199 0.1)
			(stroke
				(width 0.15)
				(type solid)
			)
			(layer "F.Fab")
		)
		(fp_line
			(start 0.599 0)
			(end 0.201 0)
			(stroke
				(width 0.15)
				(type solid)
			)
			(layer "F.Fab")
		)
		(fp_line
			(start 0.201 0)
			(end 0.201 -0.202)
			(stroke
				(width 0.15)
				(type solid)
			)
			(layer "F.Fab")
		)
		(fp_line
			(start -0.101 0)
			(end 0.201 0.2)
			(stroke
				(width 0.15)
				(type solid)
			)
			(layer "F.Fab")
		)
		(fp_line
			(start -0.199 0)
			(end -0.597 0)
			(stroke
				(width 0.15)
				(type solid)
			)
			(layer "F.Fab")
		)
		(fp_line
			(start 0.201 0.2)
			(end 0.201 0)
			(stroke
				(width 0.15)
				(type solid)
			)
			(layer "F.Fab")
		)
		(fp_line
			(start -0.199 0.2)
			(end -0.199 0.1)
			(stroke
				(width 0.15)
				(type solid)
			)
			(layer "F.Fab")
		)
		(fp_rect
			(start 0.848 0.4)
			(end -0.85 -0.402)
			(stroke
				(width 0.15)
				(type solid)
			)
			(fill no)
			(layer "F.Fab")
		)
		(fp_text user "${REFERENCE}"
			(at -1.31 3.769 90)
			(layer "F.Fab")
			(effects
				(font
					(size 0.7 0.7)
					(thickness 0.15)
				)
				(justify left bottom)
			)
		)
		(fp_text user "Author: Antmicro"
			(at -1.31 4.769 90)
			(layer "F.Fab")
			(effects
				(font
					(size 0.7 0.7)
					(thickness 0.15)
				)
				(justify left bottom)
			)
		)
		(fp_text user "License: Apache-2.0"
			(at -1.31 5.769 90)
			(layer "F.Fab")
			(effects
				(font
					(size 0.7 0.7)
					(thickness 0.15)
				)
				(justify left bottom)
			)
		)
		(pad "1" smd roundrect
			(at -0.7 0 270)
			(size 0.8 1)
			(layers "F.Cu" "F.Mask" "F.Paste")
			(roundrect_rratio 0.2)
			(net 634 "+12V")
			(pinfunction "C")
			(pintype "passive")
		)
		(pad "2" smd roundrect
			(at 0.7 0 270)
			(size 0.8 1)
			(layers "F.Cu" "F.Mask" "F.Paste")
			(roundrect_rratio 0.2)
			(net 1 "GND")
			(pinfunction "A")
			(pintype "passive")
		)
	)
	(footprint "antmicro-footprints:R_0402_1005Metric"
		(layer "F.Cu")
		(at 196.9 98.82 -90)
		(descr "Resistor SMD 0402")
		(tags "resistor SMD 0402")
		(property "Reference" "R388"
			(at -0.72 3.5 90)
			(layer "F.SilkS")
			(effects
				(font
					(size 0.7 0.7)
					(thickness 0.15)
				)
				(justify right top)
			)
		)
		(property "Value" "R_0R_0402"
			(at -1.011843 1.772047 90)
			(layer "F.Fab")
			(effects
				(font
					(size 0.7 0.7)
					(thickness 0.15)
				)
				(justify right top)
			)
		)
		(property "Datasheet" "https://industrial.panasonic.com/cdbs/www-data/pdf/RDA0000/AOA0000C301.pdf"
			(at 0 0 90)
			(layer "F.Fab")
			(hide yes)
			(effects
				(font
					(size 1.27 1.27)
					(thickness 0.15)
				)
			)
		)
		(property "Description" "SMD Chip Resistor, Jumper, 0 ohm, 100 mW, 0402 [1005 Metric], Thick Film, General Purpose"
			(at 0 0 90)
			(layer "F.Fab")
			(hide yes)
			(effects
				(font
					(size 1.27 1.27)
					(thickness 0.15)
				)
			)
		)
		(property "MPN" "ERJ2GE0R00X"
			(at 0 0 270)
			(unlocked yes)
			(layer "F.Fab")
			(hide yes)
			(effects
				(font
					(size 1 1)
					(thickness 0.15)
				)
			)
		)
		(property "Manufacturer" "Panasonic"
			(at 0 0 270)
			(unlocked yes)
			(layer "F.Fab")
			(hide yes)
			(effects
				(font
					(size 1 1)
					(thickness 0.15)
				)
			)
		)
		(property "License" "Apache-2.0"
			(at 0 0 270)
			(unlocked yes)
			(layer "F.Fab")
			(hide yes)
			(effects
				(font
					(size 1 1)
					(thickness 0.15)
				)
			)
		)
		(property "Author" "Antmicro"
			(at 0 0 270)
			(unlocked yes)
			(layer "F.Fab")
			(hide yes)
			(effects
				(font
					(size 1 1)
					(thickness 0.15)
				)
			)
		)
		(property "Val" "0R"
			(at 0 0 270)
			(unlocked yes)
			(layer "F.Fab")
			(hide yes)
			(effects
				(font
					(size 1 1)
					(thickness 0.15)
				)
			)
		)
		(property "Tolerance" "~"
			(at 0 0 270)
			(unlocked yes)
			(layer "F.Fab")
			(hide yes)
			(effects
				(font
					(size 1 1)
					(thickness 0.15)
				)
			)
		)
		(property "Current" "1A"
			(at 0 0 270)
			(unlocked yes)
			(layer "F.Fab")
			(hide yes)
			(effects
				(font
					(size 1 1)
					(thickness 0.15)
				)
			)
		)
		(sheetname "/USB Debug, PD/")
		(sheetfile "usb_debug_pd.kicad_sch")
		(attr smd exclude_from_pos_files exclude_from_bom dnp)
		(fp_rect
			(start -0.925 -0.47)
			(end 0.925 0.47)
			(stroke
				(width 0.05)
				(type default)
			)
			(fill no)
			(layer "F.CrtYd")
		)
		(fp_rect
			(start -0.5 -0.25)
			(end 0.5 0.25)
			(stroke
				(width 0.15)
				(type solid)
			)
			(fill no)
			(layer "F.Fab")
		)
		(fp_text user "License: Apache-2.0"
			(at -0.95 5.169 90)
			(layer "F.Fab")
			(effects
				(font
					(size 0.7 0.7)
					(thickness 0.15)
				)
				(justify right top)
			)
		)
		(fp_text user "Author: Antmicro"
			(at -0.95 4.169 90)
			(layer "F.Fab")
			(effects
				(font
					(size 0.7 0.7)
					(thickness 0.15)
				)
				(justify right top)
			)
		)
		(fp_text user "${REFERENCE}"
			(at -0.95 3.168 90)
			(layer "F.Fab")
			(effects
				(font
					(size 0.7 0.7)
					(thickness 0.15)
				)
				(justify right top)
			)
		)
		(pad "1" smd roundrect
			(at -0.48 0 270)
			(size 0.59 0.64)
			(layers "F.Cu" "F.Mask" "F.Paste")
			(roundrect_rratio 0.25)
			(net 811 "/USB Debug, PD/MOSI")
			(pintype "passive")
		)
		(pad "2" smd roundrect
			(at 0.48 0 270)
			(size 0.59 0.64)
			(layers "F.Cu" "F.Mask" "F.Paste")
			(roundrect_rratio 0.25)
			(net 850 "/I2C_{SYS}.SDA")
			(pintype "passive")
		)
	)
	(footprint "antmicro-footprints:R_0402_1005Metric"
		(layer "F.Cu")
		(at 147.8 119.2)
		(descr "Resistor SMD 0402")
		(tags "resistor SMD 0402")
		(property "Reference" "R373"
			(at -3.7 0.5 0)
			(layer "F.SilkS")
			(effects
				(font
					(size 0.7 0.7)
					(thickness 0.15)
				)
				(justify left bottom)
			)
		)
		(property "Value" "R_2k2_0402"
			(at -1.011843 1.772047 0)
			(layer "F.Fab")
			(effects
				(font
					(size 0.7 0.7)
					(thickness 0.15)
				)
				(justify left bottom)
			)
		)
		(property "Datasheet" "https://www.bourns.com/docs/product-datasheets/cr.pdf"
			(at 0 0 0)
			(layer "F.Fab")
			(hide yes)
			(effects
				(font
					(size 1.27 1.27)
					(thickness 0.15)
				)
			)
		)
		(property "Description" "SMD Chip Resistor, 2.2 kohm, ± 1%, 62.5 mW, 0402 [1005 Metric], Thick Film, General Purpose"
			(at 0 0 0)
			(layer "F.Fab")
			(hide yes)
			(effects
				(font
					(size 1.27 1.27)
					(thickness 0.15)
				)
			)
		)
		(property "MPN" "CR0402-FX-2201GLF"
			(at 0 0 0)
			(unlocked yes)
			(layer "F.Fab")
			(hide yes)
			(effects
				(font
					(size 1 1)
					(thickness 0.15)
				)
			)
		)
		(property "Manufacturer" "Bourns"
			(at 0 0 0)
			(unlocked yes)
			(layer "F.Fab")
			(hide yes)
			(effects
				(font
					(size 1 1)
					(thickness 0.15)
				)
			)
		)
		(property "License" "Apache-2.0"
			(at 0 0 0)
			(unlocked yes)
			(layer "F.Fab")
			(hide yes)
			(effects
				(font
					(size 1 1)
					(thickness 0.15)
				)
			)
		)
		(property "Author" "Antmicro"
			(at 0 0 0)
			(unlocked yes)
			(layer "F.Fab")
			(hide yes)
			(effects
				(font
					(size 1 1)
					(thickness 0.15)
				)
			)
		)
		(property "Val" "2k2"
			(at 0 0 0)
			(unlocked yes)
			(layer "F.Fab")
			(hide yes)
			(effects
				(font
					(size 1 1)
					(thickness 0.15)
				)
			)
		)
		(property "Tolerance" "1%"
			(at 0 0 0)
			(unlocked yes)
			(layer "F.Fab")
			(hide yes)
			(effects
				(font
					(size 1 1)
					(thickness 0.15)
				)
			)
		)
		(sheetname "/SoM_IO/")
		(sheetfile "som_io.kicad_sch")
		(attr smd)
		(fp_rect
			(start -0.925 -0.47)
			(end 0.925 0.47)
			(stroke
				(width 0.05)
				(type default)
			)
			(fill no)
			(layer "F.CrtYd")
		)
		(fp_rect
			(start -0.5 -0.25)
			(end 0.5 0.25)
			(stroke
				(width 0.15)
				(type solid)
			)
			(fill no)
			(layer "F.Fab")
		)
		(fp_text user "Author: Antmicro"
			(at -0.95 4.169 0)
			(layer "F.Fab")
			(effects
				(font
					(size 0.7 0.7)
					(thickness 0.15)
				)
				(justify left bottom)
			)
		)
		(fp_text user "License: Apache-2.0"
			(at -0.95 5.169 0)
			(layer "F.Fab")
			(effects
				(font
					(size 0.7 0.7)
					(thickness 0.15)
				)
				(justify left bottom)
			)
		)
		(fp_text user "${REFERENCE}"
			(at -0.95 3.168 0)
			(layer "F.Fab")
			(effects
				(font
					(size 0.7 0.7)
					(thickness 0.15)
				)
				(justify left bottom)
			)
		)
		(pad "1" smd roundrect
			(at -0.48 0)
			(size 0.59 0.64)
			(layers "F.Cu" "F.Mask" "F.Paste")
			(roundrect_rratio 0.25)
			(net 2 "+3V3")
			(pintype "passive")
		)
		(pad "2" smd roundrect
			(at 0.48 0)
			(size 0.59 0.64)
			(layers "F.Cu" "F.Mask" "F.Paste")
			(roundrect_rratio 0.25)
			(net 561 "/Expansion connector/I2C0.SDA")
			(pintype "passive")
		)
	)
	(footprint "antmicro-footprints:C_0402_1005Metric"
		(layer "F.Cu")
		(at 177.945 110.706 -90)
		(descr "Capacitor SMD 0402")
		(tags "capacitor SMD 0402")
		(property "Reference" "C48"
			(at -2.9 0.325 90)
			(layer "F.SilkS")
			(effects
				(font
					(size 0.7 0.7)
					(thickness 0.15)
				)
				(justify right top)
			)
		)
		(property "Value" "C_100n_0402"
			(at -1.022927 2.155213 90)
			(layer "F.Fab")
			(effects
				(font
					(size 0.7 0.7)
					(thickness 0.15)
				)
				(justify right top)
			)
		)
		(property "Datasheet" "https://www.murata.com/products/productdetail?partno=GRM155R61H104KE14%23"
			(at 0 0 90)
			(layer "F.Fab")
			(hide yes)
			(effects
				(font
					(size 1.27 1.27)
					(thickness 0.15)
				)
			)
		)
		(property "Description" "SMD Multilayer Ceramic Capacitor, 0.1 µF, 50 V, 0402 [1005 Metric], ± 10%, X5R, GRM Series"
			(at 0 0 90)
			(layer "F.Fab")
			(hide yes)
			(effects
				(font
					(size 1.27 1.27)
					(thickness 0.15)
				)
			)
		)
		(property "Manufacturer" "Murata"
			(at 0 0 270)
			(unlocked yes)
			(layer "F.Fab")
			(hide yes)
			(effects
				(font
					(size 1 1)
					(thickness 0.15)
				)
			)
		)
		(property "MPN" "GRM155R61H104KE14D"
			(at 0 0 270)
			(unlocked yes)
			(layer "F.Fab")
			(hide yes)
			(effects
				(font
					(size 1 1)
					(thickness 0.15)
				)
			)
		)
		(property "Val" "100n"
			(at 0 0 270)
			(unlocked yes)
			(layer "F.Fab")
			(hide yes)
			(effects
				(font
					(size 1 1)
					(thickness 0.15)
				)
			)
		)
		(property "License" "Apache-2.0"
			(at 0 0 270)
			(unlocked yes)
			(layer "F.Fab")
			(hide yes)
			(effects
				(font
					(size 1 1)
					(thickness 0.15)
				)
			)
		)
		(property "Author" "Antmicro"
			(at 0 0 270)
			(unlocked yes)
			(layer "F.Fab")
			(hide yes)
			(effects
				(font
					(size 1 1)
					(thickness 0.15)
				)
			)
		)
		(property "Voltage" "50V"
			(at 0 0 270)
			(unlocked yes)
			(layer "F.Fab")
			(hide yes)
			(effects
				(font
					(size 1 1)
					(thickness 0.15)
				)
			)
		)
		(property "Dielectric" "X5R"
			(at 0 0 270)
			(unlocked yes)
			(layer "F.Fab")
			(hide yes)
			(effects
				(font
					(size 1 1)
					(thickness 0.15)
				)
			)
		)
		(sheetname "/DCDC/")
		(sheetfile "dcdc.kicad_sch")
		(attr smd)
		(fp_rect
			(start -0.925 -0.47)
			(end 0.925 0.47)
			(stroke
				(width 0.05)
				(type default)
			)
			(fill no)
			(layer "F.CrtYd")
		)
		(fp_line
			(start -0.494 0.248)
			(end -0.494 -0.25)
			(stroke
				(width 0.15)
				(type solid)
			)
			(layer "F.Fab")
		)
		(fp_line
			(start 0.504 0.248)
			(end -0.494 0.248)
			(stroke
				(width 0.15)
				(type solid)
			)
			(layer "F.Fab")
		)
		(fp_line
			(start -0.494 -0.25)
			(end 0.504 -0.25)
			(stroke
				(width 0.15)
				(type solid)
			)
			(layer "F.Fab")
		)
		(fp_line
			(start 0.504 -0.25)
			(end 0.504 0.248)
			(stroke
				(width 0.15)
				(type solid)
			)
			(layer "F.Fab")
		)
		(fp_text user "License: Apache-2.0"
			(at -0.939 5.799 90)
			(layer "F.Fab")
			(effects
				(font
					(size 0.7 0.7)
					(thickness 0.15)
				)
				(justify right top)
			)
		)
		(fp_text user "${REFERENCE}"
			(at -0.939 4.599 90)
			(layer "F.Fab")
			(effects
				(font
					(size 0.7 0.7)
					(thickness 0.15)
				)
				(justify right top)
			)
		)
		(fp_text user "Author: Antmicro"
			(at -0.939 3.399 90)
			(layer "F.Fab")
			(effects
				(font
					(size 0.7 0.7)
					(thickness 0.15)
				)
				(justify right top)
			)
		)
		(pad "1" smd roundrect
			(at -0.48 0 270)
			(size 0.59 0.64)
			(layers "F.Cu" "F.Mask" "F.Paste")
			(roundrect_rratio 0.25)
			(net 13 "VCC")
			(pintype "passive")
		)
		(pad "2" smd roundrect
			(at 0.48 0 270)
			(size 0.59 0.64)
			(layers "F.Cu" "F.Mask" "F.Paste")
			(roundrect_rratio 0.25)
			(net 1 "GND")
			(pintype "passive")
		)
	)
	(footprint "antmicro-footprints:C_0402_1005Metric"
		(layer "F.Cu")
		(at 97.95 56.37 -90)
		(descr "Capacitor SMD 0402")
		(tags "capacitor SMD 0402")
		(property "Reference" "C41"
			(at -1.12 -0.6 90)
			(layer "F.SilkS")
			(effects
				(font
					(size 0.7 0.7)
					(thickness 0.15)
				)
				(justify right top)
			)
		)
		(property "Value" "C_100n_0402"
			(at -1.022927 2.155213 90)
			(layer "F.Fab")
			(effects
				(font
					(size 0.7 0.7)
					(thickness 0.15)
				)
				(justify right top)
			)
		)
		(property "Datasheet" "https://www.murata.com/products/productdetail?partno=GRM155R61H104KE14%23"
			(at 0 0 90)
			(layer "F.Fab")
			(hide yes)
			(effects
				(font
					(size 1.27 1.27)
					(thickness 0.15)
				)
			)
		)
		(property "Description" "SMD Multilayer Ceramic Capacitor, 0.1 µF, 50 V, 0402 [1005 Metric], ± 10%, X5R, GRM Series"
			(at 0 0 90)
			(layer "F.Fab")
			(hide yes)
			(effects
				(font
					(size 1.27 1.27)
					(thickness 0.15)
				)
			)
		)
		(property "MPN" "GRM155R61H104KE14D"
			(at 0 0 270)
			(unlocked yes)
			(layer "F.Fab")
			(hide yes)
			(effects
				(font
					(size 1 1)
					(thickness 0.15)
				)
			)
		)
		(property "Manufacturer" "Murata"
			(at 0 0 270)
			(unlocked yes)
			(layer "F.Fab")
			(hide yes)
			(effects
				(font
					(size 1 1)
					(thickness 0.15)
				)
			)
		)
		(property "License" "Apache-2.0"
			(at 0 0 270)
			(unlocked yes)
			(layer "F.Fab")
			(hide yes)
			(effects
				(font
					(size 1 1)
					(thickness 0.15)
				)
			)
		)
		(property "Author" "Antmicro"
			(at 0 0 270)
			(unlocked yes)
			(layer "F.Fab")
			(hide yes)
			(effects
				(font
					(size 1 1)
					(thickness 0.15)
				)
			)
		)
		(property "Val" "100n"
			(at 0 0 270)
			(unlocked yes)
			(layer "F.Fab")
			(hide yes)
			(effects
				(font
					(size 1 1)
					(thickness 0.15)
				)
			)
		)
		(property "Voltage" "50V"
			(at 0 0 270)
			(unlocked yes)
			(layer "F.Fab")
			(hide yes)
			(effects
				(font
					(size 1 1)
					(thickness 0.15)
				)
			)
		)
		(property "Dielectric" "X5R"
			(at 0 0 270)
			(unlocked yes)
			(layer "F.Fab")
			(hide yes)
			(effects
				(font
					(size 1 1)
					(thickness 0.15)
				)
			)
		)
		(sheetname "/SoM_Power/")
		(sheetfile "som_power.kicad_sch")
		(attr smd)
		(fp_rect
			(start -0.925 -0.47)
			(end 0.925 0.47)
			(stroke
				(width 0.05)
				(type default)
			)
			(fill no)
			(layer "F.CrtYd")
		)
		(fp_line
			(start -0.494 0.248)
			(end -0.494 -0.25)
			(stroke
				(width 0.15)
				(type solid)
			)
			(layer "F.Fab")
		)
		(fp_line
			(start 0.504 0.248)
			(end -0.494 0.248)
			(stroke
				(width 0.15)
				(type solid)
			)
			(layer "F.Fab")
		)
		(fp_line
			(start -0.494 -0.25)
			(end 0.504 -0.25)
			(stroke
				(width 0.15)
				(type solid)
			)
			(layer "F.Fab")
		)
		(fp_line
			(start 0.504 -0.25)
			(end 0.504 0.248)
			(stroke
				(width 0.15)
				(type solid)
			)
			(layer "F.Fab")
		)
		(fp_text user "${REFERENCE}"
			(at -0.939 4.599 90)
			(layer "F.Fab")
			(effects
				(font
					(size 0.7 0.7)
					(thickness 0.15)
				)
				(justify right top)
			)
		)
		(fp_text user "License: Apache-2.0"
			(at -0.939 5.799 90)
			(layer "F.Fab")
			(effects
				(font
					(size 0.7 0.7)
					(thickness 0.15)
				)
				(justify right top)
			)
		)
		(fp_text user "Author: Antmicro"
			(at -0.939 3.399 90)
			(layer "F.Fab")
			(effects
				(font
					(size 0.7 0.7)
					(thickness 0.15)
				)
				(justify right top)
			)
		)
		(pad "1" smd roundrect
			(at -0.48 0 270)
			(size 0.59 0.64)
			(layers "F.Cu" "F.Mask" "F.Paste")
			(roundrect_rratio 0.25)
			(net 1 "GND")
			(pintype "passive")
		)
		(pad "2" smd roundrect
			(at 0.48 0 270)
			(size 0.59 0.64)
			(layers "F.Cu" "F.Mask" "F.Paste")
			(roundrect_rratio 0.25)
			(net 4 "+3V3_AON")
			(pintype "passive")
		)
	)
	(footprint "antmicro-footprints:R_0402_1005Metric"
		(layer "F.Cu")
		(at 63.839 58.171 90)
		(descr "Resistor SMD 0402")
		(tags "resistor SMD 0402")
		(property "Reference" "R163"
			(at -1.429 -1.539 90)
			(layer "F.SilkS")
			(effects
				(font
					(size 0.7 0.7)
					(thickness 0.15)
				)
				(justify left bottom)
			)
		)
		(property "Value" "R_0R_0402"
			(at -1.011843 1.772047 90)
			(layer "F.Fab")
			(effects
				(font
					(size 0.7 0.7)
					(thickness 0.15)
				)
				(justify left bottom)
			)
		)
		(property "Datasheet" "https://industrial.panasonic.com/cdbs/www-data/pdf/RDA0000/AOA0000C301.pdf"
			(at 0 0 90)
			(layer "F.Fab")
			(hide yes)
			(effects
				(font
					(size 1.27 1.27)
					(thickness 0.15)
				)
			)
		)
		(property "Description" "SMD Chip Resistor, Jumper, 0 ohm, 100 mW, 0402 [1005 Metric], Thick Film, General Purpose"
			(at 0 0 90)
			(layer "F.Fab")
			(hide yes)
			(effects
				(font
					(size 1.27 1.27)
					(thickness 0.15)
				)
			)
		)
		(property "Manufacturer" "Panasonic"
			(at 0 0 90)
			(unlocked yes)
			(layer "F.Fab")
			(hide yes)
			(effects
				(font
					(size 1 1)
					(thickness 0.15)
				)
			)
		)
		(property "MPN" "ERJ2GE0R00X"
			(at 0 0 90)
			(unlocked yes)
			(layer "F.Fab")
			(hide yes)
			(effects
				(font
					(size 1 1)
					(thickness 0.15)
				)
			)
		)
		(property "Val" "0R"
			(at 0 0 90)
			(unlocked yes)
			(layer "F.Fab")
			(hide yes)
			(effects
				(font
					(size 1 1)
					(thickness 0.15)
				)
			)
		)
		(property "License" "Apache-2.0"
			(at 0 0 90)
			(unlocked yes)
			(layer "F.Fab")
			(hide yes)
			(effects
				(font
					(size 1 1)
					(thickness 0.15)
				)
			)
		)
		(property "Author" "Antmicro"
			(at 0 0 90)
			(unlocked yes)
			(layer "F.Fab")
			(hide yes)
			(effects
				(font
					(size 1 1)
					(thickness 0.15)
				)
			)
		)
		(property "Tolerance" "~"
			(at 0 0 90)
			(unlocked yes)
			(layer "F.Fab")
			(hide yes)
			(effects
				(font
					(size 1 1)
					(thickness 0.15)
				)
			)
		)
		(property "Current" "1A"
			(at 0 0 90)
			(unlocked yes)
			(layer "F.Fab")
			(hide yes)
			(effects
				(font
					(size 1 1)
					(thickness 0.15)
				)
			)
		)
		(sheetname "/CSI/")
		(sheetfile "csi.kicad_sch")
		(attr smd)
		(fp_rect
			(start -0.925 -0.47)
			(end 0.925 0.47)
			(stroke
				(width 0.05)
				(type default)
			)
			(fill no)
			(layer "F.CrtYd")
		)
		(fp_rect
			(start -0.5 -0.25)
			(end 0.5 0.25)
			(stroke
				(width 0.15)
				(type solid)
			)
			(fill no)
			(layer "F.Fab")
		)
		(fp_text user "Author: Antmicro"
			(at -0.95 4.169 90)
			(layer "F.Fab")
			(effects
				(font
					(size 0.7 0.7)
					(thickness 0.15)
				)
				(justify left bottom)
			)
		)
		(fp_text user "${REFERENCE}"
			(at -0.95 3.168 90)
			(layer "F.Fab")
			(effects
				(font
					(size 0.7 0.7)
					(thickness 0.15)
				)
				(justify left bottom)
			)
		)
		(fp_text user "License: Apache-2.0"
			(at -0.95 5.169 90)
			(layer "F.Fab")
			(effects
				(font
					(size 0.7 0.7)
					(thickness 0.15)
				)
				(justify left bottom)
			)
		)
		(pad "1" smd roundrect
			(at -0.48 0 90)
			(size 0.59 0.64)
			(layers "F.Cu" "F.Mask" "F.Paste")
			(roundrect_rratio 0.25)
			(net 984 "/CSI/I2C_MUX_SCL")
			(pintype "passive")
		)
		(pad "2" smd roundrect
			(at 0.48 0 90)
			(size 0.59 0.64)
			(layers "F.Cu" "F.Mask" "F.Paste")
			(roundrect_rratio 0.25)
			(net 983 "/CSI/I2C_{CAM}.SCL")
			(pintype "passive")
		)
	)
	(footprint "antmicro-footprints:R_0402_1005Metric"
		(layer "F.Cu")
		(at 180.554468 86.725 -90)
		(descr "Resistor SMD 0402")
		(tags "resistor SMD 0402")
		(property "Reference" "R41"
			(at -2.96 0.32 90)
			(layer "F.SilkS")
			(effects
				(font
					(size 0.7 0.7)
					(thickness 0.15)
				)
				(justify right top)
			)
		)
		(property "Value" "R_200k_0402"
			(at -1.011843 1.772047 90)
			(layer "F.Fab")
			(effects
				(font
					(size 0.7 0.7)
					(thickness 0.15)
				)
				(justify right top)
			)
		)
		(property "Datasheet" "https://www.bourns.com/docs/product-datasheets/cr.pdf"
			(at 0 0 90)
			(layer "F.Fab")
			(hide yes)
			(effects
				(font
					(size 1.27 1.27)
					(thickness 0.15)
				)
			)
		)
		(property "Description" "SMD Chip Resistor, 200 kohm, ± 1%, 62.5 mW, 0402 [1005 Metric], Thick Film, General Purpose"
			(at 0 0 90)
			(layer "F.Fab")
			(hide yes)
			(effects
				(font
					(size 1.27 1.27)
					(thickness 0.15)
				)
			)
		)
		(property "MPN" "CR0402-FX-2003GLF"
			(at 0 0 270)
			(unlocked yes)
			(layer "F.Fab")
			(hide yes)
			(effects
				(font
					(size 1 1)
					(thickness 0.15)
				)
			)
		)
		(property "Manufacturer" "Bourns"
			(at 0 0 270)
			(unlocked yes)
			(layer "F.Fab")
			(hide yes)
			(effects
				(font
					(size 1 1)
					(thickness 0.15)
				)
			)
		)
		(property "License" "Apache-2.0"
			(at 0 0 270)
			(unlocked yes)
			(layer "F.Fab")
			(hide yes)
			(effects
				(font
					(size 1 1)
					(thickness 0.15)
				)
			)
		)
		(property "Author" "Antmicro"
			(at 0 0 270)
			(unlocked yes)
			(layer "F.Fab")
			(hide yes)
			(effects
				(font
					(size 1 1)
					(thickness 0.15)
				)
			)
		)
		(property "Val" "200k"
			(at 0 0 270)
			(unlocked yes)
			(layer "F.Fab")
			(hide yes)
			(effects
				(font
					(size 1 1)
					(thickness 0.15)
				)
			)
		)
		(property "Tolerance" "1%"
			(at 0 0 270)
			(unlocked yes)
			(layer "F.Fab")
			(hide yes)
			(effects
				(font
					(size 1 1)
					(thickness 0.15)
				)
			)
		)
		(component_classes
			(class "DCDC_SOM")
		)
		(sheetname "/DCDC/")
		(sheetfile "dcdc.kicad_sch")
		(attr smd)
		(fp_rect
			(start -0.925 -0.47)
			(end 0.925 0.47)
			(stroke
				(width 0.05)
				(type default)
			)
			(fill no)
			(layer "F.CrtYd")
		)
		(fp_rect
			(start -0.5 -0.25)
			(end 0.5 0.25)
			(stroke
				(width 0.15)
				(type solid)
			)
			(fill no)
			(layer "F.Fab")
		)
		(fp_text user "${REFERENCE}"
			(at -0.95 3.168 90)
			(layer "F.Fab")
			(effects
				(font
					(size 0.7 0.7)
					(thickness 0.15)
				)
				(justify right top)
			)
		)
		(fp_text user "Author: Antmicro"
			(at -0.95 4.169 90)
			(layer "F.Fab")
			(effects
				(font
					(size 0.7 0.7)
					(thickness 0.15)
				)
				(justify right top)
			)
		)
		(fp_text user "License: Apache-2.0"
			(at -0.95 5.169 90)
			(layer "F.Fab")
			(effects
				(font
					(size 0.7 0.7)
					(thickness 0.15)
				)
				(justify right top)
			)
		)
		(pad "1" smd roundrect
			(at -0.48 0 270)
			(size 0.59 0.64)
			(layers "F.Cu" "F.Mask" "F.Paste")
			(roundrect_rratio 0.25)
			(net 1 "GND")
			(pintype "passive")
		)
		(pad "2" smd roundrect
			(at 0.48 0 270)
			(size 0.59 0.64)
			(layers "F.Cu" "F.Mask" "F.Paste")
			(roundrect_rratio 0.25)
			(net 1214 "/DCDC/16V_MODE2")
			(pintype "passive")
		)
	)
	(footprint "antmicro-footprints:R_0402_1005Metric"
		(layer "F.Cu")
		(at 136 108.1 180)
		(descr "Resistor SMD 0402")
		(tags "resistor SMD 0402")
		(property "Reference" "R401"
			(at 1 0.3 0)
			(layer "F.SilkS")
			(effects
				(font
					(size 0.7 0.7)
					(thickness 0.15)
				)
				(justify right top)
			)
		)
		(property "Value" "R_0R_0402"
			(at -1.011843 1.772047 0)
			(layer "F.Fab")
			(effects
				(font
					(size 0.7 0.7)
					(thickness 0.15)
				)
				(justify right top)
			)
		)
		(property "Datasheet" "https://industrial.panasonic.com/cdbs/www-data/pdf/RDA0000/AOA0000C301.pdf"
			(at 0 0 0)
			(layer "F.Fab")
			(hide yes)
			(effects
				(font
					(size 1.27 1.27)
					(thickness 0.15)
				)
			)
		)
		(property "Description" "SMD Chip Resistor, Jumper, 0 ohm, 100 mW, 0402 [1005 Metric], Thick Film, General Purpose"
			(at 0 0 0)
			(layer "F.Fab")
			(hide yes)
			(effects
				(font
					(size 1.27 1.27)
					(thickness 0.15)
				)
			)
		)
		(property "MPN" "ERJ2GE0R00X"
			(at 0 0 180)
			(unlocked yes)
			(layer "F.Fab")
			(hide yes)
			(effects
				(font
					(size 1 1)
					(thickness 0.15)
				)
			)
		)
		(property "Manufacturer" "Panasonic"
			(at 0 0 180)
			(unlocked yes)
			(layer "F.Fab")
			(hide yes)
			(effects
				(font
					(size 1 1)
					(thickness 0.15)
				)
			)
		)
		(property "License" "Apache-2.0"
			(at 0 0 180)
			(unlocked yes)
			(layer "F.Fab")
			(hide yes)
			(effects
				(font
					(size 1 1)
					(thickness 0.15)
				)
			)
		)
		(property "Author" "Antmicro"
			(at 0 0 180)
			(unlocked yes)
			(layer "F.Fab")
			(hide yes)
			(effects
				(font
					(size 1 1)
					(thickness 0.15)
				)
			)
		)
		(property "Val" "0R"
			(at 0 0 180)
			(unlocked yes)
			(layer "F.Fab")
			(hide yes)
			(effects
				(font
					(size 1 1)
					(thickness 0.15)
				)
			)
		)
		(property "Tolerance" "~"
			(at 0 0 180)
			(unlocked yes)
			(layer "F.Fab")
			(hide yes)
			(effects
				(font
					(size 1 1)
					(thickness 0.15)
				)
			)
		)
		(property "Current" "1A"
			(at 0 0 180)
			(unlocked yes)
			(layer "F.Fab")
			(hide yes)
			(effects
				(font
					(size 1 1)
					(thickness 0.15)
				)
			)
		)
		(sheetname "/Peripherals/")
		(sheetfile "peripherals.kicad_sch")
		(attr smd)
		(fp_rect
			(start -0.925 -0.47)
			(end 0.925 0.47)
			(stroke
				(width 0.05)
				(type default)
			)
			(fill no)
			(layer "F.CrtYd")
		)
		(fp_rect
			(start -0.5 -0.25)
			(end 0.5 0.25)
			(stroke
				(width 0.15)
				(type solid)
			)
			(fill no)
			(layer "F.Fab")
		)
		(fp_text user "${REFERENCE}"
			(at -0.95 3.168 0)
			(layer "F.Fab")
			(effects
				(font
					(size 0.7 0.7)
					(thickness 0.15)
				)
				(justify right top)
			)
		)
		(fp_text user "License: Apache-2.0"
			(at -0.95 5.169 0)
			(layer "F.Fab")
			(effects
				(font
					(size 0.7 0.7)
					(thickness 0.15)
				)
				(justify right top)
			)
		)
		(fp_text user "Author: Antmicro"
			(at -0.95 4.169 0)
			(layer "F.Fab")
			(effects
				(font
					(size 0.7 0.7)
					(thickness 0.15)
				)
				(justify right top)
			)
		)
		(pad "1" smd roundrect
			(at -0.48 0 180)
			(size 0.59 0.64)
			(layers "F.Cu" "F.Mask" "F.Paste")
			(roundrect_rratio 0.25)
			(net 1315 "/Peripherals/GPIOEX_P0_0")
			(pintype "passive")
		)
		(pad "2" smd roundrect
			(at 0.48 0 180)
			(size 0.59 0.64)
			(layers "F.Cu" "F.Mask" "F.Paste")
			(roundrect_rratio 0.25)
			(net 74 "/CSI/CAM_CTRL.CSIA_PEN")
			(pintype "passive")
		)
	)
	(footprint "antmicro-footprints:SOD-523"
		(layer "F.Cu")
		(at 135.7 65.2 180)
		(property "Reference" "D11"
			(at -3.14 0.4 0)
			(layer "F.SilkS")
			(effects
				(font
					(size 0.7 0.7)
					(thickness 0.15)
				)
				(justify right top)
			)
		)
		(property "Value" "PESD5Z5.0F"
			(at 0 1.499 0)
			(layer "F.Fab")
			(effects
				(font
					(size 0.7 0.7)
					(thickness 0.15)
				)
				(justify right top)
			)
		)
		(property "Datasheet" "https://assets.nexperia.com/documents/data-sheet/PESD5Z5_0.pdf"
			(at 0 0 0)
			(layer "F.Fab")
			(hide yes)
			(effects
				(font
					(size 1.27 1.27)
					(thickness 0.15)
				)
			)
		)
		(property "Description" "Unidirectional TVS, 30 kV,  SOD-523, 5 V, 89 pF"
			(at 0 0 0)
			(layer "F.Fab")
			(hide yes)
			(effects
				(font
					(size 1.27 1.27)
					(thickness 0.15)
				)
			)
		)
		(property "Manufacturer" "Nexperia"
			(at 0 0 180)
			(unlocked yes)
			(layer "F.Fab")
			(hide yes)
			(effects
				(font
					(size 1 1)
					(thickness 0.15)
				)
			)
		)
		(property "MPN" "PESD5Z5.0F"
			(at 0 0 180)
			(unlocked yes)
			(layer "F.Fab")
			(hide yes)
			(effects
				(font
					(size 1 1)
					(thickness 0.15)
				)
			)
		)
		(property "Author" "Antmicro"
			(at 0 0 180)
			(unlocked yes)
			(layer "F.Fab")
			(hide yes)
			(effects
				(font
					(size 1 1)
					(thickness 0.15)
				)
			)
		)
		(property "License" "Apache-2.0"
			(at 0 0 180)
			(unlocked yes)
			(layer "F.Fab")
			(hide yes)
			(effects
				(font
					(size 1 1)
					(thickness 0.15)
				)
			)
		)
		(sheetname "/Power/")
		(sheetfile "power.kicad_sch")
		(attr smd)
		(fp_line
			(start -0.35 -0.5)
			(end -0.35 0.5)
			(stroke
				(width 0.15)
				(type solid)
			)
			(layer "F.SilkS")
		)
		(fp_poly
			(pts
				(xy -1 -0.6) (xy -1 0.6) (xy 1 0.6) (xy 1 -0.6)
			)
			(stroke
				(width 0.05)
				(type solid)
			)
			(fill no)
			(layer "F.CrtYd")
		)
		(fp_line
			(start 0.65 -0.425)
			(end 0.65 0.423)
			(stroke
				(width 0.15)
				(type solid)
			)
			(layer "F.Fab")
		)
		(fp_line
			(start -0.35 -0.4)
			(end -0.35 0.4)
			(stroke
				(width 0.15)
				(type solid)
			)
			(layer "F.Fab")
		)
		(fp_line
			(start -0.652 0.423)
			(end 0.65 0.423)
			(stroke
				(width 0.15)
				(type solid)
			)
			(layer "F.Fab")
		)
		(fp_line
			(start -0.652 0.423)
			(end -0.652 -0.425)
			(stroke
				(width 0.15)
				(type solid)
			)
			(layer "F.Fab")
		)
		(fp_line
			(start -0.652 -0.425)
			(end 0.65 -0.425)
			(stroke
				(width 0.15)
				(type solid)
			)
			(layer "F.Fab")
		)
		(fp_text user "License: Apache-2.0"
			(at -1.276 5.9 0)
			(layer "F.Fab")
			(effects
				(font
					(size 0.7 0.7)
					(thickness 0.15)
				)
				(justify right top)
			)
		)
		(fp_text user "Author: Antmicro"
			(at -1.276 4.7 0)
			(layer "F.Fab")
			(effects
				(font
					(size 0.7 0.7)
					(thickness 0.15)
				)
				(justify right top)
			)
		)
		(fp_text user "${REFERENCE}"
			(at -1.276 3.499 0)
			(layer "F.Fab")
			(effects
				(font
					(size 0.7 0.7)
					(thickness 0.15)
				)
				(justify right top)
			)
		)
		(pad "1" smd roundrect
			(at -0.701 0 180)
			(size 0.5 0.6)
			(layers "F.Cu" "F.Mask" "F.Paste")
			(roundrect_rratio 0.25)
			(net 4 "+3V3_AON")
			(pinfunction "C")
			(pintype "passive")
		)
		(pad "2" smd roundrect
			(at 0.699001 0 180)
			(size 0.5 0.6)
			(layers "F.Cu" "F.Mask" "F.Paste")
			(roundrect_rratio 0.25)
			(net 1 "GND")
			(pinfunction "A")
			(pintype "passive")
		)
	)
	(footprint "antmicro-footprints:R_0402_1005Metric"
		(layer "F.Cu")
		(at 136 111.1 180)
		(descr "Resistor SMD 0402")
		(tags "resistor SMD 0402")
		(property "Reference" "R402"
			(at 1 0.3 0)
			(layer "F.SilkS")
			(effects
				(font
					(size 0.7 0.7)
					(thickness 0.15)
				)
				(justify right top)
			)
		)
		(property "Value" "R_0R_0402"
			(at -1.011843 1.772047 0)
			(layer "F.Fab")
			(effects
				(font
					(size 0.7 0.7)
					(thickness 0.15)
				)
				(justify right top)
			)
		)
		(property "Datasheet" "https://industrial.panasonic.com/cdbs/www-data/pdf/RDA0000/AOA0000C301.pdf"
			(at 0 0 0)
			(layer "F.Fab")
			(hide yes)
			(effects
				(font
					(size 1.27 1.27)
					(thickness 0.15)
				)
			)
		)
		(property "Description" "SMD Chip Resistor, Jumper, 0 ohm, 100 mW, 0402 [1005 Metric], Thick Film, General Purpose"
			(at 0 0 0)
			(layer "F.Fab")
			(hide yes)
			(effects
				(font
					(size 1.27 1.27)
					(thickness 0.15)
				)
			)
		)
		(property "MPN" "ERJ2GE0R00X"
			(at 0 0 180)
			(unlocked yes)
			(layer "F.Fab")
			(hide yes)
			(effects
				(font
					(size 1 1)
					(thickness 0.15)
				)
			)
		)
		(property "Manufacturer" "Panasonic"
			(at 0 0 180)
			(unlocked yes)
			(layer "F.Fab")
			(hide yes)
			(effects
				(font
					(size 1 1)
					(thickness 0.15)
				)
			)
		)
		(property "License" "Apache-2.0"
			(at 0 0 180)
			(unlocked yes)
			(layer "F.Fab")
			(hide yes)
			(effects
				(font
					(size 1 1)
					(thickness 0.15)
				)
			)
		)
		(property "Author" "Antmicro"
			(at 0 0 180)
			(unlocked yes)
			(layer "F.Fab")
			(hide yes)
			(effects
				(font
					(size 1 1)
					(thickness 0.15)
				)
			)
		)
		(property "Val" "0R"
			(at 0 0 180)
			(unlocked yes)
			(layer "F.Fab")
			(hide yes)
			(effects
				(font
					(size 1 1)
					(thickness 0.15)
				)
			)
		)
		(property "Tolerance" "~"
			(at 0 0 180)
			(unlocked yes)
			(layer "F.Fab")
			(hide yes)
			(effects
				(font
					(size 1 1)
					(thickness 0.15)
				)
			)
		)
		(property "Current" "1A"
			(at 0 0 180)
			(unlocked yes)
			(layer "F.Fab")
			(hide yes)
			(effects
				(font
					(size 1 1)
					(thickness 0.15)
				)
			)
		)
		(sheetname "/Peripherals/")
		(sheetfile "peripherals.kicad_sch")
		(attr smd)
		(fp_rect
			(start -0.925 -0.47)
			(end 0.925 0.47)
			(stroke
				(width 0.05)
				(type default)
			)
			(fill no)
			(layer "F.CrtYd")
		)
		(fp_rect
			(start -0.5 -0.25)
			(end 0.5 0.25)
			(stroke
				(width 0.15)
				(type solid)
			)
			(fill no)
			(layer "F.Fab")
		)
		(fp_text user "License: Apache-2.0"
			(at -0.95 5.169 0)
			(layer "F.Fab")
			(effects
				(font
					(size 0.7 0.7)
					(thickness 0.15)
				)
				(justify right top)
			)
		)
		(fp_text user "${REFERENCE}"
			(at -0.95 3.168 0)
			(layer "F.Fab")
			(effects
				(font
					(size 0.7 0.7)
					(thickness 0.15)
				)
				(justify right top)
			)
		)
		(fp_text user "Author: Antmicro"
			(at -0.95 4.169 0)
			(layer "F.Fab")
			(effects
				(font
					(size 0.7 0.7)
					(thickness 0.15)
				)
				(justify right top)
			)
		)
		(pad "1" smd roundrect
			(at -0.48 0 180)
			(size 0.59 0.64)
			(layers "F.Cu" "F.Mask" "F.Paste")
			(roundrect_rratio 0.25)
			(net 1312 "/Peripherals/GPIOEX_P0_3")
			(pintype "passive")
		)
		(pad "2" smd roundrect
			(at 0.48 0 180)
			(size 0.59 0.64)
			(layers "F.Cu" "F.Mask" "F.Paste")
			(roundrect_rratio 0.25)
			(net 117 "/CSI/CAM_CTRL.CSIB_FLG")
			(pintype "passive")
		)
	)
	(footprint "antmicro-footprints:C_0402_1005Metric"
		(layer "F.Cu")
		(at 94 63.5 180)
		(descr "Capacitor SMD 0402")
		(tags "capacitor SMD 0402")
		(property "Reference" "C40"
			(at -9.05 -0.6 0)
			(layer "F.SilkS")
			(effects
				(font
					(size 0.7 0.7)
					(thickness 0.15)
				)
				(justify right top)
			)
		)
		(property "Value" "C_100n_0402"
			(at -1.022927 2.155213 0)
			(layer "F.Fab")
			(effects
				(font
					(size 0.7 0.7)
					(thickness 0.15)
				)
				(justify right top)
			)
		)
		(property "Datasheet" "https://www.murata.com/products/productdetail?partno=GRM155R61H104KE14%23"
			(at 0 0 0)
			(layer "F.Fab")
			(hide yes)
			(effects
				(font
					(size 1.27 1.27)
					(thickness 0.15)
				)
			)
		)
		(property "Description" "SMD Multilayer Ceramic Capacitor, 0.1 µF, 50 V, 0402 [1005 Metric], ± 10%, X5R, GRM Series"
			(at 0 0 0)
			(layer "F.Fab")
			(hide yes)
			(effects
				(font
					(size 1.27 1.27)
					(thickness 0.15)
				)
			)
		)
		(property "MPN" "GRM155R61H104KE14D"
			(at 0 0 180)
			(unlocked yes)
			(layer "F.Fab")
			(hide yes)
			(effects
				(font
					(size 1 1)
					(thickness 0.15)
				)
			)
		)
		(property "Manufacturer" "Murata"
			(at 0 0 180)
			(unlocked yes)
			(layer "F.Fab")
			(hide yes)
			(effects
				(font
					(size 1 1)
					(thickness 0.15)
				)
			)
		)
		(property "License" "Apache-2.0"
			(at 0 0 180)
			(unlocked yes)
			(layer "F.Fab")
			(hide yes)
			(effects
				(font
					(size 1 1)
					(thickness 0.15)
				)
			)
		)
		(property "Author" "Antmicro"
			(at 0 0 180)
			(unlocked yes)
			(layer "F.Fab")
			(hide yes)
			(effects
				(font
					(size 1 1)
					(thickness 0.15)
				)
			)
		)
		(property "Val" "100n"
			(at 0 0 180)
			(unlocked yes)
			(layer "F.Fab")
			(hide yes)
			(effects
				(font
					(size 1 1)
					(thickness 0.15)
				)
			)
		)
		(property "Voltage" "50V"
			(at 0 0 180)
			(unlocked yes)
			(layer "F.Fab")
			(hide yes)
			(effects
				(font
					(size 1 1)
					(thickness 0.15)
				)
			)
		)
		(property "Dielectric" "X5R"
			(at 0 0 180)
			(unlocked yes)
			(layer "F.Fab")
			(hide yes)
			(effects
				(font
					(size 1 1)
					(thickness 0.15)
				)
			)
		)
		(sheetname "/SoM_Power/")
		(sheetfile "som_power.kicad_sch")
		(attr smd)
		(fp_poly
			(pts
				(xy -0.925 -0.47) (xy 0.925 -0.47) (xy 0.925 0.47) (xy -0.925 0.47)
			)
			(stroke
				(width 0.05)
				(type default)
			)
			(fill no)
			(layer "F.CrtYd")
		)
		(fp_line
			(start 0.504 0.248)
			(end -0.494 0.248)
			(stroke
				(width 0.15)
				(type solid)
			)
			(layer "F.Fab")
		)
		(fp_line
			(start 0.504 -0.25)
			(end 0.504 0.248)
			(stroke
				(width 0.15)
				(type solid)
			)
			(layer "F.Fab")
		)
		(fp_line
			(start -0.494 0.248)
			(end -0.494 -0.25)
			(stroke
				(width 0.15)
				(type solid)
			)
			(layer "F.Fab")
		)
		(fp_line
			(start -0.494 -0.25)
			(end 0.504 -0.25)
			(stroke
				(width 0.15)
				(type solid)
			)
			(layer "F.Fab")
		)
		(fp_text user "Author: Antmicro"
			(at -0.939 3.399 0)
			(layer "F.Fab")
			(effects
				(font
					(size 0.7 0.7)
					(thickness 0.15)
				)
				(justify right top)
			)
		)
		(fp_text user "License: Apache-2.0"
			(at -0.939 5.799 0)
			(layer "F.Fab")
			(effects
				(font
					(size 0.7 0.7)
					(thickness 0.15)
				)
				(justify right top)
			)
		)
		(fp_text user "${REFERENCE}"
			(at -0.939 4.599 0)
			(layer "F.Fab")
			(effects
				(font
					(size 0.7 0.7)
					(thickness 0.15)
				)
				(justify right top)
			)
		)
		(pad "1" smd roundrect
			(at -0.48 0 180)
			(size 0.59 0.64)
			(layers "F.Cu" "F.Mask" "F.Paste")
			(roundrect_rratio 0.25)
			(net 1 "GND")
			(pintype "passive")
		)
		(pad "2" smd roundrect
			(at 0.48 0 180)
			(size 0.59 0.64)
			(layers "F.Cu" "F.Mask" "F.Paste")
			(roundrect_rratio 0.25)
			(net 4 "+3V3_AON")
			(pintype "passive")
		)
	)
	(footprint "antmicro-footprints:C_0603_1608Metric_EIA"
		(layer "F.Cu")
		(at 173.55 113.59 -90)
		(descr "Capacitor SMD 0603, IPC-7351 Density Level A")
		(tags "Capacitor 0603")
		(property "Reference" "C63"
			(at -1.21 6.839468 90)
			(layer "F.SilkS")
			(effects
				(font
					(size 0.7 0.7)
					(thickness 0.15)
				)
				(justify right top)
			)
		)
		(property "Value" "C_22u_16V_0603"
			(at -1.42757 1.770288 90)
			(layer "F.Fab")
			(effects
				(font
					(size 0.7 0.7)
					(thickness 0.15)
				)
				(justify right top)
			)
		)
		(property "Datasheet" "https://product.samsungsem.com/mlcc/CL10A226MO7JZN.do"
			(at 0 0 90)
			(layer "F.Fab")
			(hide yes)
			(effects
				(font
					(size 1.27 1.27)
					(thickness 0.15)
				)
			)
		)
		(property "Description" "SMD Multilayer Ceramic Capacitor"
			(at 0 0 90)
			(layer "F.Fab")
			(hide yes)
			(effects
				(font
					(size 1.27 1.27)
					(thickness 0.15)
				)
			)
		)
		(property "Manufacturer" "Samsung Electro-Mechanics"
			(at 0 0 270)
			(unlocked yes)
			(layer "F.Fab")
			(hide yes)
			(effects
				(font
					(size 1 1)
					(thickness 0.15)
				)
			)
		)
		(property "MPN" "CL10A226MO7JZNC"
			(at 0 0 270)
			(unlocked yes)
			(layer "F.Fab")
			(hide yes)
			(effects
				(font
					(size 1 1)
					(thickness 0.15)
				)
			)
		)
		(property "Val" "22u"
			(at 0 0 270)
			(unlocked yes)
			(layer "F.Fab")
			(hide yes)
			(effects
				(font
					(size 1 1)
					(thickness 0.15)
				)
			)
		)
		(property "License" "Apache-2.0"
			(at 0 0 270)
			(unlocked yes)
			(layer "F.Fab")
			(hide yes)
			(effects
				(font
					(size 1 1)
					(thickness 0.15)
				)
			)
		)
		(property "Author" "Antmicro"
			(at 0 0 270)
			(unlocked yes)
			(layer "F.Fab")
			(hide yes)
			(effects
				(font
					(size 1 1)
					(thickness 0.15)
				)
			)
		)
		(property "Voltage" "16V"
			(at 0 0 270)
			(unlocked yes)
			(layer "F.Fab")
			(hide yes)
			(effects
				(font
					(size 1 1)
					(thickness 0.15)
				)
			)
		)
		(property "Dielectric" ""
			(at 0 0 270)
			(unlocked yes)
			(layer "F.Fab")
			(hide yes)
			(effects
				(font
					(size 1 1)
					(thickness 0.15)
				)
			)
		)
		(sheetname "/DCDC/")
		(sheetfile "dcdc.kicad_sch")
		(attr smd)
		(fp_line
			(start -0.15 0.55)
			(end 0.15 0.55)
			(stroke
				(width 0.15)
				(type solid)
			)
			(layer "F.SilkS")
		)
		(fp_line
			(start -0.15 -0.55)
			(end 0.15 -0.55)
			(stroke
				(width 0.15)
				(type solid)
			)
			(layer "F.SilkS")
		)
		(fp_rect
			(start -1.25 -0.65)
			(end 1.25 0.65)
			(stroke
				(width 0.05)
				(type solid)
			)
			(fill no)
			(layer "F.CrtYd")
		)
		(fp_rect
			(start -0.8 -0.45)
			(end 0.8 0.45)
			(stroke
				(width 0.15)
				(type solid)
			)
			(fill no)
			(layer "F.Fab")
		)
		(fp_text user "License: Apache-2.0"
			(at -1.682 5.895 90)
			(layer "F.Fab")
			(effects
				(font
					(size 0.7 0.7)
					(thickness 0.15)
				)
				(justify right top)
			)
		)
		(fp_text user "Author: Antmicro"
			(at -1.682 4.894 90)
			(layer "F.Fab")
			(effects
				(font
					(size 0.7 0.7)
					(thickness 0.15)
				)
				(justify right top)
			)
		)
		(fp_text user "${REFERENCE}"
			(at -1.682 3.895 90)
			(layer "F.Fab")
			(effects
				(font
					(size 0.7 0.7)
					(thickness 0.15)
				)
				(justify right top)
			)
		)
		(pad "1" smd roundrect
			(at -0.7 0 270)
			(size 0.8 1.1)
			(layers "F.Cu" "F.Mask" "F.Paste")
			(roundrect_rratio 0.2)
			(net 1 "GND")
			(pintype "passive")
		)
		(pad "2" smd roundrect
			(at 0.7 0 270)
			(size 0.8 1.1)
			(layers "F.Cu" "F.Mask" "F.Paste")
			(roundrect_rratio 0.2)
			(net 253 "/DCDC/5V_OUT")
			(pintype "passive")
		)
	)
	(footprint "antmicro-footprints:R_0402_1005Metric"
		(layer "F.Cu")
		(at 90 65.45)
		(descr "Resistor SMD 0402")
		(tags "resistor SMD 0402")
		(property "Reference" "R297"
			(at -1.1 1.3 0)
			(layer "F.SilkS")
			(effects
				(font
					(size 0.7 0.7)
					(thickness 0.15)
				)
				(justify left bottom)
			)
		)
		(property "Value" "R_0R_0402"
			(at -1.011843 1.772046 0)
			(layer "F.Fab")
			(effects
				(font
					(size 0.7 0.7)
					(thickness 0.15)
				)
				(justify left bottom)
			)
		)
		(property "Datasheet" "https://industrial.panasonic.com/cdbs/www-data/pdf/RDA0000/AOA0000C301.pdf"
			(at 0 0 0)
			(layer "F.Fab")
			(hide yes)
			(effects
				(font
					(size 1.27 1.27)
					(thickness 0.15)
				)
			)
		)
		(property "Description" "SMD Chip Resistor, Jumper, 0 ohm, 100 mW, 0402 [1005 Metric], Thick Film, General Purpose"
			(at 0 0 0)
			(layer "F.Fab")
			(hide yes)
			(effects
				(font
					(size 1.27 1.27)
					(thickness 0.15)
				)
			)
		)
		(property "MPN" "ERJ2GE0R00X"
			(at 0 0 0)
			(unlocked yes)
			(layer "F.Fab")
			(hide yes)
			(effects
				(font
					(size 1 1)
					(thickness 0.15)
				)
			)
		)
		(property "Manufacturer" "Panasonic"
			(at 0 0 0)
			(unlocked yes)
			(layer "F.Fab")
			(hide yes)
			(effects
				(font
					(size 1 1)
					(thickness 0.15)
				)
			)
		)
		(property "License" "Apache-2.0"
			(at 0 0 0)
			(unlocked yes)
			(layer "F.Fab")
			(hide yes)
			(effects
				(font
					(size 1 1)
					(thickness 0.15)
				)
			)
		)
		(property "Author" "Antmicro"
			(at 0 0 0)
			(unlocked yes)
			(layer "F.Fab")
			(hide yes)
			(effects
				(font
					(size 1 1)
					(thickness 0.15)
				)
			)
		)
		(property "Val" "0R"
			(at 0 0 0)
			(unlocked yes)
			(layer "F.Fab")
			(hide yes)
			(effects
				(font
					(size 1 1)
					(thickness 0.15)
				)
			)
		)
		(property "Tolerance" "~"
			(at 0 0 0)
			(unlocked yes)
			(layer "F.Fab")
			(hide yes)
			(effects
				(font
					(size 1 1)
					(thickness 0.15)
				)
			)
		)
		(property "Current" "1A"
			(at 0 0 0)
			(unlocked yes)
			(layer "F.Fab")
			(hide yes)
			(effects
				(font
					(size 1 1)
					(thickness 0.15)
				)
			)
		)
		(sheetname "/SoM_Power/")
		(sheetfile "som_power.kicad_sch")
		(attr smd)
		(fp_poly
			(pts
				(xy -0.925 -0.47) (xy -0.925 0.47) (xy 0.925 0.47) (xy 0.925 -0.47)
			)
			(stroke
				(width 0.05)
				(type default)
			)
			(fill no)
			(layer "F.CrtYd")
		)
		(fp_poly
			(pts
				(xy -0.5 -0.25) (xy -0.5 0.25) (xy 0.5 0.25) (xy 0.5 -0.25)
			)
			(stroke
				(width 0.15)
				(type solid)
			)
			(fill no)
			(layer "F.Fab")
		)
		(fp_text user "${REFERENCE}"
			(at -0.95 3.168 0)
			(layer "F.Fab")
			(effects
				(font
					(size 0.7 0.7)
					(thickness 0.15)
				)
				(justify left bottom)
			)
		)
		(fp_text user "License: Apache-2.0"
			(at -0.949999 5.169 0)
			(layer "F.Fab")
			(effects
				(font
					(size 0.7 0.7)
					(thickness 0.15)
				)
				(justify left bottom)
			)
		)
		(fp_text user "Author: Antmicro"
			(at -0.95 4.169 0)
			(layer "F.Fab")
			(effects
				(font
					(size 0.7 0.7)
					(thickness 0.15)
				)
				(justify left bottom)
			)
		)
		(pad "1" smd roundrect
			(at -0.48 0)
			(size 0.59 0.64)
			(layers "F.Cu" "F.Mask" "F.Paste")
			(roundrect_rratio 0.25)
			(net 887 "Net-(Q17-D)")
			(pintype "passive")
		)
		(pad "2" smd roundrect
			(at 0.48 0)
			(size 0.59 0.64)
			(layers "F.Cu" "F.Mask" "F.Paste")
			(roundrect_rratio 0.25)
			(net 1032 "/SoM_Power/~{FORCE_SHDN}")
			(pintype "passive")
		)
	)
	(footprint "antmicro-footprints:R_0402_1005Metric"
		(layer "F.Cu")
		(at 195.1 126.3)
		(descr "Resistor SMD 0402")
		(tags "resistor SMD 0402")
		(property "Reference" "R83"
			(at 0.15 -1.35 0)
			(layer "F.SilkS")
			(effects
				(font
					(size 0.7 0.7)
					(thickness 0.15)
				)
				(justify left bottom)
			)
		)
		(property "Value" "R_10k_0402"
			(at -1.011843 1.772047 0)
			(layer "F.Fab")
			(effects
				(font
					(size 0.7 0.7)
					(thickness 0.15)
				)
				(justify left bottom)
			)
		)
		(property "Datasheet" "https://www.bourns.com/docs/product-datasheets/cr.pdf"
			(at 0 0 0)
			(layer "F.Fab")
			(hide yes)
			(effects
				(font
					(size 1.27 1.27)
					(thickness 0.15)
				)
			)
		)
		(property "Description" "SMD Chip Resistor, 10 kohm, ± 1%, 62.5 mW, 0402 [1005 Metric], Thick Film, General Purpose"
			(at 0 0 0)
			(layer "F.Fab")
			(hide yes)
			(effects
				(font
					(size 1.27 1.27)
					(thickness 0.15)
				)
			)
		)
		(property "MPN" "CR0402-FX-1002GLF"
			(at 0 0 0)
			(unlocked yes)
			(layer "F.Fab")
			(hide yes)
			(effects
				(font
					(size 1 1)
					(thickness 0.15)
				)
			)
		)
		(property "Manufacturer" "Bourns"
			(at 0 0 0)
			(unlocked yes)
			(layer "F.Fab")
			(hide yes)
			(effects
				(font
					(size 1 1)
					(thickness 0.15)
				)
			)
		)
		(property "License" "Apache-2.0"
			(at 0 0 0)
			(unlocked yes)
			(layer "F.Fab")
			(hide yes)
			(effects
				(font
					(size 1 1)
					(thickness 0.15)
				)
			)
		)
		(property "Author" "Antmicro"
			(at 0 0 0)
			(unlocked yes)
			(layer "F.Fab")
			(hide yes)
			(effects
				(font
					(size 1 1)
					(thickness 0.15)
				)
			)
		)
		(property "Val" "10k"
			(at 0 0 0)
			(unlocked yes)
			(layer "F.Fab")
			(hide yes)
			(effects
				(font
					(size 1 1)
					(thickness 0.15)
				)
			)
		)
		(property "Tolerance" "1%"
			(at 0 0 0)
			(unlocked yes)
			(layer "F.Fab")
			(hide yes)
			(effects
				(font
					(size 1 1)
					(thickness 0.15)
				)
			)
		)
		(sheetname "/USB Hub/")
		(sheetfile "usb_hub.kicad_sch")
		(attr smd)
		(fp_rect
			(start -0.925 -0.47)
			(end 0.925 0.47)
			(stroke
				(width 0.05)
				(type default)
			)
			(fill no)
			(layer "F.CrtYd")
		)
		(fp_rect
			(start -0.5 -0.25)
			(end 0.5 0.25)
			(stroke
				(width 0.15)
				(type solid)
			)
			(fill no)
			(layer "F.Fab")
		)
		(fp_text user "Author: Antmicro"
			(at -0.95 4.169 0)
			(layer "F.Fab")
			(effects
				(font
					(size 0.7 0.7)
					(thickness 0.15)
				)
				(justify left bottom)
			)
		)
		(fp_text user "${REFERENCE}"
			(at -0.95 3.168 0)
			(layer "F.Fab")
			(effects
				(font
					(size 0.7 0.7)
					(thickness 0.15)
				)
				(justify left bottom)
			)
		)
		(fp_text user "License: Apache-2.0"
			(at -0.95 5.169 0)
			(layer "F.Fab")
			(effects
				(font
					(size 0.7 0.7)
					(thickness 0.15)
				)
				(justify left bottom)
			)
		)
		(pad "1" smd roundrect
			(at -0.48 0)
			(size 0.59 0.64)
			(layers "F.Cu" "F.Mask" "F.Paste")
			(roundrect_rratio 0.25)
			(net 2 "+3V3")
			(pintype "passive")
		)
		(pad "2" smd roundrect
			(at 0.48 0)
			(size 0.59 0.64)
			(layers "F.Cu" "F.Mask" "F.Paste")
			(roundrect_rratio 0.25)
			(net 917 "/USB Hub/TEST2")
			(pintype "passive")
		)
	)
	(footprint "antmicro-footprints:LED_0603_1608Metric_G"
		(layer "F.Cu")
		(at 235.540532 82.71 180)
		(descr "LED SMD 0603 Green")
		(tags "LED SMD 0603 Green")
		(property "Reference" "D24"
			(at -1.059468 -0.799999 0)
			(layer "F.SilkS")
			(effects
				(font
					(size 0.7 0.7)
					(thickness 0.15)
				)
				(justify right top)
			)
		)
		(property "Value" "LED_G_0603_LTST-C190GKT"
			(at -0.001 1.599 0)
			(layer "F.Fab")
			(effects
				(font
					(size 0.7 0.7)
					(thickness 0.15)
				)
				(justify right top)
			)
		)
		(property "Datasheet" "https://media.digikey.com/pdf/Data%20Sheets/Lite-On%20PDFs/LTST-C190GKT.pdf"
			(at 0 0 0)
			(layer "F.Fab")
			(hide yes)
			(effects
				(font
					(size 1.27 1.27)
					(thickness 0.15)
				)
			)
		)
		(property "Description" "LED, Green, SMD, 0603, 20 mA, 2.1 V, 569 nm"
			(at 0 0 0)
			(layer "F.Fab")
			(hide yes)
			(effects
				(font
					(size 1.27 1.27)
					(thickness 0.15)
				)
			)
		)
		(property "MPN" "LTST-C190GKT"
			(at 0 0 180)
			(unlocked yes)
			(layer "F.Fab")
			(hide yes)
			(effects
				(font
					(size 1 1)
					(thickness 0.15)
				)
			)
		)
		(property "Manufacturer" "Lite-On"
			(at 0 0 180)
			(unlocked yes)
			(layer "F.Fab")
			(hide yes)
			(effects
				(font
					(size 1 1)
					(thickness 0.15)
				)
			)
		)
		(property "Author" "Antmicro"
			(at 0 0 180)
			(unlocked yes)
			(layer "F.Fab")
			(hide yes)
			(effects
				(font
					(size 1 1)
					(thickness 0.15)
				)
			)
		)
		(property "License" "Apache-2.0"
			(at 0 0 180)
			(unlocked yes)
			(layer "F.Fab")
			(hide yes)
			(effects
				(font
					(size 1 1)
					(thickness 0.15)
				)
			)
		)
		(property "Color" "Green"
			(at 0 0 180)
			(unlocked yes)
			(layer "F.Fab")
			(hide yes)
			(effects
				(font
					(size 1 1)
					(thickness 0.15)
				)
			)
		)
		(sheetname "/USB Debug, PD/")
		(sheetfile "usb_debug_pd.kicad_sch")
		(attr smd)
		(fp_line
			(start 0.22 0.35)
			(end -0.22 0.35)
			(stroke
				(width 0.15)
				(type solid)
			)
			(layer "F.SilkS")
		)
		(fp_line
			(start 0.22 -0.35)
			(end -0.22 -0.35)
			(stroke
				(width 0.15)
				(type solid)
			)
			(layer "F.SilkS")
		)
		(fp_line
			(start 0.105328 0.201008)
			(end 0.105329 -0.198992)
			(stroke
				(width 0.1)
				(type solid)
			)
			(layer "F.SilkS")
		)
		(fp_line
			(start 0.105328 0.201008)
			(end -0.094672 0.001008)
			(stroke
				(width 0.1)
				(type solid)
			)
			(layer "F.SilkS")
		)
		(fp_line
			(start 0.105328 0.001008)
			(end 0.240001 0.001)
			(stroke
				(width 0.1)
				(type solid)
			)
			(layer "F.SilkS")
		)
		(fp_line
			(start -0.094672 0.201008)
			(end -0.094672 -0.198992)
			(stroke
				(width 0.1)
				(type solid)
			)
			(layer "F.SilkS")
		)
		(fp_line
			(start -0.094672 0.001008)
			(end 0.105329 -0.198992)
			(stroke
				(width 0.1)
				(type solid)
			)
			(layer "F.SilkS")
		)
		(fp_line
			(start -0.094672 0.001008)
			(end -0.24 0.001008)
			(stroke
				(width 0.1)
				(type solid)
			)
			(layer "F.SilkS")
		)
		(fp_line
			(start -1.18 -0.319)
			(end -1.18 0.321)
			(stroke
				(width 0.15)
				(type solid)
			)
			(layer "F.SilkS")
		)
		(fp_poly
			(pts
				(xy 1.25 0.65) (xy -1.25 0.65) (xy -1.25 -0.65) (xy 1.25 -0.65)
			)
			(stroke
				(width 0.05)
				(type solid)
			)
			(fill no)
			(layer "F.CrtYd")
		)
		(fp_line
			(start 0.599 0)
			(end 0.200999 0)
			(stroke
				(width 0.15)
				(type solid)
			)
			(layer "F.Fab")
		)
		(fp_line
			(start 0.201 0.2)
			(end 0.200999 0)
			(stroke
				(width 0.15)
				(type solid)
			)
			(layer "F.Fab")
		)
		(fp_line
			(start 0.201 -0.202)
			(end -0.101 0)
			(stroke
				(width 0.15)
				(type solid)
			)
			(layer "F.Fab")
		)
		(fp_line
			(start 0.200999 0)
			(end 0.201 -0.202)
			(stroke
				(width 0.15)
				(type solid)
			)
			(layer "F.Fab")
		)
		(fp_line
			(start -0.101 0)
			(end 0.201 0.2)
			(stroke
				(width 0.15)
				(type solid)
			)
			(layer "F.Fab")
		)
		(fp_line
			(start -0.199 0.2)
			(end -0.199 0.1)
			(stroke
				(width 0.15)
				(type solid)
			)
			(layer "F.Fab")
		)
		(fp_line
			(start -0.199 0)
			(end -0.597 0)
			(stroke
				(width 0.15)
				(type solid)
			)
			(layer "F.Fab")
		)
		(fp_line
			(start -0.199 -0.202)
			(end -0.199 0.1)
			(stroke
				(width 0.15)
				(type solid)
			)
			(layer "F.Fab")
		)
		(fp_poly
			(pts
				(xy 0.848 0.4) (xy -0.85 0.4) (xy -0.85 -0.402) (xy 0.848 -0.401999)
			)
			(stroke
				(width 0.15)
				(type solid)
			)
			(fill no)
			(layer "F.Fab")
		)
		(fp_text user "Author: Antmicro"
			(at -1.4224 4.799 0)
			(layer "F.Fab")
			(effects
				(font
					(size 0.7 0.7)
					(thickness 0.15)
				)
				(justify right top)
			)
		)
		(fp_text user "License: Apache-2.0"
			(at -1.4224 3.599 0)
			(layer "F.Fab")
			(effects
				(font
					(size 0.7 0.7)
					(thickness 0.15)
				)
				(justify right top)
			)
		)
		(fp_text user "${REFERENCE}"
			(at -1.4224 5.999 0)
			(layer "F.Fab")
			(effects
				(font
					(size 0.7 0.7)
					(thickness 0.15)
				)
				(justify right top)
			)
		)
		(pad "1" smd roundrect
			(at -0.7 0)
			(size 0.8 1)
			(layers "F.Cu" "F.Mask" "F.Paste")
			(roundrect_rratio 0.2)
			(net 1 "GND")
			(pinfunction "C")
			(pintype "passive")
		)
		(pad "2" smd roundrect
			(at 0.7 0)
			(size 0.8 1)
			(layers "F.Cu" "F.Mask" "F.Paste")
			(roundrect_rratio 0.2)
			(net 1387 "Net-(D24-A)")
			(pinfunction "A")
			(pintype "passive")
		)
	)
	(footprint "antmicro-footprints:R_0402_1005Metric"
		(layer "F.Cu")
		(at 208.1 64.22 90)
		(descr "Resistor SMD 0402")
		(tags "resistor SMD 0402")
		(property "Reference" "R409"
			(at -0.98 -3.2 180)
			(layer "F.SilkS")
			(effects
				(font
					(size 0.7 0.7)
					(thickness 0.15)
				)
				(justify left bottom)
			)
		)
		(property "Value" "R_232k_0402"
			(at -1.011843 1.772047 90)
			(layer "F.Fab")
			(effects
				(font
					(size 0.7 0.7)
					(thickness 0.15)
				)
				(justify left bottom)
			)
		)
		(property "Datasheet" "https://www.mouser.com/datasheet/2/447/PYu_RT_1_to_0_01_RoHS_L_12-3003070.pdf"
			(at 0 0 90)
			(layer "F.Fab")
			(hide yes)
			(effects
				(font
					(size 1.27 1.27)
					(thickness 0.15)
				)
			)
		)
		(property "Description" "SMD Chip Resistor"
			(at 0 0 90)
			(layer "F.Fab")
			(hide yes)
			(effects
				(font
					(size 1.27 1.27)
					(thickness 0.15)
				)
			)
		)
		(property "MPN" "RT0402FRE07232KL"
			(at 0 0 90)
			(unlocked yes)
			(layer "F.Fab")
			(hide yes)
			(effects
				(font
					(size 1 1)
					(thickness 0.15)
				)
			)
		)
		(property "Manufacturer" "YAGEO"
			(at 0 0 90)
			(unlocked yes)
			(layer "F.Fab")
			(hide yes)
			(effects
				(font
					(size 1 1)
					(thickness 0.15)
				)
			)
		)
		(property "License" "Apache-2.0"
			(at 0 0 90)
			(unlocked yes)
			(layer "F.Fab")
			(hide yes)
			(effects
				(font
					(size 1 1)
					(thickness 0.15)
				)
			)
		)
		(property "Author" "Antmicro"
			(at 0 0 90)
			(unlocked yes)
			(layer "F.Fab")
			(hide yes)
			(effects
				(font
					(size 1 1)
					(thickness 0.15)
				)
			)
		)
		(property "Val" "232k"
			(at 0 0 90)
			(unlocked yes)
			(layer "F.Fab")
			(hide yes)
			(effects
				(font
					(size 1 1)
					(thickness 0.15)
				)
			)
		)
		(property "Tolerance" "1%"
			(at 0 0 90)
			(unlocked yes)
			(layer "F.Fab")
			(hide yes)
			(effects
				(font
					(size 1 1)
					(thickness 0.15)
				)
			)
		)
		(sheetname "/Power/")
		(sheetfile "power.kicad_sch")
		(attr smd)
		(fp_rect
			(start -0.925 -0.47)
			(end 0.925 0.47)
			(stroke
				(width 0.05)
				(type default)
			)
			(fill no)
			(layer "F.CrtYd")
		)
		(fp_rect
			(start -0.5 -0.25)
			(end 0.5 0.25)
			(stroke
				(width 0.15)
				(type solid)
			)
			(fill no)
			(layer "F.Fab")
		)
		(fp_text user "Author: Antmicro"
			(at -0.95 4.169 90)
			(layer "F.Fab")
			(effects
				(font
					(size 0.7 0.7)
					(thickness 0.15)
				)
				(justify left bottom)
			)
		)
		(fp_text user "License: Apache-2.0"
			(at -0.95 5.169 90)
			(layer "F.Fab")
			(effects
				(font
					(size 0.7 0.7)
					(thickness 0.15)
				)
				(justify left bottom)
			)
		)
		(fp_text user "${REFERENCE}"
			(at -0.95 3.168 90)
			(layer "F.Fab")
			(effects
				(font
					(size 0.7 0.7)
					(thickness 0.15)
				)
				(justify left bottom)
			)
		)
		(pad "1" smd roundrect
			(at -0.48 0 90)
			(size 0.59 0.64)
			(layers "F.Cu" "F.Mask" "F.Paste")
			(roundrect_rratio 0.25)
			(net 1386 "Net-(U9-SET)")
			(pintype "passive")
		)
		(pad "2" smd roundrect
			(at 0.48 0 90)
			(size 0.59 0.64)
			(layers "F.Cu" "F.Mask" "F.Paste")
			(roundrect_rratio 0.25)
			(net 1383 "VCC_NO_OVP")
			(pintype "passive")
		)
	)
	(footprint "antmicro-footprints:LED_0603_1608Metric_G"
		(layer "F.Cu")
		(at 161.74 55.3 -90)
		(descr "LED SMD 0603 Green")
		(tags "LED SMD 0603 Green")
		(property "Reference" "D40"
			(at -0.89 1.44 90)
			(layer "F.SilkS")
			(effects
				(font
					(size 0.7 0.7)
					(thickness 0.15)
				)
				(justify right top)
			)
		)
		(property "Value" "LED_G_0603_LTST-C190GKT"
			(at -0.001 1.599 90)
			(layer "F.Fab")
			(effects
				(font
					(size 0.7 0.7)
					(thickness 0.15)
				)
				(justify right top)
			)
		)
		(property "Datasheet" "https://media.digikey.com/pdf/Data%20Sheets/Lite-On%20PDFs/LTST-C190GKT.pdf"
			(at 0 0 90)
			(layer "F.Fab")
			(hide yes)
			(effects
				(font
					(size 1.27 1.27)
					(thickness 0.15)
				)
			)
		)
		(property "Description" "LED, Green, SMD, 0603, 20 mA, 2.1 V, 569 nm"
			(at 0 0 90)
			(layer "F.Fab")
			(hide yes)
			(effects
				(font
					(size 1.27 1.27)
					(thickness 0.15)
				)
			)
		)
		(property "MPN" "LTST-C190GKT"
			(at 0 0 270)
			(unlocked yes)
			(layer "F.Fab")
			(hide yes)
			(effects
				(font
					(size 1 1)
					(thickness 0.15)
				)
			)
		)
		(property "Manufacturer" "Lite-On"
			(at 0 0 270)
			(unlocked yes)
			(layer "F.Fab")
			(hide yes)
			(effects
				(font
					(size 1 1)
					(thickness 0.15)
				)
			)
		)
		(property "Author" "Antmicro"
			(at 0 0 270)
			(unlocked yes)
			(layer "F.Fab")
			(hide yes)
			(effects
				(font
					(size 1 1)
					(thickness 0.15)
				)
			)
		)
		(property "License" "Apache-2.0"
			(at 0 0 270)
			(unlocked yes)
			(layer "F.Fab")
			(hide yes)
			(effects
				(font
					(size 1 1)
					(thickness 0.15)
				)
			)
		)
		(property "Color" "Green"
			(at 0 0 270)
			(unlocked yes)
			(layer "F.Fab")
			(hide yes)
			(effects
				(font
					(size 1 1)
					(thickness 0.15)
				)
			)
		)
		(sheetname "/Power/")
		(sheetfile "power.kicad_sch")
		(attr smd)
		(fp_line
			(start 0.22 0.35)
			(end -0.22 0.35)
			(stroke
				(width 0.15)
				(type solid)
			)
			(layer "F.SilkS")
		)
		(fp_line
			(start -0.094672 0.201008)
			(end -0.094672 -0.198992)
			(stroke
				(width 0.1)
				(type solid)
			)
			(layer "F.SilkS")
		)
		(fp_line
			(start 0.105328 0.201008)
			(end -0.094672 0.001008)
			(stroke
				(width 0.1)
				(type solid)
			)
			(layer "F.SilkS")
		)
		(fp_line
			(start 0.105328 0.201008)
			(end 0.105328 -0.198992)
			(stroke
				(width 0.1)
				(type solid)
			)
			(layer "F.SilkS")
		)
		(fp_line
			(start -0.094672 0.001008)
			(end -0.24 0.001008)
			(stroke
				(width 0.1)
				(type solid)
			)
			(layer "F.SilkS")
		)
		(fp_line
			(start -0.094672 0.001008)
			(end 0.105328 -0.198992)
			(stroke
				(width 0.1)
				(type solid)
			)
			(layer "F.SilkS")
		)
		(fp_line
			(start 0.105328 0.001008)
			(end 0.24 0.001)
			(stroke
				(width 0.1)
				(type solid)
			)
			(layer "F.SilkS")
		)
		(fp_line
			(start -1.18 -0.319)
			(end -1.18 0.321)
			(stroke
				(width 0.15)
				(type solid)
			)
			(layer "F.SilkS")
		)
		(fp_line
			(start 0.22 -0.35)
			(end -0.22 -0.35)
			(stroke
				(width 0.15)
				(type solid)
			)
			(layer "F.SilkS")
		)
		(fp_rect
			(start 1.25 0.65)
			(end -1.25 -0.65)
			(stroke
				(width 0.05)
				(type solid)
			)
			(fill no)
			(layer "F.CrtYd")
		)
		(fp_line
			(start -0.199 0.2)
			(end -0.199 0.1)
			(stroke
				(width 0.15)
				(type solid)
			)
			(layer "F.Fab")
		)
		(fp_line
			(start 0.201 0.2)
			(end 0.201 0)
			(stroke
				(width 0.15)
				(type solid)
			)
			(layer "F.Fab")
		)
		(fp_line
			(start -0.199 0)
			(end -0.597 0)
			(stroke
				(width 0.15)
				(type solid)
			)
			(layer "F.Fab")
		)
		(fp_line
			(start -0.101 0)
			(end 0.201 0.2)
			(stroke
				(width 0.15)
				(type solid)
			)
			(layer "F.Fab")
		)
		(fp_line
			(start 0.201 0)
			(end 0.201 -0.202)
			(stroke
				(width 0.15)
				(type solid)
			)
			(layer "F.Fab")
		)
		(fp_line
			(start 0.599 0)
			(end 0.201 0)
			(stroke
				(width 0.15)
				(type solid)
			)
			(layer "F.Fab")
		)
		(fp_line
			(start -0.199 -0.202)
			(end -0.199 0.1)
			(stroke
				(width 0.15)
				(type solid)
			)
			(layer "F.Fab")
		)
		(fp_line
			(start 0.201 -0.202)
			(end -0.101 0)
			(stroke
				(width 0.15)
				(type solid)
			)
			(layer "F.Fab")
		)
		(fp_rect
			(start 0.848 0.4)
			(end -0.85 -0.402)
			(stroke
				(width 0.15)
				(type solid)
			)
			(fill no)
			(layer "F.Fab")
		)
		(fp_text user "Author: Antmicro"
			(at -1.4224 4.799 90)
			(layer "F.Fab")
			(effects
				(font
					(size 0.7 0.7)
					(thickness 0.15)
				)
				(justify right top)
			)
		)
		(fp_text user "${REFERENCE}"
			(at -1.4224 5.999 90)
			(layer "F.Fab")
			(effects
				(font
					(size 0.7 0.7)
					(thickness 0.15)
				)
				(justify right top)
			)
		)
		(fp_text user "License: Apache-2.0"
			(at -1.4224 3.599 90)
			(layer "F.Fab")
			(effects
				(font
					(size 0.7 0.7)
					(thickness 0.15)
				)
				(justify right top)
			)
		)
		(pad "1" smd roundrect
			(at -0.7 0 90)
			(size 0.8 1)
			(layers "F.Cu" "F.Mask" "F.Paste")
			(roundrect_rratio 0.2)
			(net 891 "Net-(D40-C)")
			(pinfunction "C")
			(pintype "passive")
		)
		(pad "2" smd roundrect
			(at 0.7 0 90)
			(size 0.8 1)
			(layers "F.Cu" "F.Mask" "F.Paste")
			(roundrect_rratio 0.2)
			(net 1008 "Net-(D40-A)")
			(pinfunction "A")
			(pintype "passive")
		)
	)
	(footprint "antmicro-footprints:TP_SMD_0.75mm"
		(layer "F.Cu")
		(at 82.1 128.5 180)
		(property "Reference" "TP72"
			(at 0.5 0.5 180)
			(layer "F.SilkS")
			(effects
				(font
					(size 0.7 0.7)
					(thickness 0.15)
				)
				(justify left bottom)
			)
		)
		(property "Value" "TP_0.75mm_SMD"
			(at 0 1.2 180)
			(layer "F.Fab")
			(effects
				(font
					(size 0.7 0.7)
					(thickness 0.15)
				)
				(justify left bottom)
			)
		)
		(property "Description" "SMT test point"
			(at 0 0 180)
			(layer "F.Fab")
			(hide yes)
			(effects
				(font
					(size 1.27 1.27)
					(thickness 0.15)
				)
			)
		)
		(property "MPN" ""
			(at 0 0 180)
			(unlocked yes)
			(layer "F.Fab")
			(hide yes)
			(effects
				(font
					(size 1 1)
					(thickness 0.15)
				)
			)
		)
		(property "Manufacturer" ""
			(at 0 0 180)
			(unlocked yes)
			(layer "F.Fab")
			(hide yes)
			(effects
				(font
					(size 1 1)
					(thickness 0.15)
				)
			)
		)
		(property "Author" "Antmicro"
			(at 0 0 180)
			(unlocked yes)
			(layer "F.Fab")
			(hide yes)
			(effects
				(font
					(size 1 1)
					(thickness 0.15)
				)
			)
		)
		(property "License" "Apache-2.0"
			(at 0 0 180)
			(unlocked yes)
			(layer "F.Fab")
			(hide yes)
			(effects
				(font
					(size 1 1)
					(thickness 0.15)
				)
			)
		)
		(sheetname "/Expansion connector/")
		(sheetfile "expansion_connector.kicad_sch")
		(attr exclude_from_pos_files exclude_from_bom)
		(fp_circle
			(center 0 0)
			(end 0.475 0)
			(stroke
				(width 0.05)
				(type default)
			)
			(fill no)
			(layer "F.CrtYd")
		)
		(fp_text user "${REFERENCE}"
			(at -0.4 2.7 180)
			(layer "F.Fab")
			(effects
				(font
					(size 0.7 0.7)
					(thickness 0.15)
				)
				(justify left bottom)
			)
		)
		(fp_text user "Author: Antmicro"
			(at -0.4 3.901 180)
			(layer "F.Fab")
			(effects
				(font
					(size 0.7 0.7)
					(thickness 0.15)
				)
				(justify left bottom)
			)
		)
		(fp_text user "License: Apache-2.0"
			(at -0.4 5.101 180)
			(layer "F.Fab")
			(effects
				(font
					(size 0.7 0.7)
					(thickness 0.15)
				)
				(justify left bottom)
			)
		)
		(pad "1" smd circle
			(at 0 0 180)
			(size 0.75 0.75)
			(layers "F.Cu" "F.Mask")
			(net 777 "Net-(J18-PadB40)")
			(pinfunction "1")
			(pintype "passive")
		)
	)
	(footprint "antmicro-footprints:MLP44-24L_4x4x0.75mm"
		(layer "F.Cu")
		(at 181 128)
		(property "Reference" "U13"
			(at 0.475 3.29 0)
			(layer "F.SilkS")
			(effects
				(font
					(size 0.7 0.7)
					(thickness 0.15)
				)
				(justify left bottom)
			)
		)
		(property "Value" "SIC437AED-T1-GE3"
			(at -2.7 3.6 0)
			(layer "F.Fab")
			(effects
				(font
					(size 0.7 0.7)
					(thickness 0.15)
				)
				(justify left bottom)
			)
		)
		(property "Datasheet" "https://www.vishay.com/docs/75921/sic437.pdf"
			(at 0 0 0)
			(layer "F.Fab")
			(hide yes)
			(effects
				(font
					(size 1.27 1.27)
					(thickness 0.15)
				)
			)
		)
		(property "Description" "DC/DC Buck Step Down Regulator Adjustable, 4.5-28V In, 0.6V to 20V/12A Out, 1MHz, PowerPAK MLP44-24"
			(at 0 0 0)
			(layer "F.Fab")
			(hide yes)
			(effects
				(font
					(size 1.27 1.27)
					(thickness 0.15)
				)
			)
		)
		(property "Manufacturer" "Vishay"
			(at 0 0 0)
			(unlocked yes)
			(layer "F.Fab")
			(hide yes)
			(effects
				(font
					(size 1 1)
					(thickness 0.15)
				)
			)
		)
		(property "MPN" "SIC437AED-T1-GE3"
			(at 0 0 0)
			(unlocked yes)
			(layer "F.Fab")
			(hide yes)
			(effects
				(font
					(size 1 1)
					(thickness 0.15)
				)
			)
		)
		(property "Author" "Antmicro"
			(at 0 0 0)
			(unlocked yes)
			(layer "F.Fab")
			(hide yes)
			(effects
				(font
					(size 1 1)
					(thickness 0.15)
				)
			)
		)
		(property "License" "Apache-2.0"
			(at 0 0 0)
			(unlocked yes)
			(layer "F.Fab")
			(hide yes)
			(effects
				(font
					(size 1 1)
					(thickness 0.15)
				)
			)
		)
		(sheetname "/DCDC/")
		(sheetfile "dcdc.kicad_sch")
		(attr smd)
		(net_tie_pad_groups "1,2,26" "3,4,27" "5,6,7,8,9")
		(fp_line
			(start -2.11 -1.38)
			(end -2.11 -2.1)
			(stroke
				(width 0.15)
				(type solid)
			)
			(layer "F.SilkS")
		)
		(fp_line
			(start -2.11 2.11)
			(end -2.11 1.39)
			(stroke
				(width 0.15)
				(type solid)
			)
			(layer "F.SilkS")
		)
		(fp_line
			(start -1.89 -2.1)
			(end -2.11 -2.1)
			(stroke
				(width 0.15)
				(type solid)
			)
			(layer "F.SilkS")
		)
		(fp_line
			(start -1.89 2.11)
			(end -2.11 2.11)
			(stroke
				(width 0.15)
				(type solid)
			)
			(layer "F.SilkS")
		)
		(fp_line
			(start 1.44 2.11)
			(end 2.11 2.11)
			(stroke
				(width 0.15)
				(type solid)
			)
			(layer "F.SilkS")
		)
		(fp_line
			(start 1.89 -2.11)
			(end 2.11 -2.11)
			(stroke
				(width 0.15)
				(type solid)
			)
			(layer "F.SilkS")
		)
		(fp_line
			(start 2.11 -2.11)
			(end 2.11 -1.69)
			(stroke
				(width 0.15)
				(type solid)
			)
			(layer "F.SilkS")
		)
		(fp_line
			(start 2.11 2.11)
			(end 2.11 1.84)
			(stroke
				(width 0.15)
				(type solid)
			)
			(layer "F.SilkS")
		)
		(fp_circle
			(center -2.25 -1.15)
			(end -2.2 -1.15)
			(stroke
				(width 0.15)
				(type solid)
			)
			(fill yes)
			(layer "F.SilkS")
		)
		(fp_line
			(start -2.55 -2.55)
			(end 2.55 -2.55)
			(stroke
				(width 0.05)
				(type solid)
			)
			(layer "F.CrtYd")
		)
		(fp_line
			(start -2.55 2.55)
			(end -2.55 -2.55)
			(stroke
				(width 0.05)
				(type solid)
			)
			(layer "F.CrtYd")
		)
		(fp_line
			(start 2.55 -2.55)
			(end 2.55 2.55)
			(stroke
				(width 0.05)
				(type solid)
			)
			(layer "F.CrtYd")
		)
		(fp_line
			(start 2.55 2.55)
			(end -2.55 2.55)
			(stroke
				(width 0.05)
				(type solid)
			)
			(layer "F.CrtYd")
		)
		(fp_line
			(start -2 -1)
			(end -2 2)
			(stroke
				(width 0.15)
				(type solid)
			)
			(layer "F.Fab")
		)
		(fp_line
			(start -2 2)
			(end 2 2)
			(stroke
				(width 0.15)
				(type solid)
			)
			(layer "F.Fab")
		)
		(fp_line
			(start -1 -2)
			(end -2 -1)
			(stroke
				(width 0.15)
				(type solid)
			)
			(layer "F.Fab")
		)
		(fp_line
			(start 2 -2)
			(end -1 -2)
			(stroke
				(width 0.15)
				(type solid)
			)
			(layer "F.Fab")
		)
		(fp_line
			(start 2 2)
			(end 2 -2)
			(stroke
				(width 0.15)
				(type solid)
			)
			(layer "F.Fab")
		)
		(fp_text user "Author: Antmicro"
			(at -2.7 8 0)
			(layer "F.Fab")
			(effects
				(font
					(size 0.7 0.7)
					(thickness 0.15)
				)
				(justify left bottom)
			)
		)
		(fp_text user "License: Apache-2.0"
			(at -2.7 5.6 0)
			(layer "F.Fab")
			(effects
				(font
					(size 0.7 0.7)
					(thickness 0.15)
				)
				(justify left bottom)
			)
		)
		(fp_text user "${REFERENCE}"
			(at -2.7 6.8 0)
			(layer "F.Fab")
			(effects
				(font
					(size 0.7 0.7)
					(thickness 0.15)
				)
				(justify left bottom)
			)
		)
		(pad "1" smd roundrect
			(at -1.94 -0.825 90)
			(size 0.3 0.725)
			(layers "F.Cu" "F.Mask" "F.Paste")
			(roundrect_rratio 0.25)
			(net 13 "VCC")
			(pinfunction "V_{IN}")
			(pintype "power_in")
		)
		(pad "2" smd roundrect
			(at -1.94 -0.375 90)
			(size 0.3 0.725)
			(layers "F.Cu" "F.Mask" "F.Paste")
			(roundrect_rratio 0.25)
			(net 13 "VCC")
			(pinfunction "V_{IN}")
			(pintype "passive")
		)
		(pad "3" smd roundrect
			(at -1.94 0.525 90)
			(size 0.3 0.725)
			(layers "F.Cu" "F.Mask" "F.Paste")
			(roundrect_rratio 0.25)
			(net 1 "GND")
			(pinfunction "P_{GND}")
			(pintype "passive")
		)
		(pad "4" smd roundrect
			(at -1.94 0.975 90)
			(size 0.3 0.725)
			(layers "F.Cu" "F.Mask" "F.Paste")
			(roundrect_rratio 0.25)
			(net 1 "GND")
			(pinfunction "P_{GND}")
			(pintype "passive")
		)
		(pad "5" smd custom
			(at -1.475 1.94)
			(size 0.3 0.3)
			(layers "F.Cu" "F.Mask" "F.Paste")
			(net 1182 "/DCDC/3V3_SW")
			(pinfunction "SW")
			(pintype "passive")
			(options
				(clearance outline)
				(anchor circle)
			)
			(primitives
				(gr_poly
					(pts
						(xy -0.15 -0.2875) (xy -0.144291 -0.316201) (xy -0.128033 -0.340533) (xy -0.103701 -0.356791)
						(xy -0.075 -0.3625) (xy 0.075 -0.3625) (xy 0.103701 -0.356791) (xy 0.128033 -0.340533) (xy 0.144291 -0.316201)
						(xy 0.15 -0.2875) (xy 0.15 0.2875) (xy 0.144291 0.316201) (xy 0.128033 0.340533) (xy 0.103701 0.356791)
						(xy 0.075 0.3625) (xy -0.075 0.3625) (xy -0.103701 0.356791) (xy -0.128033 0.340533) (xy -0.144291 0.316201)
						(xy -0.15 0.2875)
					)
					(width 0)
					(fill yes)
				)
				(gr_poly
					(pts
						(xy -0.15 -0.3625) (xy 2.2 -0.3625) (xy 2.2 -0.0875) (xy -0.15 -0.0875)
					)
					(width 0)
					(fill yes)
				)
			)
		)
		(pad "6" smd roundrect
			(at -1.025 1.94)
			(size 0.3 0.725)
			(layers "F.Cu" "F.Mask" "F.Paste")
			(roundrect_rratio 0.25)
			(net 1182 "/DCDC/3V3_SW")
			(pinfunction "SW")
			(pintype "passive")
		)
		(pad "7" smd roundrect
			(at -0.575 1.94)
			(size 0.3 0.725)
			(layers "F.Cu" "F.Mask" "F.Paste")
			(roundrect_rratio 0.25)
			(net 1182 "/DCDC/3V3_SW")
			(pinfunction "SW")
			(pintype "passive")
		)
		(pad "8" smd roundrect
			(at 0.125 1.94)
			(size 0.3 0.725)
			(layers "F.Cu" "F.Mask" "F.Paste")
			(roundrect_rratio 0.25)
			(net 1182 "/DCDC/3V3_SW")
			(pinfunction "SW")
			(pintype "passive")
		)
		(pad "9" smd roundrect
			(at 0.575 1.94)
			(size 0.3 0.725)
			(layers "F.Cu" "F.Mask" "F.Paste")
			(roundrect_rratio 0.25)
			(net 1182 "/DCDC/3V3_SW")
			(pinfunction "SW")
			(pintype "passive")
		)
		(pad "10" smd roundrect
			(at 1.025 1.935)
			(size 0.3 0.725)
			(layers "F.Cu" "F.Mask" "F.Paste")
			(roundrect_rratio 0.25)
			(net 1059 "unconnected-(U13-GL-Pad10)_2")
			(pinfunction "GL")
			(pintype "passive+no_connect")
		)
		(pad "11" smd roundrect
			(at 1.94 1.425 90)
			(size 0.3 0.725)
			(layers "F.Cu" "F.Mask" "F.Paste")
			(roundrect_rratio 0.25)
			(net 1057 "unconnected-(U13-GL-Pad10)")
			(pinfunction "GL")
			(pintype "passive+no_connect")
		)
		(pad "12" smd roundrect
			(at 1.94 0.975 90)
			(size 0.3 0.725)
			(layers "F.Cu" "F.Mask" "F.Paste")
			(roundrect_rratio 0.25)
			(net 24 "/DCDC/3V3_VDRV")
			(pinfunction "V_{DRV}")
			(pintype "passive")
		)
		(pad "13" smd roundrect
			(at 1.94 0.525 90)
			(size 0.3 0.725)
			(layers "F.Cu" "F.Mask" "F.Paste")
			(roundrect_rratio 0.25)
			(net 1 "GND")
			(pinfunction "P_{GND}")
			(pintype "power_in")
		)
		(pad "14" smd roundrect
			(at 1.94 0.075 90)
			(size 0.3 0.725)
			(layers "F.Cu" "F.Mask" "F.Paste")
			(roundrect_rratio 0.25)
			(net 1056 "unconnected-(U13-P_{GOOD}-Pad14)")
			(pinfunction "P_{GOOD}")
			(pintype "output+no_connect")
		)
		(pad "15" smd roundrect
			(at 1.94 -0.375 90)
			(size 0.3 0.725)
			(layers "F.Cu" "F.Mask" "F.Paste")
			(roundrect_rratio 0.25)
			(net 19 "/DCDC/3V3_VDD")
			(pinfunction "V_{DD}")
			(pintype "passive")
		)
		(pad "16" smd roundrect
			(at 1.94 -0.825 90)
			(size 0.3 0.725)
			(layers "F.Cu" "F.Mask" "F.Paste")
			(roundrect_rratio 0.25)
			(net 1 "GND")
			(pinfunction "A_{GND}")
			(pintype "power_in")
		)
		(pad "17" smd roundrect
			(at 1.94 -1.275 90)
			(size 0.3 0.725)
			(layers "F.Cu" "F.Mask" "F.Paste")
			(roundrect_rratio 0.25)
			(net 1218 "/DCDC/3V3_FB")
			(pinfunction "FB")
			(pintype "passive")
		)
		(pad "18" smd roundrect
			(at 1.475 -1.94)
			(size 0.3 0.725)
			(layers "F.Cu" "F.Mask" "F.Paste")
			(roundrect_rratio 0.25)
			(net 567 "/DCDC/3V3_OUT")
			(pinfunction "V_{OUT}")
			(pintype "passive")
		)
		(pad "19" smd roundrect
			(at 1.025 -1.94)
			(size 0.3 0.725)
			(layers "F.Cu" "F.Mask" "F.Paste")
			(roundrect_rratio 0.25)
			(net 1293 "/DCDC/CARRIER_PWR_ON")
			(pinfunction "EN")
			(pintype "input")
		)
		(pad "20" smd roundrect
			(at 0.575 -1.94)
			(size 0.3 0.725)
			(layers "F.Cu" "F.Mask" "F.Paste")
			(roundrect_rratio 0.25)
			(net 1216 "/DCDC/3V3_MODE2")
			(pinfunction "MODE2")
			(pintype "input")
		)
		(pad "21" smd roundrect
			(at 0.125 -1.94)
			(size 0.3 0.725)
			(layers "F.Cu" "F.Mask" "F.Paste")
			(roundrect_rratio 0.25)
			(net 1213 "/DCDC/3V3_MODE1")
			(pinfunction "MODE1")
			(pintype "input")
		)
		(pad "22" smd roundrect
			(at -0.575 -1.94)
			(size 0.3 0.725)
			(layers "F.Cu" "F.Mask" "F.Paste")
			(roundrect_rratio 0.25)
			(net 13 "VCC")
			(pinfunction "V_{IN}")
			(pintype "passive")
		)
		(pad "23" smd roundrect
			(at -1.025 -1.94)
			(size 0.3 0.725)
			(layers "F.Cu" "F.Mask" "F.Paste")
			(roundrect_rratio 0.25)
			(net 28 "/DCDC/3V3_BOOT")
			(pinfunction "BOOT")
			(pintype "passive")
		)
		(pad "24" smd roundrect
			(at -1.475 -1.94)
			(size 0.3 0.725)
			(layers "F.Cu" "F.Mask" "F.Paste")
			(roundrect_rratio 0.25)
			(net 29 "/DCDC/3V3_PHASE")
			(pinfunction "PHASE")
			(pintype "passive")
		)
		(pad "25" smd rect
			(at 0.49 -0.75 180)
			(size 1.575 1.05)
			(layers "F.Cu" "F.Mask" "F.Paste")
			(net 1 "GND")
			(pinfunction "A_{GND}")
			(pintype "passive")
		)
		(pad "26" smd rect
			(at -1.175 -0.75 180)
			(size 1.15 1.05)
			(layers "F.Cu" "F.Mask" "F.Paste")
			(net 13 "VCC")
			(pinfunction "V_{IN}")
			(pintype "passive")
		)
		(pad "27" smd custom
			(at -0.75 0.775)
			(size 1 1)
			(layers "F.Cu" "F.Mask" "F.Paste")
			(net 1 "GND")
			(pinfunction "P_{GND}")
			(pintype "passive")
			(options
				(clearance outline)
				(anchor rect)
			)
			(primitives
				(gr_poly
					(pts
						(xy -1 0.5) (xy -1 -0.7) (xy 1.825 -0.7) (xy 1.825 -0.245) (xy 1.175 -0.245) (xy 1.175 0.5)
					)
					(width 0)
					(fill yes)
				)
			)
		)
		(pad "28" smd rect
			(at 0.985 0.99 180)
			(size 0.58 0.38)
			(layers "F.Cu" "F.Mask" "F.Paste")
			(net 1058 "unconnected-(U13-GL-Pad10)_1")
			(pinfunction "GL")
			(pintype "passive+no_connect")
		)
	)
	(footprint "antmicro-footprints:C_0805_2012Metric"
		(layer "F.Cu")
		(at 172.37 110.346 90)
		(descr "Capacitor SMD 0805")
		(tags "capacitor SMD 0805")
		(property "Reference" "C267"
			(at 1.79 0.36 90)
			(layer "F.SilkS")
			(effects
				(font
					(size 0.7 0.7)
					(thickness 0.15)
				)
				(justify left bottom)
			)
		)
		(property "Value" "C_22u_25V_0805"
			(at -2.055717 1.963152 90)
			(layer "F.Fab")
			(effects
				(font
					(size 0.7 0.7)
					(thickness 0.15)
				)
				(justify left bottom)
			)
		)
		(property "Datasheet" "https://product.samsungsem.com/mlcc/CL21A226MAYNNN.do"
			(at 0 0 90)
			(layer "F.Fab")
			(hide yes)
			(effects
				(font
					(size 1.27 1.27)
					(thickness 0.15)
				)
			)
		)
		(property "Description" "SMT Multilayer Ceramic Capacitor, 22uF, +/-20%, 25V, X5R, 0805 [2012 Metric]"
			(at 0 0 90)
			(layer "F.Fab")
			(hide yes)
			(effects
				(font
					(size 1.27 1.27)
					(thickness 0.15)
				)
			)
		)
		(property "MPN" "CL21A226MAYNNNE"
			(at 0 0 90)
			(unlocked yes)
			(layer "F.Fab")
			(hide yes)
			(effects
				(font
					(size 1 1)
					(thickness 0.15)
				)
			)
		)
		(property "Manufacturer" "Samsung Electro-Mechanics"
			(at 0 0 90)
			(unlocked yes)
			(layer "F.Fab")
			(hide yes)
			(effects
				(font
					(size 1 1)
					(thickness 0.15)
				)
			)
		)
		(property "License" "Apache-2.0"
			(at 0 0 90)
			(unlocked yes)
			(layer "F.Fab")
			(hide yes)
			(effects
				(font
					(size 1 1)
					(thickness 0.15)
				)
			)
		)
		(property "Author" "Antmicro"
			(at 0 0 90)
			(unlocked yes)
			(layer "F.Fab")
			(hide yes)
			(effects
				(font
					(size 1 1)
					(thickness 0.15)
				)
			)
		)
		(property "Val" "22u"
			(at 0 0 90)
			(unlocked yes)
			(layer "F.Fab")
			(hide yes)
			(effects
				(font
					(size 1 1)
					(thickness 0.15)
				)
			)
		)
		(property "Voltage" "25V"
			(at 0 0 90)
			(unlocked yes)
			(layer "F.Fab")
			(hide yes)
			(effects
				(font
					(size 1 1)
					(thickness 0.15)
				)
			)
		)
		(property "Dielectric" "X5R"
			(at 0 0 90)
			(unlocked yes)
			(layer "F.Fab")
			(hide yes)
			(effects
				(font
					(size 1 1)
					(thickness 0.15)
				)
			)
		)
		(property "Public" "False"
			(at 0 0 90)
			(unlocked yes)
			(layer "F.Fab")
			(hide yes)
			(effects
				(font
					(size 1 1)
					(thickness 0.15)
				)
			)
		)
		(sheetname "/DCDC/")
		(sheetfile "dcdc.kicad_sch")
		(attr smd)
		(fp_line
			(start -0.3 -0.7)
			(end 0.3 -0.7)
			(stroke
				(width 0.15)
				(type solid)
			)
			(layer "F.SilkS")
		)
		(fp_line
			(start -0.3 0.7)
			(end 0.3 0.7)
			(stroke
				(width 0.15)
				(type solid)
			)
			(layer "F.SilkS")
		)
		(fp_rect
			(start 1.95 -0.9)
			(end -1.95 0.9)
			(stroke
				(width 0.05)
				(type default)
			)
			(fill no)
			(layer "F.CrtYd")
		)
		(fp_rect
			(start -0.95 -0.675)
			(end 0.95 0.675)
			(stroke
				(width 0.15)
				(type solid)
			)
			(fill no)
			(layer "F.Fab")
		)
		(fp_text user "Author: Antmicro"
			(at -1.9 5.947 90)
			(layer "F.Fab")
			(effects
				(font
					(size 0.7 0.7)
					(thickness 0.15)
				)
				(justify left bottom)
			)
		)
		(fp_text user "${REFERENCE}"
			(at -1.9 3.947 90)
			(layer "F.Fab")
			(effects
				(font
					(size 0.7 0.7)
					(thickness 0.15)
				)
				(justify left bottom)
			)
		)
		(fp_text user "License: Apache-2.0"
			(at -1.9 4.947 90)
			(layer "F.Fab")
			(effects
				(font
					(size 0.7 0.7)
					(thickness 0.15)
				)
				(justify left bottom)
			)
		)
		(pad "1" smd roundrect
			(at -1.1 0 90)
			(size 1.2 1.3)
			(layers "F.Cu" "F.Mask" "F.Paste")
			(roundrect_rratio 0.25)
			(net 1 "GND")
			(pintype "passive")
		)
		(pad "2" smd roundrect
			(at 1.1 0 90)
			(size 1.2 1.3)
			(layers "F.Cu" "F.Mask" "F.Paste")
			(roundrect_rratio 0.25)
			(net 13 "VCC")
			(pintype "passive")
		)
	)
	(footprint "antmicro-footprints:C_0402_1005Metric"
		(layer "F.Cu")
		(at 218.695 125.675 180)
		(descr "Capacitor SMD 0402")
		(tags "capacitor SMD 0402")
		(property "Reference" "C103"
			(at 0.835 0.365 0)
			(layer "F.SilkS")
			(effects
				(font
					(size 0.7 0.7)
					(thickness 0.15)
				)
				(justify right top)
			)
		)
		(property "Value" "C_100n_0402"
			(at -1.022927 2.155213 0)
			(layer "F.Fab")
			(effects
				(font
					(size 0.7 0.7)
					(thickness 0.15)
				)
				(justify right top)
			)
		)
		(property "Datasheet" "https://www.murata.com/products/productdetail?partno=GRM155R61H104KE14%23"
			(at 0 0 0)
			(layer "F.Fab")
			(hide yes)
			(effects
				(font
					(size 1.27 1.27)
					(thickness 0.15)
				)
			)
		)
		(property "Description" "SMD Multilayer Ceramic Capacitor, 0.1 µF, 50 V, 0402 [1005 Metric], ± 10%, X5R, GRM Series"
			(at 0 0 0)
			(layer "F.Fab")
			(hide yes)
			(effects
				(font
					(size 1.27 1.27)
					(thickness 0.15)
				)
			)
		)
		(property "Manufacturer" "Murata"
			(at 0 0 180)
			(unlocked yes)
			(layer "F.Fab")
			(hide yes)
			(effects
				(font
					(size 1 1)
					(thickness 0.15)
				)
			)
		)
		(property "MPN" "GRM155R61H104KE14D"
			(at 0 0 180)
			(unlocked yes)
			(layer "F.Fab")
			(hide yes)
			(effects
				(font
					(size 1 1)
					(thickness 0.15)
				)
			)
		)
		(property "Val" "100n"
			(at 0 0 180)
			(unlocked yes)
			(layer "F.Fab")
			(hide yes)
			(effects
				(font
					(size 1 1)
					(thickness 0.15)
				)
			)
		)
		(property "License" "Apache-2.0"
			(at 0 0 180)
			(unlocked yes)
			(layer "F.Fab")
			(hide yes)
			(effects
				(font
					(size 1 1)
					(thickness 0.15)
				)
			)
		)
		(property "Author" "Antmicro"
			(at 0 0 180)
			(unlocked yes)
			(layer "F.Fab")
			(hide yes)
			(effects
				(font
					(size 1 1)
					(thickness 0.15)
				)
			)
		)
		(property "Voltage" "50V"
			(at 0 0 180)
			(unlocked yes)
			(layer "F.Fab")
			(hide yes)
			(effects
				(font
					(size 1 1)
					(thickness 0.15)
				)
			)
		)
		(property "Dielectric" "X5R"
			(at 0 0 180)
			(unlocked yes)
			(layer "F.Fab")
			(hide yes)
			(effects
				(font
					(size 1 1)
					(thickness 0.15)
				)
			)
		)
		(sheetname "/USB Hub/")
		(sheetfile "usb_hub.kicad_sch")
		(attr smd)
		(fp_rect
			(start -0.925 -0.47)
			(end 0.925 0.47)
			(stroke
				(width 0.05)
				(type default)
			)
			(fill no)
			(layer "F.CrtYd")
		)
		(fp_line
			(start 0.504 0.248)
			(end -0.494 0.248)
			(stroke
				(width 0.15)
				(type solid)
			)
			(layer "F.Fab")
		)
		(fp_line
			(start 0.504 -0.25)
			(end 0.504 0.248)
			(stroke
				(width 0.15)
				(type solid)
			)
			(layer "F.Fab")
		)
		(fp_line
			(start -0.494 0.248)
			(end -0.494 -0.25)
			(stroke
				(width 0.15)
				(type solid)
			)
			(layer "F.Fab")
		)
		(fp_line
			(start -0.494 -0.25)
			(end 0.504 -0.25)
			(stroke
				(width 0.15)
				(type solid)
			)
			(layer "F.Fab")
		)
		(fp_text user "Author: Antmicro"
			(at -0.939 3.399 0)
			(layer "F.Fab")
			(effects
				(font
					(size 0.7 0.7)
					(thickness 0.15)
				)
				(justify right top)
			)
		)
		(fp_text user "${REFERENCE}"
			(at -0.939 4.599 0)
			(layer "F.Fab")
			(effects
				(font
					(size 0.7 0.7)
					(thickness 0.15)
				)
				(justify right top)
			)
		)
		(fp_text user "License: Apache-2.0"
			(at -0.939 5.799 0)
			(layer "F.Fab")
			(effects
				(font
					(size 0.7 0.7)
					(thickness 0.15)
				)
				(justify right top)
			)
		)
		(pad "1" smd roundrect
			(at -0.48 0 180)
			(size 0.59 0.64)
			(layers "F.Cu" "F.Mask" "F.Paste")
			(roundrect_rratio 0.25)
			(net 110 "/USB Hub/USBC4_CONN_TX2_N")
			(pintype "passive")
		)
		(pad "2" smd roundrect
			(at 0.48 0 180)
			(size 0.59 0.64)
			(layers "F.Cu" "F.Mask" "F.Paste")
			(roundrect_rratio 0.25)
			(net 214 "/USB Hub/USBC4_TX_{2}-")
			(pintype "passive")
		)
	)
	(footprint "antmicro-footprints:C_0402_1005Metric"
		(layer "F.Cu")
		(at 152.48 116.1 180)
		(descr "Capacitor SMD 0402")
		(tags "capacitor SMD 0402")
		(property "Reference" "C1"
			(at -2.52 1.7 0)
			(layer "F.SilkS")
			(effects
				(font
					(size 0.7 0.7)
					(thickness 0.15)
				)
				(justify right top)
			)
		)
		(property "Value" "C_100n_0402"
			(at -1.022927 2.155213 0)
			(layer "F.Fab")
			(effects
				(font
					(size 0.7 0.7)
					(thickness 0.15)
				)
				(justify right top)
			)
		)
		(property "Datasheet" "https://www.murata.com/products/productdetail?partno=GRM155R61H104KE14%23"
			(at 0 0 0)
			(layer "F.Fab")
			(hide yes)
			(effects
				(font
					(size 1.27 1.27)
					(thickness 0.15)
				)
			)
		)
		(property "Description" "SMD Multilayer Ceramic Capacitor, 0.1 µF, 50 V, 0402 [1005 Metric], ± 10%, X5R, GRM Series"
			(at 0 0 0)
			(layer "F.Fab")
			(hide yes)
			(effects
				(font
					(size 1.27 1.27)
					(thickness 0.15)
				)
			)
		)
		(property "Manufacturer" "Murata"
			(at 0 0 180)
			(unlocked yes)
			(layer "F.Fab")
			(hide yes)
			(effects
				(font
					(size 1 1)
					(thickness 0.15)
				)
			)
		)
		(property "MPN" "GRM155R61H104KE14D"
			(at 0 0 180)
			(unlocked yes)
			(layer "F.Fab")
			(hide yes)
			(effects
				(font
					(size 1 1)
					(thickness 0.15)
				)
			)
		)
		(property "Val" "100n"
			(at 0 0 180)
			(unlocked yes)
			(layer "F.Fab")
			(hide yes)
			(effects
				(font
					(size 1 1)
					(thickness 0.15)
				)
			)
		)
		(property "License" "Apache-2.0"
			(at 0 0 180)
			(unlocked yes)
			(layer "F.Fab")
			(hide yes)
			(effects
				(font
					(size 1 1)
					(thickness 0.15)
				)
			)
		)
		(property "Author" "Antmicro"
			(at 0 0 180)
			(unlocked yes)
			(layer "F.Fab")
			(hide yes)
			(effects
				(font
					(size 1 1)
					(thickness 0.15)
				)
			)
		)
		(property "Voltage" "50V"
			(at 0 0 180)
			(unlocked yes)
			(layer "F.Fab")
			(hide yes)
			(effects
				(font
					(size 1 1)
					(thickness 0.15)
				)
			)
		)
		(property "Dielectric" "X5R"
			(at 0 0 180)
			(unlocked yes)
			(layer "F.Fab")
			(hide yes)
			(effects
				(font
					(size 1 1)
					(thickness 0.15)
				)
			)
		)
		(sheetname "/SoM_IO/")
		(sheetfile "som_io.kicad_sch")
		(attr smd)
		(fp_poly
			(pts
				(xy -0.925 -0.47) (xy -0.925 0.47) (xy 0.925 0.47) (xy 0.925 -0.47)
			)
			(stroke
				(width 0.05)
				(type default)
			)
			(fill no)
			(layer "F.CrtYd")
		)
		(fp_line
			(start 0.504 0.248)
			(end -0.494 0.248)
			(stroke
				(width 0.15)
				(type solid)
			)
			(layer "F.Fab")
		)
		(fp_line
			(start 0.504 -0.25)
			(end 0.504 0.248)
			(stroke
				(width 0.15)
				(type solid)
			)
			(layer "F.Fab")
		)
		(fp_line
			(start -0.494 0.248)
			(end -0.494 -0.25)
			(stroke
				(width 0.15)
				(type solid)
			)
			(layer "F.Fab")
		)
		(fp_line
			(start -0.494 -0.25)
			(end 0.504 -0.25)
			(stroke
				(width 0.15)
				(type solid)
			)
			(layer "F.Fab")
		)
		(fp_text user "Author: Antmicro"
			(at -0.939 3.399 0)
			(layer "F.Fab")
			(effects
				(font
					(size 0.7 0.7)
					(thickness 0.15)
				)
				(justify right top)
			)
		)
		(fp_text user "${REFERENCE}"
			(at -0.939 4.599 0)
			(layer "F.Fab")
			(effects
				(font
					(size 0.7 0.7)
					(thickness 0.15)
				)
				(justify right top)
			)
		)
		(fp_text user "License: Apache-2.0"
			(at -0.939 5.799 0)
			(layer "F.Fab")
			(effects
				(font
					(size 0.7 0.7)
					(thickness 0.15)
				)
				(justify right top)
			)
		)
		(pad "1" smd roundrect
			(at -0.48 0 180)
			(size 0.59 0.64)
			(layers "F.Cu" "F.Mask" "F.Paste")
			(roundrect_rratio 0.25)
			(net 1 "GND")
			(pintype "passive")
		)
		(pad "2" smd roundrect
			(at 0.48 0 180)
			(size 0.59 0.64)
			(layers "F.Cu" "F.Mask" "F.Paste")
			(roundrect_rratio 0.25)
			(net 11 "+1V8")
			(pintype "passive")
		)
	)
	(footprint "antmicro-footprints:C_0402_1005Metric"
		(layer "F.Cu")
		(at 201.7 133.7 90)
		(descr "Capacitor SMD 0402")
		(tags "capacitor SMD 0402")
		(property "Reference" "C96"
			(at -1.1 -1.8 90)
			(layer "F.SilkS")
			(effects
				(font
					(size 0.7 0.7)
					(thickness 0.15)
				)
				(justify left bottom)
			)
		)
		(property "Value" "C_100n_0402"
			(at -1.022927 2.155213 90)
			(layer "F.Fab")
			(effects
				(font
					(size 0.7 0.7)
					(thickness 0.15)
				)
				(justify left bottom)
			)
		)
		(property "Datasheet" "https://www.murata.com/products/productdetail?partno=GRM155R61H104KE14%23"
			(at 0 0 90)
			(layer "F.Fab")
			(hide yes)
			(effects
				(font
					(size 1.27 1.27)
					(thickness 0.15)
				)
			)
		)
		(property "Description" "SMD Multilayer Ceramic Capacitor, 0.1 µF, 50 V, 0402 [1005 Metric], ± 10%, X5R, GRM Series"
			(at 0 0 90)
			(layer "F.Fab")
			(hide yes)
			(effects
				(font
					(size 1.27 1.27)
					(thickness 0.15)
				)
			)
		)
		(property "MPN" "GRM155R61H104KE14D"
			(at 0 0 90)
			(unlocked yes)
			(layer "F.Fab")
			(hide yes)
			(effects
				(font
					(size 1 1)
					(thickness 0.15)
				)
			)
		)
		(property "Val" "100n"
			(at 0 0 90)
			(unlocked yes)
			(layer "F.Fab")
			(hide yes)
			(effects
				(font
					(size 1 1)
					(thickness 0.15)
				)
			)
		)
		(property "Voltage" "50V"
			(at 0 0 90)
			(unlocked yes)
			(layer "F.Fab")
			(hide yes)
			(effects
				(font
					(size 1 1)
					(thickness 0.15)
				)
			)
		)
		(property "Dielectric" "X5R"
			(at 0 0 90)
			(unlocked yes)
			(layer "F.Fab")
			(hide yes)
			(effects
				(font
					(size 1 1)
					(thickness 0.15)
				)
			)
		)
		(property "Manufacturer" "Murata"
			(at 0 0 90)
			(unlocked yes)
			(layer "F.Fab")
			(hide yes)
			(effects
				(font
					(size 1 1)
					(thickness 0.15)
				)
			)
		)
		(property "License" "Apache-2.0"
			(at 0 0 90)
			(unlocked yes)
			(layer "F.Fab")
			(hide yes)
			(effects
				(font
					(size 1 1)
					(thickness 0.15)
				)
			)
		)
		(property "Author" "Antmicro"
			(at 0 0 90)
			(unlocked yes)
			(layer "F.Fab")
			(hide yes)
			(effects
				(font
					(size 1 1)
					(thickness 0.15)
				)
			)
		)
		(sheetname "/USB Hub/")
		(sheetfile "usb_hub.kicad_sch")
		(attr smd)
		(fp_rect
			(start -0.925 -0.47)
			(end 0.925 0.47)
			(stroke
				(width 0.05)
				(type default)
			)
			(fill no)
			(layer "F.CrtYd")
		)
		(fp_line
			(start 0.504 -0.25)
			(end 0.504 0.248)
			(stroke
				(width 0.15)
				(type solid)
			)
			(layer "F.Fab")
		)
		(fp_line
			(start -0.494 -0.25)
			(end 0.504 -0.25)
			(stroke
				(width 0.15)
				(type solid)
			)
			(layer "F.Fab")
		)
		(fp_line
			(start 0.504 0.248)
			(end -0.494 0.248)
			(stroke
				(width 0.15)
				(type solid)
			)
			(layer "F.Fab")
		)
		(fp_line
			(start -0.494 0.248)
			(end -0.494 -0.25)
			(stroke
				(width 0.15)
				(type solid)
			)
			(layer "F.Fab")
		)
		(fp_text user "${REFERENCE}"
			(at -0.939 4.599 90)
			(layer "F.Fab")
			(effects
				(font
					(size 0.7 0.7)
					(thickness 0.15)
				)
				(justify left bottom)
			)
		)
		(fp_text user "Author: Antmicro"
			(at -0.939 3.399 90)
			(layer "F.Fab")
			(effects
				(font
					(size 0.7 0.7)
					(thickness 0.15)
				)
				(justify left bottom)
			)
		)
		(fp_text user "License: Apache-2.0"
			(at -0.939 5.799 90)
			(layer "F.Fab")
			(effects
				(font
					(size 0.7 0.7)
					(thickness 0.15)
				)
				(justify left bottom)
			)
		)
		(pad "1" smd roundrect
			(at -0.48 0 90)
			(size 0.59 0.64)
			(layers "F.Cu" "F.Mask" "F.Paste")
			(roundrect_rratio 0.25)
			(net 1 "GND")
			(pintype "passive")
		)
		(pad "2" smd roundrect
			(at 0.48 0 90)
			(size 0.59 0.64)
			(layers "F.Cu" "F.Mask" "F.Paste")
			(roundrect_rratio 0.25)
			(net 2 "+3V3")
			(pintype "passive")
		)
	)
	(footprint "antmicro-footprints:R_0402_1005Metric"
		(layer "F.Cu")
		(at 183.754468 88.785 90)
		(descr "Resistor SMD 0402")
		(tags "resistor SMD 0402")
		(property "Reference" "R70"
			(at -1.03 2.61 90)
			(layer "F.SilkS")
			(effects
				(font
					(size 0.7 0.7)
					(thickness 0.15)
				)
				(justify left bottom)
			)
		)
		(property "Value" "R_10k_0402"
			(at -1.011843 1.772047 90)
			(layer "F.Fab")
			(effects
				(font
					(size 0.7 0.7)
					(thickness 0.15)
				)
				(justify left bottom)
			)
		)
		(property "Datasheet" "https://www.bourns.com/docs/product-datasheets/cr.pdf"
			(at 0 0 90)
			(layer "F.Fab")
			(hide yes)
			(effects
				(font
					(size 1.27 1.27)
					(thickness 0.15)
				)
			)
		)
		(property "Description" "SMD Chip Resistor, 10 kohm, ± 1%, 62.5 mW, 0402 [1005 Metric], Thick Film, General Purpose"
			(at 0 0 90)
			(layer "F.Fab")
			(hide yes)
			(effects
				(font
					(size 1.27 1.27)
					(thickness 0.15)
				)
			)
		)
		(property "MPN" "CR0402-FX-1002GLF"
			(at 0 0 90)
			(unlocked yes)
			(layer "F.Fab")
			(hide yes)
			(effects
				(font
					(size 1 1)
					(thickness 0.15)
				)
			)
		)
		(property "Manufacturer" "Bourns"
			(at 0 0 90)
			(unlocked yes)
			(layer "F.Fab")
			(hide yes)
			(effects
				(font
					(size 1 1)
					(thickness 0.15)
				)
			)
		)
		(property "License" "Apache-2.0"
			(at 0 0 90)
			(unlocked yes)
			(layer "F.Fab")
			(hide yes)
			(effects
				(font
					(size 1 1)
					(thickness 0.15)
				)
			)
		)
		(property "Author" "Antmicro"
			(at 0 0 90)
			(unlocked yes)
			(layer "F.Fab")
			(hide yes)
			(effects
				(font
					(size 1 1)
					(thickness 0.15)
				)
			)
		)
		(property "Val" "10k"
			(at 0 0 90)
			(unlocked yes)
			(layer "F.Fab")
			(hide yes)
			(effects
				(font
					(size 1 1)
					(thickness 0.15)
				)
			)
		)
		(property "Tolerance" "1%"
			(at 0 0 90)
			(unlocked yes)
			(layer "F.Fab")
			(hide yes)
			(effects
				(font
					(size 1 1)
					(thickness 0.15)
				)
			)
		)
		(component_classes
			(class "DCDC_SOM")
		)
		(sheetname "/DCDC/")
		(sheetfile "dcdc.kicad_sch")
		(attr smd)
		(fp_rect
			(start -0.925 -0.47)
			(end 0.925 0.47)
			(stroke
				(width 0.05)
				(type default)
			)
			(fill no)
			(layer "F.CrtYd")
		)
		(fp_rect
			(start -0.5 -0.25)
			(end 0.5 0.25)
			(stroke
				(width 0.15)
				(type solid)
			)
			(fill no)
			(layer "F.Fab")
		)
		(fp_text user "License: Apache-2.0"
			(at -0.95 5.169 90)
			(layer "F.Fab")
			(effects
				(font
					(size 0.7 0.7)
					(thickness 0.15)
				)
				(justify left bottom)
			)
		)
		(fp_text user "${REFERENCE}"
			(at -0.95 3.168 90)
			(layer "F.Fab")
			(effects
				(font
					(size 0.7 0.7)
					(thickness 0.15)
				)
				(justify left bottom)
			)
		)
		(fp_text user "Author: Antmicro"
			(at -0.95 4.169 90)
			(layer "F.Fab")
			(effects
				(font
					(size 0.7 0.7)
					(thickness 0.15)
				)
				(justify left bottom)
			)
		)
		(pad "1" smd roundrect
			(at -0.48 0 90)
			(size 0.59 0.64)
			(layers "F.Cu" "F.Mask" "F.Paste")
			(roundrect_rratio 0.25)
			(net 1 "GND")
			(pintype "passive")
		)
		(pad "2" smd roundrect
			(at 0.48 0 90)
			(size 0.59 0.64)
			(layers "F.Cu" "F.Mask" "F.Paste")
			(roundrect_rratio 0.25)
			(net 1219 "/DCDC/16V_FB")
			(pintype "passive")
		)
	)
	(footprint "antmicro-footprints:XSON-8_1x1.95mm_P0.5mm"
		(layer "F.Cu")
		(at 65.6 97.2 180)
		(property "Reference" "U48"
			(at 1.2 1.4 180)
			(layer "F.SilkS")
			(effects
				(font
					(size 0.7 0.7)
					(thickness 0.15)
				)
				(justify left bottom)
			)
		)
		(property "Value" "NTS0102_XSON"
			(at 0 2.2 180)
			(layer "F.Fab")
			(effects
				(font
					(size 0.7 0.7)
					(thickness 0.15)
				)
				(justify left bottom)
			)
		)
		(property "Datasheet" "http://www.farnell.com/datasheets/1760723.pdf"
			(at 0 0 180)
			(layer "F.Fab")
			(hide yes)
			(effects
				(font
					(size 1.27 1.27)
					(thickness 0.15)
				)
			)
		)
		(property "Description" "Transceiver, 1.65 V to 3.6 V, XSON-8"
			(at 0 0 180)
			(layer "F.Fab")
			(hide yes)
			(effects
				(font
					(size 1.27 1.27)
					(thickness 0.15)
				)
			)
		)
		(property "MPN" "NTS0102GT"
			(at 0 0 180)
			(unlocked yes)
			(layer "F.Fab")
			(hide yes)
			(effects
				(font
					(size 1 1)
					(thickness 0.15)
				)
			)
		)
		(property "Manufacturer" "NXP"
			(at 0 0 180)
			(unlocked yes)
			(layer "F.Fab")
			(hide yes)
			(effects
				(font
					(size 1 1)
					(thickness 0.15)
				)
			)
		)
		(property "Author" "Antmicro"
			(at 0 0 180)
			(unlocked yes)
			(layer "F.Fab")
			(hide yes)
			(effects
				(font
					(size 1 1)
					(thickness 0.15)
				)
			)
		)
		(property "License" "Apache-2.0"
			(at 0 0 180)
			(unlocked yes)
			(layer "F.Fab")
			(hide yes)
			(effects
				(font
					(size 1 1)
					(thickness 0.15)
				)
			)
		)
		(sheetname "/CSI/")
		(sheetfile "csi.kicad_sch")
		(attr smd)
		(fp_line
			(start 0.5 1.1)
			(end -0.5 1.1)
			(stroke
				(width 0.15)
				(type solid)
			)
			(layer "F.SilkS")
		)
		(fp_line
			(start -0.5 -1.1)
			(end 0.5 -1.1)
			(stroke
				(width 0.15)
				(type solid)
			)
			(layer "F.SilkS")
		)
		(fp_circle
			(center -0.75 -1.1)
			(end -0.701 -1.1)
			(stroke
				(width 0.15)
				(type solid)
			)
			(fill no)
			(layer "F.SilkS")
		)
		(fp_rect
			(start -0.8 -1.2)
			(end 0.8 1.2)
			(stroke
				(width 0.05)
				(type solid)
			)
			(fill no)
			(layer "F.CrtYd")
		)
		(fp_line
			(start 0.5305 1)
			(end -0.5305 1)
			(stroke
				(width 0.15)
				(type solid)
			)
			(layer "F.Fab")
		)
		(fp_line
			(start 0.5305 -1.001)
			(end 0.5305 1)
			(stroke
				(width 0.15)
				(type solid)
			)
			(layer "F.Fab")
		)
		(fp_line
			(start -0.5305 1)
			(end -0.5305 -1.001)
			(stroke
				(width 0.15)
				(type solid)
			)
			(layer "F.Fab")
		)
		(fp_line
			(start -0.5305 -1.001)
			(end 0.5305 -1.001)
			(stroke
				(width 0.15)
				(type solid)
			)
			(layer "F.Fab")
		)
		(fp_text user "License: Apache-2.0"
			(at -0.527 8.306 180)
			(layer "F.Fab")
			(effects
				(font
					(size 0.7 0.7)
					(thickness 0.15)
				)
				(justify left bottom)
			)
		)
		(fp_text user "Author: Antmicro"
			(at -0.527 7.105 180)
			(layer "F.Fab")
			(effects
				(font
					(size 0.7 0.7)
					(thickness 0.15)
				)
				(justify left bottom)
			)
		)
		(fp_text user "${REFERENCE}"
			(at -0.527 5.905 180)
			(layer "F.Fab")
			(effects
				(font
					(size 0.7 0.7)
					(thickness 0.15)
				)
				(justify left bottom)
			)
		)
		(pad "1" smd roundrect
			(at -0.45 -0.75)
			(size 0.6 0.3)
			(layers "F.Cu" "F.Mask" "F.Paste")
			(roundrect_rratio 0.25)
			(net 194 "/CSI/VSYNC_CAM1_3V3")
			(pinfunction "B_{2}")
			(pintype "bidirectional")
		)
		(pad "2" smd roundrect
			(at -0.45 -0.25)
			(size 0.6 0.25)
			(layers "F.Cu" "F.Mask" "F.Paste")
			(roundrect_rratio 0.25)
			(net 1 "GND")
			(pinfunction "GND")
			(pintype "power_in")
		)
		(pad "3" smd roundrect
			(at -0.45 0.25)
			(size 0.6 0.25)
			(layers "F.Cu" "F.Mask" "F.Paste")
			(roundrect_rratio 0.25)
			(net 11 "+1V8")
			(pinfunction "VCC_{A}")
			(pintype "power_in")
		)
		(pad "4" smd roundrect
			(at -0.45 0.75)
			(size 0.6 0.3)
			(layers "F.Cu" "F.Mask" "F.Paste")
			(roundrect_rratio 0.25)
			(net 131 "/CSI/CAM_CTRL.VSYNC_CAM1")
			(pinfunction "A_{2}")
			(pintype "bidirectional")
		)
		(pad "5" smd roundrect
			(at 0.45 0.75)
			(size 0.6 0.3)
			(layers "F.Cu" "F.Mask" "F.Paste")
			(roundrect_rratio 0.25)
			(net 155 "/CSI/CAM_CTRL.VSYNC_CAM0")
			(pinfunction "A_{1}")
			(pintype "bidirectional")
		)
		(pad "6" smd roundrect
			(at 0.45 0.25)
			(size 0.6 0.25)
			(layers "F.Cu" "F.Mask" "F.Paste")
			(roundrect_rratio 0.25)
			(net 11 "+1V8")
			(pinfunction "OE")
			(pintype "input")
		)
		(pad "7" smd roundrect
			(at 0.45 -0.25)
			(size 0.6 0.25)
			(layers "F.Cu" "F.Mask" "F.Paste")
			(roundrect_rratio 0.25)
			(net 2 "+3V3")
			(pinfunction "VCC_{B}")
			(pintype "power_in")
		)
		(pad "8" smd roundrect
			(at 0.45 -0.75)
			(size 0.6 0.3)
			(layers "F.Cu" "F.Mask" "F.Paste")
			(roundrect_rratio 0.25)
			(net 186 "/CSI/VSYNC_CAM0_3V3")
			(pinfunction "B_{1}")
			(pintype "bidirectional")
		)
	)
	(footprint "antmicro-footprints:TP_SMD_0.75mm"
		(layer "F.Cu")
		(at 202.1 73.45 -90)
		(property "Reference" "TP10"
			(at -3.35 0.1 90)
			(layer "F.SilkS")
			(effects
				(font
					(size 0.7 0.7)
					(thickness 0.15)
				)
				(justify right top)
			)
		)
		(property "Value" "TP_0.75mm_SMD"
			(at 0 1.2 90)
			(layer "F.Fab")
			(effects
				(font
					(size 0.7 0.7)
					(thickness 0.15)
				)
				(justify right top)
			)
		)
		(property "Description" "SMT test point"
			(at 0 0 90)
			(layer "F.Fab")
			(hide yes)
			(effects
				(font
					(size 1.27 1.27)
					(thickness 0.15)
				)
			)
		)
		(property "MPN" ""
			(at 0 0 270)
			(unlocked yes)
			(layer "F.Fab")
			(hide yes)
			(effects
				(font
					(size 1 1)
					(thickness 0.15)
				)
			)
		)
		(property "Manufacturer" ""
			(at 0 0 270)
			(unlocked yes)
			(layer "F.Fab")
			(hide yes)
			(effects
				(font
					(size 1 1)
					(thickness 0.15)
				)
			)
		)
		(property "Author" "Antmicro"
			(at 0 0 270)
			(unlocked yes)
			(layer "F.Fab")
			(hide yes)
			(effects
				(font
					(size 1 1)
					(thickness 0.15)
				)
			)
		)
		(property "License" "Apache-2.0"
			(at 0 0 270)
			(unlocked yes)
			(layer "F.Fab")
			(hide yes)
			(effects
				(font
					(size 1 1)
					(thickness 0.15)
				)
			)
		)
		(sheetname "/USB Debug, PD/")
		(sheetfile "usb_debug_pd.kicad_sch")
		(attr exclude_from_pos_files exclude_from_bom)
		(fp_circle
			(center 0 0)
			(end 0.475 0)
			(stroke
				(width 0.05)
				(type default)
			)
			(fill no)
			(layer "F.CrtYd")
		)
		(fp_text user "${REFERENCE}"
			(at -0.4 2.7 90)
			(layer "F.Fab")
			(effects
				(font
					(size 0.7 0.7)
					(thickness 0.15)
				)
				(justify right top)
			)
		)
		(fp_text user "License: Apache-2.0"
			(at -0.4 5.101 90)
			(layer "F.Fab")
			(effects
				(font
					(size 0.7 0.7)
					(thickness 0.15)
				)
				(justify right top)
			)
		)
		(fp_text user "Author: Antmicro"
			(at -0.4 3.901 90)
			(layer "F.Fab")
			(effects
				(font
					(size 0.7 0.7)
					(thickness 0.15)
				)
				(justify right top)
			)
		)
		(pad "1" smd circle
			(at 0 0 270)
			(size 0.75 0.75)
			(layers "F.Cu" "F.Mask")
			(net 1039 "/USB Debug, PD/PDC_I2C3_SCL")
			(pinfunction "1")
			(pintype "passive")
		)
	)
	(footprint "antmicro-footprints:L_Bourns-SRP7028A"
		(layer "F.Cu")
		(at 120.12 59.28 90)
		(property "Reference" "L8"
			(at 3.71 2.27 180)
			(layer "F.SilkS")
			(effects
				(font
					(size 0.7 0.7)
					(thickness 0.15)
				)
				(justify left bottom)
			)
		)
		(property "Value" "L_3u3_6A_Bourns-SRP7028A"
			(at -4.81 4.65 90)
			(layer "F.Fab")
			(effects
				(font
					(size 0.7 0.7)
					(thickness 0.15)
				)
				(justify left bottom)
			)
		)
		(property "Datasheet" "https://www.bourns.com/docs/Product-Datasheets/SRP7028A.pdf"
			(at -0.003 -0.299 90)
			(layer "F.Fab")
			(effects
				(font
					(size 0.7 0.7)
					(thickness 0.15)
				)
				(justify left bottom)
			)
		)
		(property "Description" "Power Inductor (SMD), 3.3 µH, 6 A, Shielded, 12 A, SRP7028A Series"
			(at -0.003 -0.299 90)
			(layer "F.Fab")
			(effects
				(font
					(size 0.7 0.7)
					(thickness 0.15)
				)
				(justify left bottom)
			)
		)
		(property "Val" "3u3/6A"
			(at 0 0 90)
			(unlocked yes)
			(layer "F.Fab")
			(hide yes)
			(effects
				(font
					(size 1 1)
					(thickness 0.15)
				)
			)
		)
		(property "Manufacturer" "Bourns"
			(at 0 0 90)
			(unlocked yes)
			(layer "F.Fab")
			(hide yes)
			(effects
				(font
					(size 1 1)
					(thickness 0.15)
				)
			)
		)
		(property "MPN" "SRP7028A-3R3M"
			(at 0 0 90)
			(unlocked yes)
			(layer "F.Fab")
			(hide yes)
			(effects
				(font
					(size 1 1)
					(thickness 0.15)
				)
			)
		)
		(property "ISat" "12 A"
			(at 0 0 90)
			(unlocked yes)
			(layer "F.Fab")
			(hide yes)
			(effects
				(font
					(size 1 1)
					(thickness 0.15)
				)
			)
		)
		(property "IMax" "6 A"
			(at 0 0 90)
			(unlocked yes)
			(layer "F.Fab")
			(hide yes)
			(effects
				(font
					(size 1 1)
					(thickness 0.15)
				)
			)
		)
		(property "Size" "7.3x6.6x2.8"
			(at 0 0 90)
			(unlocked yes)
			(layer "F.Fab")
			(hide yes)
			(effects
				(font
					(size 1 1)
					(thickness 0.15)
				)
			)
		)
		(property "Author" "Antmicro"
			(at 0 0 90)
			(unlocked yes)
			(layer "F.Fab")
			(hide yes)
			(effects
				(font
					(size 1 1)
					(thickness 0.15)
				)
			)
		)
		(property "License" "Apache-2.0"
			(at 0 0 90)
			(unlocked yes)
			(layer "F.Fab")
			(hide yes)
			(effects
				(font
					(size 1 1)
					(thickness 0.15)
				)
			)
		)
		(sheetname "/DCDC/")
		(sheetfile "dcdc.kicad_sch")
		(attr smd)
		(fp_line
			(start 3.44 -3.39)
			(end -3.44 -3.39)
			(stroke
				(width 0.15)
				(type solid)
			)
			(layer "F.SilkS")
		)
		(fp_line
			(start 3.44 -2.115)
			(end 3.44 -3.39)
			(stroke
				(width 0.15)
				(type solid)
			)
			(layer "F.SilkS")
		)
		(fp_line
			(start -3.44 -2.115)
			(end -3.44 -3.39)
			(stroke
				(width 0.15)
				(type solid)
			)
			(layer "F.SilkS")
		)
		(fp_line
			(start 3.44 2.115)
			(end 3.44 3.39)
			(stroke
				(width 0.15)
				(type solid)
			)
			(layer "F.SilkS")
		)
		(fp_line
			(start -3.44 2.115)
			(end -3.44 3.39)
			(stroke
				(width 0.15)
				(type solid)
			)
			(layer "F.SilkS")
		)
		(fp_line
			(start -3.44 3.39)
			(end 3.44 3.39)
			(stroke
				(width 0.15)
				(type solid)
			)
			(layer "F.SilkS")
		)
		(fp_circle
			(center -4.39 0)
			(end -4.34 0)
			(stroke
				(width 0.15)
				(type solid)
			)
			(fill yes)
			(layer "F.SilkS")
		)
		(fp_rect
			(start -4.5 -3.6)
			(end 4.5 3.6)
			(stroke
				(width 0.05)
				(type solid)
			)
			(fill no)
			(layer "F.CrtYd")
		)
		(fp_text user "License: Apache-2.0"
			(at -4.81 8.25 90)
			(layer "F.Fab")
			(effects
				(font
					(size 0.7 0.7)
					(thickness 0.15)
				)
				(justify left bottom)
			)
		)
		(fp_text user "Author: Antmicro"
			(at -4.81 5.85 90)
			(layer "F.Fab")
			(effects
				(font
					(size 0.7 0.7)
					(thickness 0.15)
				)
				(justify left bottom)
			)
		)
		(fp_text user "${REFERENCE}"
			(at -4.81 7.05 90)
			(layer "F.Fab")
			(effects
				(font
					(size 0.7 0.7)
					(thickness 0.15)
				)
				(justify left bottom)
			)
		)
		(pad "1" smd roundrect
			(at -2.725 0 90)
			(size 2.95 3.5)
			(layers "F.Cu" "F.Mask" "F.Paste")
			(roundrect_rratio 0.05)
			(net 1297 "/DCDC/5V_{AON}_SW")
			(pintype "passive")
		)
		(pad "2" smd roundrect
			(at 2.725 0 90)
			(size 2.95 3.5)
			(layers "F.Cu" "F.Mask" "F.Paste")
			(roundrect_rratio 0.05)
			(net 1278 "/DCDC/5V_{AON}_OUT")
			(pintype "passive")
		)
	)
	(footprint "antmicro-footprints:SW_KMR211NGLFS_SMD"
		(layer "F.Cu")
		(at 215 55.52)
		(property "Reference" "S5"
			(at -3.5 2.85 180)
			(layer "F.SilkS")
			(hide yes)
			(effects
				(font
					(size 0.7 0.7)
					(thickness 0.15)
				)
				(justify left bottom)
			)
		)
		(property "Value" "SW_KMR211NGLFS_SMD"
			(at 0 2.8 0)
			(layer "F.Fab")
			(effects
				(font
					(size 0.7 0.7)
					(thickness 0.15)
				)
				(justify left bottom)
			)
		)
		(property "Datasheet" "http://www.farnell.com/datasheets/2631211.pdf"
			(at 0 0 0)
			(layer "F.Fab")
			(hide yes)
			(effects
				(font
					(size 1.27 1.27)
					(thickness 0.15)
				)
			)
		)
		(property "Description" "Tactile Switch, KMR 2 Series, Top Actuated, Surface Mount, Oval Button, 120 gf, 50mA at 32VDC"
			(at 0 0 0)
			(layer "F.Fab")
			(hide yes)
			(effects
				(font
					(size 1.27 1.27)
					(thickness 0.15)
				)
			)
		)
		(property "MPN" "KMR211NGLFS"
			(at 0 0 0)
			(unlocked yes)
			(layer "F.Fab")
			(hide yes)
			(effects
				(font
					(size 1 1)
					(thickness 0.15)
				)
			)
		)
		(property "Manufacturer" "C&K"
			(at 0 0 0)
			(unlocked yes)
			(layer "F.Fab")
			(hide yes)
			(effects
				(font
					(size 1 1)
					(thickness 0.15)
				)
			)
		)
		(property "Author" "Antmicro"
			(at 0 0 0)
			(unlocked yes)
			(layer "F.Fab")
			(hide yes)
			(effects
				(font
					(size 1 1)
					(thickness 0.15)
				)
			)
		)
		(property "License" "Apache-2.0"
			(at 0 0 0)
			(unlocked yes)
			(layer "F.Fab")
			(hide yes)
			(effects
				(font
					(size 1 1)
					(thickness 0.15)
				)
			)
		)
		(sheetname "/SoM_Power/")
		(sheetfile "som_power.kicad_sch")
		(attr smd)
		(fp_line
			(start -2.1 -1.6)
			(end -2.1 -1.499)
			(stroke
				(width 0.15)
				(type solid)
			)
			(layer "F.SilkS")
		)
		(fp_line
			(start -2.1 1.601)
			(end -2.1 1.48)
			(stroke
				(width 0.15)
				(type solid)
			)
			(layer "F.SilkS")
		)
		(fp_line
			(start 2.101 -1.6)
			(end -2.1 -1.6)
			(stroke
				(width 0.15)
				(type solid)
			)
			(layer "F.SilkS")
		)
		(fp_line
			(start 2.101 -1.58)
			(end 2.101 -1.459)
			(stroke
				(width 0.15)
				(type solid)
			)
			(layer "F.SilkS")
		)
		(fp_line
			(start 2.101 1.601)
			(end -2.1 1.601)
			(stroke
				(width 0.15)
				(type solid)
			)
			(layer "F.SilkS")
		)
		(fp_line
			(start 2.101 1.601)
			(end 2.101 1.48)
			(stroke
				(width 0.15)
				(type solid)
			)
			(layer "F.SilkS")
		)
		(fp_poly
			(pts
				(xy 2.751 1.75) (xy 2.751 -1.749) (xy -2.748 -1.749) (xy -2.748 1.749999)
			)
			(stroke
				(width 0.05)
				(type solid)
			)
			(fill no)
			(layer "F.CrtYd")
		)
		(fp_line
			(start -2.1 -1.6)
			(end -2.1 1.601)
			(stroke
				(width 0.15)
				(type solid)
			)
			(layer "F.Fab")
		)
		(fp_line
			(start -2.1 1.601)
			(end 2.101 1.601)
			(stroke
				(width 0.15)
				(type solid)
			)
			(layer "F.Fab")
		)
		(fp_line
			(start -0.248 -0.8)
			(end 0.25 -0.8)
			(stroke
				(width 0.15)
				(type solid)
			)
			(layer "F.Fab")
		)
		(fp_line
			(start 0.25 0.802)
			(end -0.248 0.802)
			(stroke
				(width 0.15)
				(type solid)
			)
			(layer "F.Fab")
		)
		(fp_line
			(start 2.101 -1.6)
			(end -2.1 -1.6)
			(stroke
				(width 0.15)
				(type solid)
			)
			(layer "F.Fab")
		)
		(fp_line
			(start 2.101 1.601)
			(end 2.101 -1.6)
			(stroke
				(width 0.15)
				(type solid)
			)
			(layer "F.Fab")
		)
		(fp_arc
			(start -0.248 0.802)
			(mid -1.050001 0.001)
			(end -0.248 -0.8)
			(stroke
				(width 0.15)
				(type solid)
			)
			(layer "F.Fab")
		)
		(fp_arc
			(start 0.25 -0.8)
			(mid 1.051001 0.001)
			(end 0.25 0.802)
			(stroke
				(width 0.15)
				(type solid)
			)
			(layer "F.Fab")
		)
		(fp_text user "Author: Antmicro"
			(at -3 5.5 0)
			(layer "F.Fab")
			(effects
				(font
					(size 0.7 0.7)
					(thickness 0.15)
				)
				(justify left bottom)
			)
		)
		(fp_text user "License: Apache-2.0"
			(at -3 6.75 0)
			(layer "F.Fab")
			(effects
				(font
					(size 0.7 0.7)
					(thickness 0.15)
				)
				(justify left bottom)
			)
		)
		(fp_text user "${REFERENCE}"
			(at -3 4.25 0)
			(layer "F.Fab")
			(effects
				(font
					(size 0.7 0.7)
					(thickness 0.15)
				)
				(justify left bottom)
			)
		)
		(pad "1" smd rect
			(at -2.048 -0.8 180)
			(size 0.9 1)
			(layers "F.Cu" "F.Mask" "F.Paste")
			(net 1 "GND")
			(pinfunction "1")
			(pintype "passive")
		)
		(pad "2" smd rect
			(at 2.049999 -0.8 180)
			(size 0.9 1)
			(layers "F.Cu" "F.Mask" "F.Paste")
			(net 1 "GND")
			(pinfunction "2")
			(pintype "passive")
		)
		(pad "3" smd rect
			(at -2.048 0.802 180)
			(size 0.9 1)
			(layers "F.Cu" "F.Mask" "F.Paste")
			(net 610 "/SoM_Power/~{PWR_BTN}")
			(pinfunction "3")
			(pintype "passive")
		)
		(pad "4" smd rect
			(at 2.05 0.802001 180)
			(size 0.9 1)
			(layers "F.Cu" "F.Mask" "F.Paste")
			(net 610 "/SoM_Power/~{PWR_BTN}")
			(pinfunction "4")
			(pintype "passive")
		)
	)
	(footprint "antmicro-footprints:USON-10_2.5x1mm_P0.5mm"
		(layer "F.Cu")
		(at 220.815 117.625 180)
		(descr "USON-10 2.5x1mm_ Pitch 0.5mm")
		(tags "USON-10 2.5x1mm Pitch 0.5mm")
		(property "Reference" "U24"
			(at -0.995 1.095 90)
			(layer "F.SilkS")
			(effects
				(font
					(size 0.7 0.7)
					(thickness 0.15)
				)
				(justify right top)
			)
		)
		(property "Value" "TPD4E05U06QDQARQ1"
			(at 0.018 2.499 0)
			(layer "F.Fab")
			(effects
				(font
					(size 0.7 0.7)
					(thickness 0.15)
				)
				(justify right top)
			)
		)
		(property "Datasheet" "https://www.ti.com/lit/ds/symlink/tpd4e05u06-q1.pdf?HQS=dis-mous-null-mousermode-dsf-pf-null-wwe&ts=1663591265741&ref_url=https%253A%252F%252Fwww.mouser.com%252F"
			(at 0 0 0)
			(layer "F.Fab")
			(hide yes)
			(effects
				(font
					(size 1.27 1.27)
					(thickness 0.15)
				)
			)
		)
		(property "Description" "TVS diode array, 12 kV, USON-10, 5.5 V, 0.5 pF"
			(at 0 0 0)
			(layer "F.Fab")
			(hide yes)
			(effects
				(font
					(size 1.27 1.27)
					(thickness 0.15)
				)
			)
		)
		(property "Manufacturer" "Texas Instruments"
			(at 0 0 180)
			(unlocked yes)
			(layer "F.Fab")
			(hide yes)
			(effects
				(font
					(size 1 1)
					(thickness 0.15)
				)
			)
		)
		(property "MPN" "TPD4E05U06QDQARQ1"
			(at 0 0 180)
			(unlocked yes)
			(layer "F.Fab")
			(hide yes)
			(effects
				(font
					(size 1 1)
					(thickness 0.15)
				)
			)
		)
		(property "Author" "Antmicro"
			(at 0 0 180)
			(unlocked yes)
			(layer "F.Fab")
			(hide yes)
			(effects
				(font
					(size 1 1)
					(thickness 0.15)
				)
			)
		)
		(property "License" "Apache-2.0"
			(at 0 0 180)
			(unlocked yes)
			(layer "F.Fab")
			(hide yes)
			(effects
				(font
					(size 1 1)
					(thickness 0.15)
				)
			)
		)
		(sheetname "/USB Hub/")
		(sheetfile "usb_hub.kicad_sch")
		(attr smd)
		(fp_line
			(start 0.498 1.398)
			(end -0.5 1.398)
			(stroke
				(width 0.15)
				(type solid)
			)
			(layer "F.SilkS")
		)
		(fp_line
			(start 0.498 -1.401)
			(end -0.5 -1.401)
			(stroke
				(width 0.15)
				(type solid)
			)
			(layer "F.SilkS")
		)
		(fp_circle
			(center -0.68 -1.27)
			(end -0.63 -1.27)
			(stroke
				(width 0.15)
				(type solid)
			)
			(fill yes)
			(layer "F.SilkS")
		)
		(fp_rect
			(start -0.8 -1.5)
			(end 0.8 1.499)
			(stroke
				(width 0.05)
				(type solid)
			)
			(fill no)
			(layer "F.CrtYd")
		)
		(fp_line
			(start 0.498 -1.25)
			(end 0.498 1.249)
			(stroke
				(width 0.15)
				(type solid)
			)
			(layer "F.Fab")
		)
		(fp_line
			(start 0.498 -1.25)
			(end -0.25 -1.25)
			(stroke
				(width 0.15)
				(type solid)
			)
			(layer "F.Fab")
		)
		(fp_line
			(start -0.25 -1.25)
			(end -0.5 -1)
			(stroke
				(width 0.15)
				(type solid)
			)
			(layer "F.Fab")
		)
		(fp_line
			(start -0.5 1.249)
			(end 0.498 1.249)
			(stroke
				(width 0.15)
				(type solid)
			)
			(layer "F.Fab")
		)
		(fp_line
			(start -0.5 -1)
			(end -0.5 1.249)
			(stroke
				(width 0.15)
				(type solid)
			)
			(layer "F.Fab")
		)
		(fp_text user "License: Apache-2.0"
			(at -0.802 6.9 0)
			(layer "F.Fab")
			(effects
				(font
					(size 0.7 0.7)
					(thickness 0.15)
				)
				(justify right top)
			)
		)
		(fp_text user "Author: Antmicro"
			(at -0.802 5.7 0)
			(layer "F.Fab")
			(effects
				(font
					(size 0.7 0.7)
					(thickness 0.15)
				)
				(justify right top)
			)
		)
		(fp_text user "${REFERENCE}"
			(at -0.802 4.498 0)
			(layer "F.Fab")
			(effects
				(font
					(size 0.7 0.7)
					(thickness 0.15)
				)
				(justify right top)
			)
		)
		(pad "1" smd roundrect
			(at -0.387 -1 90)
			(size 0.25 0.55)
			(layers "F.Cu" "F.Mask" "F.Paste")
			(roundrect_rratio 0.25)
			(net 95 "/USB Hub/USBC3_CONN_TX1_N")
			(pintype "passive")
		)
		(pad "2" smd roundrect
			(at -0.387 -0.5 90)
			(size 0.25 0.55)
			(layers "F.Cu" "F.Mask" "F.Paste")
			(roundrect_rratio 0.25)
			(net 164 "/USB Hub/USBC3_CONN_TX1_P")
			(pintype "passive")
		)
		(pad "3" smd roundrect
			(at -0.387 0 90)
			(size 0.4 0.55)
			(layers "F.Cu" "F.Mask" "F.Paste")
			(roundrect_rratio 0.25)
			(net 1 "GND")
			(pintype "power_in")
		)
		(pad "4" smd roundrect
			(at -0.387 0.498 90)
			(size 0.25 0.55)
			(layers "F.Cu" "F.Mask" "F.Paste")
			(roundrect_rratio 0.25)
			(net 513 "/USB Hub/USBC3_RX_{1}+")
			(pintype "passive")
		)
		(pad "5" smd roundrect
			(at -0.387 0.998 90)
			(size 0.25 0.55)
			(layers "F.Cu" "F.Mask" "F.Paste")
			(roundrect_rratio 0.25)
			(net 507 "/USB Hub/USBC3_RX_{1}-")
			(pintype "passive")
		)
		(pad "6" smd roundrect
			(at 0.385 0.998 90)
			(size 0.25 0.55)
			(layers "F.Cu" "F.Mask" "F.Paste")
			(roundrect_rratio 0.25)
			(net 507 "/USB Hub/USBC3_RX_{1}-")
			(pintype "passive")
		)
		(pad "7" smd roundrect
			(at 0.385 0.498 90)
			(size 0.25 0.55)
			(layers "F.Cu" "F.Mask" "F.Paste")
			(roundrect_rratio 0.25)
			(net 513 "/USB Hub/USBC3_RX_{1}+")
			(pintype "passive")
		)
		(pad "8" smd roundrect
			(at 0.385 0 90)
			(size 0.4 0.55)
			(layers "F.Cu" "F.Mask" "F.Paste")
			(roundrect_rratio 0.25)
			(net 1 "GND")
			(pintype "passive")
		)
		(pad "9" smd roundrect
			(at 0.385 -0.5 90)
			(size 0.25 0.55)
			(layers "F.Cu" "F.Mask" "F.Paste")
			(roundrect_rratio 0.25)
			(net 164 "/USB Hub/USBC3_CONN_TX1_P")
			(pintype "passive")
		)
		(pad "10" smd roundrect
			(at 0.385 -1 90)
			(size 0.25 0.55)
			(layers "F.Cu" "F.Mask" "F.Paste")
			(roundrect_rratio 0.25)
			(net 95 "/USB Hub/USBC3_CONN_TX1_N")
			(pintype "passive")
		)
	)
	(footprint "antmicro-footprints:SOD-523"
		(layer "F.Cu")
		(at 111.22 59.79 90)
		(property "Reference" "D62"
			(at -1.6 -3.66 90)
			(layer "F.SilkS")
			(effects
				(font
					(size 0.7 0.7)
					(thickness 0.15)
				)
				(justify left bottom)
			)
		)
		(property "Value" "PESD5Z5.0F"
			(at 0 1.499 90)
			(layer "F.Fab")
			(effects
				(font
					(size 0.7 0.7)
					(thickness 0.15)
				)
				(justify left bottom)
			)
		)
		(property "Datasheet" "https://assets.nexperia.com/documents/data-sheet/PESD5Z5_0.pdf"
			(at 0 0 90)
			(layer "F.Fab")
			(hide yes)
			(effects
				(font
					(size 1.27 1.27)
					(thickness 0.15)
				)
			)
		)
		(property "Description" "Unidirectional TVS, 30 kV,  SOD-523, 5 V, 89 pF"
			(at 0 0 90)
			(layer "F.Fab")
			(hide yes)
			(effects
				(font
					(size 1.27 1.27)
					(thickness 0.15)
				)
			)
		)
		(property "Manufacturer" "Nexperia"
			(at 0 0 90)
			(unlocked yes)
			(layer "F.Fab")
			(hide yes)
			(effects
				(font
					(size 1 1)
					(thickness 0.15)
				)
			)
		)
		(property "MPN" "PESD5Z5.0F"
			(at 0 0 90)
			(unlocked yes)
			(layer "F.Fab")
			(hide yes)
			(effects
				(font
					(size 1 1)
					(thickness 0.15)
				)
			)
		)
		(property "Author" "Antmicro"
			(at 0 0 90)
			(unlocked yes)
			(layer "F.Fab")
			(hide yes)
			(effects
				(font
					(size 1 1)
					(thickness 0.15)
				)
			)
		)
		(property "License" "Apache-2.0"
			(at 0 0 90)
			(unlocked yes)
			(layer "F.Fab")
			(hide yes)
			(effects
				(font
					(size 1 1)
					(thickness 0.15)
				)
			)
		)
		(sheetname "/DCDC/")
		(sheetfile "dcdc.kicad_sch")
		(attr smd)
		(fp_line
			(start -0.35 -0.5)
			(end -0.35 0.5)
			(stroke
				(width 0.15)
				(type solid)
			)
			(layer "F.SilkS")
		)
		(fp_poly
			(pts
				(xy -1 -0.6) (xy 1 -0.6) (xy 1 0.6) (xy -1 0.6)
			)
			(stroke
				(width 0.05)
				(type solid)
			)
			(fill no)
			(layer "F.CrtYd")
		)
		(fp_line
			(start 0.65 -0.425)
			(end 0.65 0.423)
			(stroke
				(width 0.15)
				(type solid)
			)
			(layer "F.Fab")
		)
		(fp_line
			(start -0.652 -0.425)
			(end 0.65 -0.425)
			(stroke
				(width 0.15)
				(type solid)
			)
			(layer "F.Fab")
		)
		(fp_line
			(start -0.35 -0.4)
			(end -0.35 0.4)
			(stroke
				(width 0.15)
				(type solid)
			)
			(layer "F.Fab")
		)
		(fp_line
			(start -0.652 0.423)
			(end -0.652 -0.425)
			(stroke
				(width 0.15)
				(type solid)
			)
			(layer "F.Fab")
		)
		(fp_line
			(start -0.652 0.423)
			(end 0.65 0.423)
			(stroke
				(width 0.15)
				(type solid)
			)
			(layer "F.Fab")
		)
		(fp_text user "Author: Antmicro"
			(at -1.276 4.7 90)
			(layer "F.Fab")
			(effects
				(font
					(size 0.7 0.7)
					(thickness 0.15)
				)
				(justify left bottom)
			)
		)
		(fp_text user "License: Apache-2.0"
			(at -1.276 5.9 90)
			(layer "F.Fab")
			(effects
				(font
					(size 0.7 0.7)
					(thickness 0.15)
				)
				(justify left bottom)
			)
		)
		(fp_text user "${REFERENCE}"
			(at -1.276 3.499 90)
			(layer "F.Fab")
			(effects
				(font
					(size 0.7 0.7)
					(thickness 0.15)
				)
				(justify left bottom)
			)
		)
		(pad "1" smd roundrect
			(at -0.701 0 90)
			(size 0.5 0.6)
			(layers "F.Cu" "F.Mask" "F.Paste")
			(roundrect_rratio 0.25)
			(net 491 "+5V_AON")
			(pinfunction "C")
			(pintype "passive")
		)
		(pad "2" smd roundrect
			(at 0.699001 0 90)
			(size 0.5 0.6)
			(layers "F.Cu" "F.Mask" "F.Paste")
			(roundrect_rratio 0.25)
			(net 1 "GND")
			(pinfunction "A")
			(pintype "passive")
		)
	)
	(footprint "antmicro-footprints:R_0402_1005Metric"
		(layer "F.Cu")
		(at 162.709468 78.1 90)
		(descr "Resistor SMD 0402")
		(tags "resistor SMD 0402")
		(property "Reference" "R365"
			(at -1 -1.809468 90)
			(layer "F.SilkS")
			(effects
				(font
					(size 0.7 0.7)
					(thickness 0.15)
				)
				(justify left bottom)
			)
		)
		(property "Value" "R_27R_0402"
			(at -1.011843 1.772047 90)
			(layer "F.Fab")
			(effects
				(font
					(size 0.7 0.7)
					(thickness 0.15)
				)
				(justify left bottom)
			)
		)
		(property "Datasheet" "https://www.bourns.com/docs/product-datasheets/cr.pdf"
			(at 0 0 90)
			(layer "F.Fab")
			(hide yes)
			(effects
				(font
					(size 1.27 1.27)
					(thickness 0.15)
				)
			)
		)
		(property "Description" "SMD Chip Resistor, 27 ohm, ± 1%, 63 mW, 0402 [1005 Metric], Thick Film, General Purpose"
			(at 0 0 90)
			(layer "F.Fab")
			(hide yes)
			(effects
				(font
					(size 1.27 1.27)
					(thickness 0.15)
				)
			)
		)
		(property "Manufacturer" "Bourns"
			(at 0 0 90)
			(unlocked yes)
			(layer "F.Fab")
			(hide yes)
			(effects
				(font
					(size 1 1)
					(thickness 0.15)
				)
			)
		)
		(property "MPN" "CR0402-FX-27R0GLF"
			(at 0 0 90)
			(unlocked yes)
			(layer "F.Fab")
			(hide yes)
			(effects
				(font
					(size 1 1)
					(thickness 0.15)
				)
			)
		)
		(property "Val" "27R"
			(at 0 0 90)
			(unlocked yes)
			(layer "F.Fab")
			(hide yes)
			(effects
				(font
					(size 1 1)
					(thickness 0.15)
				)
			)
		)
		(property "License" "Apache-2.0"
			(at 0 0 90)
			(unlocked yes)
			(layer "F.Fab")
			(hide yes)
			(effects
				(font
					(size 1 1)
					(thickness 0.15)
				)
			)
		)
		(property "Author" "Antmicro"
			(at 0 0 90)
			(unlocked yes)
			(layer "F.Fab")
			(hide yes)
			(effects
				(font
					(size 1 1)
					(thickness 0.15)
				)
			)
		)
		(property "Tolerance" "1%"
			(at 0 0 90)
			(unlocked yes)
			(layer "F.Fab")
			(hide yes)
			(effects
				(font
					(size 1 1)
					(thickness 0.15)
				)
			)
		)
		(component_classes
			(class "DCDC_20V")
		)
		(sheetname "/DCDC/")
		(sheetfile "dcdc.kicad_sch")
		(attr smd)
		(fp_rect
			(start -0.925 -0.47)
			(end 0.925 0.47)
			(stroke
				(width 0.05)
				(type default)
			)
			(fill no)
			(layer "F.CrtYd")
		)
		(fp_rect
			(start -0.5 -0.25)
			(end 0.5 0.25)
			(stroke
				(width 0.15)
				(type solid)
			)
			(fill no)
			(layer "F.Fab")
		)
		(fp_text user "License: Apache-2.0"
			(at -0.95 5.169 90)
			(layer "F.Fab")
			(effects
				(font
					(size 0.7 0.7)
					(thickness 0.15)
				)
				(justify left bottom)
			)
		)
		(fp_text user "${REFERENCE}"
			(at -0.95 3.168 90)
			(layer "F.Fab")
			(effects
				(font
					(size 0.7 0.7)
					(thickness 0.15)
				)
				(justify left bottom)
			)
		)
		(fp_text user "Author: Antmicro"
			(at -0.95 4.169 90)
			(layer "F.Fab")
			(effects
				(font
					(size 0.7 0.7)
					(thickness 0.15)
				)
				(justify left bottom)
			)
		)
		(pad "1" smd roundrect
			(at -0.48 0 90)
			(size 0.59 0.64)
			(layers "F.Cu" "F.Mask" "F.Paste")
			(roundrect_rratio 0.25)
			(net 1284 "Net-(U66-IN+)")
			(pintype "passive")
		)
		(pad "2" smd roundrect
			(at 0.48 0 90)
			(size 0.59 0.64)
			(layers "F.Cu" "F.Mask" "F.Paste")
			(roundrect_rratio 0.25)
			(net 1105 "/DCDC/20V_OUT")
			(pintype "passive")
		)
	)
	(footprint "antmicro-footprints:C_0402_1005Metric"
		(layer "F.Cu")
		(at 217.6 84.3 -90)
		(descr "Capacitor SMD 0402")
		(tags "capacitor SMD 0402")
		(property "Reference" "C124"
			(at -3.7 0.4 90)
			(layer "F.SilkS")
			(effects
				(font
					(size 0.7 0.7)
					(thickness 0.15)
				)
				(justify right top)
			)
		)
		(property "Value" "C_10u_0402"
			(at -1.022927 2.155213 90)
			(layer "F.Fab")
			(effects
				(font
					(size 0.7 0.7)
					(thickness 0.15)
				)
				(justify right top)
			)
		)
		(property "Datasheet" "https://www.yageo.com/en/Chart/Download/pdf/CC0402MRX5R5BB106"
			(at 0 0 90)
			(layer "F.Fab")
			(hide yes)
			(effects
				(font
					(size 1.27 1.27)
					(thickness 0.15)
				)
			)
		)
		(property "Description" "SMD Multilayer Ceramic Capacitor, 10 µF, 6.3 V, 0402 [1005 Metric], ± 20%, X5R, CC Series"
			(at 0 0 90)
			(layer "F.Fab")
			(hide yes)
			(effects
				(font
					(size 1.27 1.27)
					(thickness 0.15)
				)
			)
		)
		(property "MPN" "CC0402MRX5R5BB106"
			(at 0 0 270)
			(unlocked yes)
			(layer "F.Fab")
			(hide yes)
			(effects
				(font
					(size 1 1)
					(thickness 0.15)
				)
			)
		)
		(property "Manufacturer" "YAGEO"
			(at 0 0 270)
			(unlocked yes)
			(layer "F.Fab")
			(hide yes)
			(effects
				(font
					(size 1 1)
					(thickness 0.15)
				)
			)
		)
		(property "License" "Apache-2.0"
			(at 0 0 270)
			(unlocked yes)
			(layer "F.Fab")
			(hide yes)
			(effects
				(font
					(size 1 1)
					(thickness 0.15)
				)
			)
		)
		(property "Author" "Antmicro"
			(at 0 0 270)
			(unlocked yes)
			(layer "F.Fab")
			(hide yes)
			(effects
				(font
					(size 1 1)
					(thickness 0.15)
				)
			)
		)
		(property "Val" "10u"
			(at 0 0 270)
			(unlocked yes)
			(layer "F.Fab")
			(hide yes)
			(effects
				(font
					(size 1 1)
					(thickness 0.15)
				)
			)
		)
		(property "Voltage" ""
			(at 0 0 270)
			(unlocked yes)
			(layer "F.Fab")
			(hide yes)
			(effects
				(font
					(size 1 1)
					(thickness 0.15)
				)
			)
		)
		(property "Dielectric" ""
			(at 0 0 270)
			(unlocked yes)
			(layer "F.Fab")
			(hide yes)
			(effects
				(font
					(size 1 1)
					(thickness 0.15)
				)
			)
		)
		(sheetname "/USB DP Alt mode/")
		(sheetfile "usb_dp.kicad_sch")
		(attr smd)
		(fp_rect
			(start -0.925 -0.47)
			(end 0.925 0.47)
			(stroke
				(width 0.05)
				(type default)
			)
			(fill no)
			(layer "F.CrtYd")
		)
		(fp_line
			(start -0.494 0.248)
			(end -0.494 -0.25)
			(stroke
				(width 0.15)
				(type solid)
			)
			(layer "F.Fab")
		)
		(fp_line
			(start 0.504 0.248)
			(end -0.494 0.248)
			(stroke
				(width 0.15)
				(type solid)
			)
			(layer "F.Fab")
		)
		(fp_line
			(start -0.494 -0.25)
			(end 0.504 -0.25)
			(stroke
				(width 0.15)
				(type solid)
			)
			(layer "F.Fab")
		)
		(fp_line
			(start 0.504 -0.25)
			(end 0.504 0.248)
			(stroke
				(width 0.15)
				(type solid)
			)
			(layer "F.Fab")
		)
		(fp_text user "${REFERENCE}"
			(at -0.939 4.599 90)
			(layer "F.Fab")
			(effects
				(font
					(size 0.7 0.7)
					(thickness 0.15)
				)
				(justify right top)
			)
		)
		(fp_text user "License: Apache-2.0"
			(at -0.939 5.799 90)
			(layer "F.Fab")
			(effects
				(font
					(size 0.7 0.7)
					(thickness 0.15)
				)
				(justify right top)
			)
		)
		(fp_text user "Author: Antmicro"
			(at -0.939 3.399 90)
			(layer "F.Fab")
			(effects
				(font
					(size 0.7 0.7)
					(thickness 0.15)
				)
				(justify right top)
			)
		)
		(pad "1" smd roundrect
			(at -0.48 0 270)
			(size 0.59 0.64)
			(layers "F.Cu" "F.Mask" "F.Paste")
			(roundrect_rratio 0.25)
			(net 1 "GND")
			(pintype "passive")
		)
		(pad "2" smd roundrect
			(at 0.48 0 270)
			(size 0.59 0.64)
			(layers "F.Cu" "F.Mask" "F.Paste")
			(roundrect_rratio 0.25)
			(net 2 "+3V3")
			(pintype "passive")
		)
	)
	(footprint "antmicro-footprints:C_0805_2012Metric"
		(layer "F.Cu")
		(at 176.345 126.92 90)
		(descr "Capacitor SMD 0805")
		(tags "capacitor SMD 0805")
		(property "Reference" "C46"
			(at 1.52 -6.685 90)
			(layer "F.SilkS")
			(effects
				(font
					(size 0.7 0.7)
					(thickness 0.15)
				)
				(justify left bottom)
			)
		)
		(property "Value" "C_22u_25V_0805"
			(at -2.055717 1.963152 90)
			(layer "F.Fab")
			(effects
				(font
					(size 0.7 0.7)
					(thickness 0.15)
				)
				(justify left bottom)
			)
		)
		(property "Datasheet" "https://product.samsungsem.com/mlcc/CL21A226MAYNNN.do"
			(at 0 0 90)
			(layer "F.Fab")
			(hide yes)
			(effects
				(font
					(size 1.27 1.27)
					(thickness 0.15)
				)
			)
		)
		(property "Description" "SMT Multilayer Ceramic Capacitor, 22uF, +/-20%, 25V, X5R, 0805 [2012 Metric]"
			(at 0 0 90)
			(layer "F.Fab")
			(hide yes)
			(effects
				(font
					(size 1.27 1.27)
					(thickness 0.15)
				)
			)
		)
		(property "MPN" "CL21A226MAYNNNE"
			(at 0 0 90)
			(unlocked yes)
			(layer "F.Fab")
			(hide yes)
			(effects
				(font
					(size 1 1)
					(thickness 0.15)
				)
			)
		)
		(property "Manufacturer" "Samsung Electro-Mechanics"
			(at 0 0 90)
			(unlocked yes)
			(layer "F.Fab")
			(hide yes)
			(effects
				(font
					(size 1 1)
					(thickness 0.15)
				)
			)
		)
		(property "License" "Apache-2.0"
			(at 0 0 90)
			(unlocked yes)
			(layer "F.Fab")
			(hide yes)
			(effects
				(font
					(size 1 1)
					(thickness 0.15)
				)
			)
		)
		(property "Author" "Antmicro"
			(at 0 0 90)
			(unlocked yes)
			(layer "F.Fab")
			(hide yes)
			(effects
				(font
					(size 1 1)
					(thickness 0.15)
				)
			)
		)
		(property "Val" "22u"
			(at 0 0 90)
			(unlocked yes)
			(layer "F.Fab")
			(hide yes)
			(effects
				(font
					(size 1 1)
					(thickness 0.15)
				)
			)
		)
		(property "Voltage" "25V"
			(at 0 0 90)
			(unlocked yes)
			(layer "F.Fab")
			(hide yes)
			(effects
				(font
					(size 1 1)
					(thickness 0.15)
				)
			)
		)
		(property "Dielectric" "X5R"
			(at 0 0 90)
			(unlocked yes)
			(layer "F.Fab")
			(hide yes)
			(effects
				(font
					(size 1 1)
					(thickness 0.15)
				)
			)
		)
		(property "Public" "False"
			(at 0 0 90)
			(unlocked yes)
			(layer "F.Fab")
			(hide yes)
			(effects
				(font
					(size 1 1)
					(thickness 0.15)
				)
			)
		)
		(sheetname "/DCDC/")
		(sheetfile "dcdc.kicad_sch")
		(attr smd)
		(fp_line
			(start -0.3 -0.7)
			(end 0.3 -0.7)
			(stroke
				(width 0.15)
				(type solid)
			)
			(layer "F.SilkS")
		)
		(fp_line
			(start -0.3 0.7)
			(end 0.3 0.7)
			(stroke
				(width 0.15)
				(type solid)
			)
			(layer "F.SilkS")
		)
		(fp_rect
			(start 1.95 -0.9)
			(end -1.95 0.9)
			(stroke
				(width 0.05)
				(type default)
			)
			(fill no)
			(layer "F.CrtYd")
		)
		(fp_rect
			(start -0.95 -0.675)
			(end 0.95 0.675)
			(stroke
				(width 0.15)
				(type solid)
			)
			(fill no)
			(layer "F.Fab")
		)
		(fp_text user "Author: Antmicro"
			(at -1.9 5.947 90)
			(layer "F.Fab")
			(effects
				(font
					(size 0.7 0.7)
					(thickness 0.15)
				)
				(justify left bottom)
			)
		)
		(fp_text user "${REFERENCE}"
			(at -1.9 3.947 90)
			(layer "F.Fab")
			(effects
				(font
					(size 0.7 0.7)
					(thickness 0.15)
				)
				(justify left bottom)
			)
		)
		(fp_text user "License: Apache-2.0"
			(at -1.9 4.947 90)
			(layer "F.Fab")
			(effects
				(font
					(size 0.7 0.7)
					(thickness 0.15)
				)
				(justify left bottom)
			)
		)
		(pad "1" smd roundrect
			(at -1.1 0 90)
			(size 1.2 1.3)
			(layers "F.Cu" "F.Mask" "F.Paste")
			(roundrect_rratio 0.25)
			(net 1 "GND")
			(pintype "passive")
		)
		(pad "2" smd roundrect
			(at 1.1 0 90)
			(size 1.2 1.3)
			(layers "F.Cu" "F.Mask" "F.Paste")
			(roundrect_rratio 0.25)
			(net 13 "VCC")
			(pintype "passive")
		)
	)
	(footprint "antmicro-footprints:C_0603_1608Metric_EIA"
		(layer "F.Cu")
		(at 176.27 130.18 -90)
		(descr "Capacitor SMD 0603, IPC-7351 Density Level A")
		(tags "Capacitor 0603")
		(property "Reference" "C64"
			(at -4.28 9.77 90)
			(layer "F.SilkS")
			(effects
				(font
					(size 0.7 0.7)
					(thickness 0.15)
				)
				(justify right top)
			)
		)
		(property "Value" "C_22u_16V_0603"
			(at -1.42757 1.770288 90)
			(layer "F.Fab")
			(effects
				(font
					(size 0.7 0.7)
					(thickness 0.15)
				)
				(justify right top)
			)
		)
		(property "Datasheet" "https://product.samsungsem.com/mlcc/CL10A226MO7JZN.do"
			(at 0 0 90)
			(layer "F.Fab")
			(hide yes)
			(effects
				(font
					(size 1.27 1.27)
					(thickness 0.15)
				)
			)
		)
		(property "Description" "SMD Multilayer Ceramic Capacitor"
			(at 0 0 90)
			(layer "F.Fab")
			(hide yes)
			(effects
				(font
					(size 1.27 1.27)
					(thickness 0.15)
				)
			)
		)
		(property "Manufacturer" "Samsung Electro-Mechanics"
			(at 0 0 270)
			(unlocked yes)
			(layer "F.Fab")
			(hide yes)
			(effects
				(font
					(size 1 1)
					(thickness 0.15)
				)
			)
		)
		(property "MPN" "CL10A226MO7JZNC"
			(at 0 0 270)
			(unlocked yes)
			(layer "F.Fab")
			(hide yes)
			(effects
				(font
					(size 1 1)
					(thickness 0.15)
				)
			)
		)
		(property "Val" "22u"
			(at 0 0 270)
			(unlocked yes)
			(layer "F.Fab")
			(hide yes)
			(effects
				(font
					(size 1 1)
					(thickness 0.15)
				)
			)
		)
		(property "License" "Apache-2.0"
			(at 0 0 270)
			(unlocked yes)
			(layer "F.Fab")
			(hide yes)
			(effects
				(font
					(size 1 1)
					(thickness 0.15)
				)
			)
		)
		(property "Author" "Antmicro"
			(at 0 0 270)
			(unlocked yes)
			(layer "F.Fab")
			(hide yes)
			(effects
				(font
					(size 1 1)
					(thickness 0.15)
				)
			)
		)
		(property "Voltage" "16V"
			(at 0 0 270)
			(unlocked yes)
			(layer "F.Fab")
			(hide yes)
			(effects
				(font
					(size 1 1)
					(thickness 0.15)
				)
			)
		)
		(property "Dielectric" ""
			(at 0 0 270)
			(unlocked yes)
			(layer "F.Fab")
			(hide yes)
			(effects
				(font
					(size 1 1)
					(thickness 0.15)
				)
			)
		)
		(sheetname "/DCDC/")
		(sheetfile "dcdc.kicad_sch")
		(attr smd)
		(fp_line
			(start -0.15 0.55)
			(end 0.15 0.55)
			(stroke
				(width 0.15)
				(type solid)
			)
			(layer "F.SilkS")
		)
		(fp_line
			(start -0.15 -0.55)
			(end 0.15 -0.55)
			(stroke
				(width 0.15)
				(type solid)
			)
			(layer "F.SilkS")
		)
		(fp_rect
			(start -1.25 -0.65)
			(end 1.25 0.65)
			(stroke
				(width 0.05)
				(type solid)
			)
			(fill no)
			(layer "F.CrtYd")
		)
		(fp_rect
			(start -0.8 -0.45)
			(end 0.8 0.45)
			(stroke
				(width 0.15)
				(type solid)
			)
			(fill no)
			(layer "F.Fab")
		)
		(fp_text user "${REFERENCE}"
			(at -1.682 3.895 90)
			(layer "F.Fab")
			(effects
				(font
					(size 0.7 0.7)
					(thickness 0.15)
				)
				(justify right top)
			)
		)
		(fp_text user "Author: Antmicro"
			(at -1.682 4.894 90)
			(layer "F.Fab")
			(effects
				(font
					(size 0.7 0.7)
					(thickness 0.15)
				)
				(justify right top)
			)
		)
		(fp_text user "License: Apache-2.0"
			(at -1.682 5.895 90)
			(layer "F.Fab")
			(effects
				(font
					(size 0.7 0.7)
					(thickness 0.15)
				)
				(justify right top)
			)
		)
		(pad "1" smd roundrect
			(at -0.7 0 270)
			(size 0.8 1.1)
			(layers "F.Cu" "F.Mask" "F.Paste")
			(roundrect_rratio 0.2)
			(net 1 "GND")
			(pintype "passive")
		)
		(pad "2" smd roundrect
			(at 0.7 0 270)
			(size 0.8 1.1)
			(layers "F.Cu" "F.Mask" "F.Paste")
			(roundrect_rratio 0.2)
			(net 567 "/DCDC/3V3_OUT")
			(pintype "passive")
		)
	)
	(footprint "antmicro-footprints:R_0402_1005Metric"
		(layer "F.Cu")
		(at 128.81 143.2 -90)
		(descr "Resistor SMD 0402")
		(tags "resistor SMD 0402")
		(property "Reference" "R340"
			(at 1 0.41 90)
			(layer "F.SilkS")
			(effects
				(font
					(size 0.7 0.7)
					(thickness 0.15)
				)
				(justify right top)
			)
		)
		(property "Value" "R_10k_0402"
			(at -1.011843 1.772046 90)
			(layer "F.Fab")
			(effects
				(font
					(size 0.7 0.7)
					(thickness 0.15)
				)
				(justify right top)
			)
		)
		(property "Datasheet" "https://www.bourns.com/docs/product-datasheets/cr.pdf"
			(at 0 0 90)
			(layer "F.Fab")
			(hide yes)
			(effects
				(font
					(size 1.27 1.27)
					(thickness 0.15)
				)
			)
		)
		(property "Description" "SMD Chip Resistor, 10 kohm, ± 1%, 62.5 mW, 0402 [1005 Metric], Thick Film, General Purpose"
			(at 0 0 90)
			(layer "F.Fab")
			(hide yes)
			(effects
				(font
					(size 1.27 1.27)
					(thickness 0.15)
				)
			)
		)
		(property "MPN" "CR0402-FX-1002GLF"
			(at 0 0 270)
			(unlocked yes)
			(layer "F.Fab")
			(hide yes)
			(effects
				(font
					(size 1 1)
					(thickness 0.15)
				)
			)
		)
		(property "Manufacturer" "Bourns"
			(at 0 0 270)
			(unlocked yes)
			(layer "F.Fab")
			(hide yes)
			(effects
				(font
					(size 1 1)
					(thickness 0.15)
				)
			)
		)
		(property "License" "Apache-2.0"
			(at 0 0 270)
			(unlocked yes)
			(layer "F.Fab")
			(hide yes)
			(effects
				(font
					(size 1 1)
					(thickness 0.15)
				)
			)
		)
		(property "Author" "Antmicro"
			(at 0 0 270)
			(unlocked yes)
			(layer "F.Fab")
			(hide yes)
			(effects
				(font
					(size 1 1)
					(thickness 0.15)
				)
			)
		)
		(property "Val" "10k"
			(at 0 0 270)
			(unlocked yes)
			(layer "F.Fab")
			(hide yes)
			(effects
				(font
					(size 1 1)
					(thickness 0.15)
				)
			)
		)
		(property "Tolerance" "1%"
			(at 0 0 270)
			(unlocked yes)
			(layer "F.Fab")
			(hide yes)
			(effects
				(font
					(size 1 1)
					(thickness 0.15)
				)
			)
		)
		(sheetname "/Expansion connector/")
		(sheetfile "expansion_connector.kicad_sch")
		(attr smd exclude_from_pos_files exclude_from_bom dnp)
		(fp_poly
			(pts
				(xy -0.925 -0.47) (xy 0.925 -0.47) (xy 0.925 0.47) (xy -0.925 0.47)
			)
			(stroke
				(width 0.05)
				(type default)
			)
			(fill no)
			(layer "F.CrtYd")
		)
		(fp_poly
			(pts
				(xy -0.5 -0.25) (xy 0.5 -0.25) (xy 0.5 0.25) (xy -0.5 0.25)
			)
			(stroke
				(width 0.15)
				(type solid)
			)
			(fill no)
			(layer "F.Fab")
		)
		(fp_text user "License: Apache-2.0"
			(at -0.949999 5.169 90)
			(layer "F.Fab")
			(effects
				(font
					(size 0.7 0.7)
					(thickness 0.15)
				)
				(justify right top)
			)
		)
		(fp_text user "${REFERENCE}"
			(at -0.95 3.168 90)
			(layer "F.Fab")
			(effects
				(font
					(size 0.7 0.7)
					(thickness 0.15)
				)
				(justify right top)
			)
		)
		(fp_text user "Author: Antmicro"
			(at -0.95 4.169 90)
			(layer "F.Fab")
			(effects
				(font
					(size 0.7 0.7)
					(thickness 0.15)
				)
				(justify right top)
			)
		)
		(pad "1" smd roundrect
			(at -0.48 0 270)
			(size 0.59 0.64)
			(layers "F.Cu" "F.Mask" "F.Paste")
			(roundrect_rratio 0.25)
			(net 677 "/Expansion connector/ADDR0")
			(pintype "passive")
		)
		(pad "2" smd roundrect
			(at 0.48 0 270)
			(size 0.59 0.64)
			(layers "F.Cu" "F.Mask" "F.Paste")
			(roundrect_rratio 0.25)
			(net 1 "GND")
			(pintype "passive")
		)
	)
	(footprint "antmicro-footprints:R_0603_1608Metric"
		(layer "F.Cu")
		(at 169.859468 149.049468 180)
		(descr "Resistor SMD 0603")
		(tags "resistor SMD 0603")
		(property "Reference" "R22"
			(at 1.3 0.295 0)
			(layer "F.SilkS")
			(effects
				(font
					(size 0.7 0.7)
					(thickness 0.15)
				)
				(justify right top)
			)
		)
		(property "Value" "R_0R_22.4A_0603"
			(at 0 1.6 0)
			(layer "F.Fab")
			(effects
				(font
					(size 0.7 0.7)
					(thickness 0.15)
				)
				(justify right top)
			)
		)
		(property "Datasheet" "https://fscdn.rohm.com/en/products/databook/datasheet/passive/resistor/chip_resistor/pmr-jpw-e.pdf"
			(at 0 0 0)
			(layer "F.Fab")
			(hide yes)
			(effects
				(font
					(size 1.27 1.27)
					(thickness 0.15)
				)
			)
		)
		(property "Description" "SMD Chip Resistor"
			(at 0 0 0)
			(layer "F.Fab")
			(hide yes)
			(effects
				(font
					(size 1.27 1.27)
					(thickness 0.15)
				)
			)
		)
		(property "Manufacturer" "ROHM Semiconductor"
			(at 0 0 0)
			(unlocked yes)
			(layer "F.Fab")
			(hide yes)
			(effects
				(font
					(size 1 1)
					(thickness 0.15)
				)
			)
		)
		(property "MPN" "PMR03EZPJ000"
			(at 0 0 0)
			(unlocked yes)
			(layer "F.Fab")
			(hide yes)
			(effects
				(font
					(size 1 1)
					(thickness 0.15)
				)
			)
		)
		(property "Val" "0R"
			(at 0 0 0)
			(unlocked yes)
			(layer "F.Fab")
			(hide yes)
			(effects
				(font
					(size 1 1)
					(thickness 0.15)
				)
			)
		)
		(property "Author" "Antmicro"
			(at 0 0 0)
			(unlocked yes)
			(layer "F.Fab")
			(hide yes)
			(effects
				(font
					(size 1 1)
					(thickness 0.15)
				)
			)
		)
		(property "License" "Apache-2.0"
			(at 0 0 0)
			(unlocked yes)
			(layer "F.Fab")
			(hide yes)
			(effects
				(font
					(size 1 1)
					(thickness 0.15)
				)
			)
		)
		(property "Max. Curr." "22.4A"
			(at 0 0 0)
			(unlocked yes)
			(layer "F.Fab")
			(hide yes)
			(effects
				(font
					(size 1 1)
					(thickness 0.15)
				)
			)
		)
		(property "Tolerance" "template_tolerance"
			(at 0 0 0)
			(unlocked yes)
			(layer "F.Fab")
			(hide yes)
			(effects
				(font
					(size 1 1)
					(thickness 0.15)
				)
			)
		)
		(sheetname "/DCDC/")
		(sheetfile "dcdc.kicad_sch")
		(attr smd)
		(fp_line
			(start -0.15 0.4)
			(end 0.15 0.4)
			(stroke
				(width 0.15)
				(type solid)
			)
			(layer "F.SilkS")
		)
		(fp_line
			(start -0.15 -0.4)
			(end 0.15 -0.4)
			(stroke
				(width 0.15)
				(type solid)
			)
			(layer "F.SilkS")
		)
		(fp_rect
			(start -1.25 -0.65)
			(end 1.25 0.65)
			(stroke
				(width 0.05)
				(type solid)
			)
			(fill no)
			(layer "F.CrtYd")
		)
		(fp_rect
			(start -0.8 -0.4)
			(end 0.8 0.4)
			(stroke
				(width 0.15)
				(type solid)
			)
			(fill no)
			(layer "F.Fab")
		)
		(fp_text user "Author: Antmicro"
			(at -1.25 4.9 0)
			(layer "F.Fab")
			(effects
				(font
					(size 0.7 0.7)
					(thickness 0.15)
				)
				(justify right top)
			)
		)
		(fp_text user "${REFERENCE}"
			(at -1.25 3.898 0)
			(layer "F.Fab")
			(effects
				(font
					(size 0.7 0.7)
					(thickness 0.15)
				)
				(justify right top)
			)
		)
		(fp_text user "License: Apache-2.0"
			(at -1.25 5.9 0)
			(layer "F.Fab")
			(effects
				(font
					(size 0.7 0.7)
					(thickness 0.15)
				)
				(justify right top)
			)
		)
		(pad "1" smd roundrect
			(at -0.7 0 180)
			(size 0.8 1)
			(layers "F.Cu" "F.Mask" "F.Paste")
			(roundrect_rratio 0.2)
			(net 880 "/DCDC/12V_OUT")
			(pintype "passive")
		)
		(pad "2" smd roundrect
			(at 0.7 0 180)
			(size 0.8 1)
			(layers "F.Cu" "F.Mask" "F.Paste")
			(roundrect_rratio 0.2)
			(net 634 "+12V")
			(pintype "passive")
		)
	)
	(footprint "antmicro-footprints:C_0402_1005Metric"
		(layer "F.Cu")
		(at 61.6 61.2)
		(descr "Capacitor SMD 0402")
		(tags "capacitor SMD 0402")
		(property "Reference" "C155"
			(at -1.4 -0.8 0)
			(layer "F.SilkS")
			(effects
				(font
					(size 0.7 0.7)
					(thickness 0.15)
				)
				(justify left bottom)
			)
		)
		(property "Value" "C_100n_0402"
			(at -1.022927 2.155213 0)
			(layer "F.Fab")
			(effects
				(font
					(size 0.7 0.7)
					(thickness 0.15)
				)
				(justify left bottom)
			)
		)
		(property "Datasheet" "https://www.murata.com/products/productdetail?partno=GRM155R61H104KE14%23"
			(at 0 0 0)
			(layer "F.Fab")
			(hide yes)
			(effects
				(font
					(size 1.27 1.27)
					(thickness 0.15)
				)
			)
		)
		(property "Description" "SMD Multilayer Ceramic Capacitor, 0.1 µF, 50 V, 0402 [1005 Metric], ± 10%, X5R, GRM Series"
			(at 0 0 0)
			(layer "F.Fab")
			(hide yes)
			(effects
				(font
					(size 1.27 1.27)
					(thickness 0.15)
				)
			)
		)
		(property "Manufacturer" "Murata"
			(at 0 0 0)
			(unlocked yes)
			(layer "F.Fab")
			(hide yes)
			(effects
				(font
					(size 1 1)
					(thickness 0.15)
				)
			)
		)
		(property "MPN" "GRM155R61H104KE14D"
			(at 0 0 0)
			(unlocked yes)
			(layer "F.Fab")
			(hide yes)
			(effects
				(font
					(size 1 1)
					(thickness 0.15)
				)
			)
		)
		(property "Val" "100n"
			(at 0 0 0)
			(unlocked yes)
			(layer "F.Fab")
			(hide yes)
			(effects
				(font
					(size 1 1)
					(thickness 0.15)
				)
			)
		)
		(property "License" "Apache-2.0"
			(at 0 0 0)
			(unlocked yes)
			(layer "F.Fab")
			(hide yes)
			(effects
				(font
					(size 1 1)
					(thickness 0.15)
				)
			)
		)
		(property "Author" "Antmicro"
			(at 0 0 0)
			(unlocked yes)
			(layer "F.Fab")
			(hide yes)
			(effects
				(font
					(size 1 1)
					(thickness 0.15)
				)
			)
		)
		(property "Voltage" "50V"
			(at 0 0 0)
			(unlocked yes)
			(layer "F.Fab")
			(hide yes)
			(effects
				(font
					(size 1 1)
					(thickness 0.15)
				)
			)
		)
		(property "Dielectric" "X5R"
			(at 0 0 0)
			(unlocked yes)
			(layer "F.Fab")
			(hide yes)
			(effects
				(font
					(size 1 1)
					(thickness 0.15)
				)
			)
		)
		(sheetname "/CSI/")
		(sheetfile "csi.kicad_sch")
		(attr smd)
		(fp_poly
			(pts
				(xy -0.925 -0.47) (xy -0.925 0.47) (xy 0.925 0.47) (xy 0.925 -0.47)
			)
			(stroke
				(width 0.05)
				(type default)
			)
			(fill no)
			(layer "F.CrtYd")
		)
		(fp_line
			(start -0.494 -0.25)
			(end 0.504 -0.25)
			(stroke
				(width 0.15)
				(type solid)
			)
			(layer "F.Fab")
		)
		(fp_line
			(start -0.494 0.248)
			(end -0.494 -0.25)
			(stroke
				(width 0.15)
				(type solid)
			)
			(layer "F.Fab")
		)
		(fp_line
			(start 0.504 -0.25)
			(end 0.504 0.248)
			(stroke
				(width 0.15)
				(type solid)
			)
			(layer "F.Fab")
		)
		(fp_line
			(start 0.504 0.248)
			(end -0.494 0.248)
			(stroke
				(width 0.15)
				(type solid)
			)
			(layer "F.Fab")
		)
		(fp_text user "${REFERENCE}"
			(at -0.939 4.599 0)
			(layer "F.Fab")
			(effects
				(font
					(size 0.7 0.7)
					(thickness 0.15)
				)
				(justify left bottom)
			)
		)
		(fp_text user "Author: Antmicro"
			(at -0.939 3.399 0)
			(layer "F.Fab")
			(effects
				(font
					(size 0.7 0.7)
					(thickness 0.15)
				)
				(justify left bottom)
			)
		)
		(fp_text user "License: Apache-2.0"
			(at -0.939 5.799 0)
			(layer "F.Fab")
			(effects
				(font
					(size 0.7 0.7)
					(thickness 0.15)
				)
				(justify left bottom)
			)
		)
		(pad "1" smd roundrect
			(at -0.48 0)
			(size 0.59 0.64)
			(layers "F.Cu" "F.Mask" "F.Paste")
			(roundrect_rratio 0.25)
			(net 1 "GND")
			(pintype "passive")
		)
		(pad "2" smd roundrect
			(at 0.48 0)
			(size 0.59 0.64)
			(layers "F.Cu" "F.Mask" "F.Paste")
			(roundrect_rratio 0.25)
			(net 11 "+1V8")
			(pintype "passive")
		)
	)
	(footprint "antmicro-footprints:C_0402_1005Metric"
		(layer "F.Cu")
		(at 184.039468 144.05 -90)
		(descr "Capacitor SMD 0402")
		(tags "capacitor SMD 0402")
		(property "Reference" "C218"
			(at 0.95 0.339468 90)
			(layer "F.SilkS")
			(effects
				(font
					(size 0.7 0.7)
					(thickness 0.15)
				)
				(justify right top)
			)
		)
		(property "Value" "C_4u7_25V_0402"
			(at -1.022927 2.155213 90)
			(layer "F.Fab")
			(effects
				(font
					(size 0.7 0.7)
					(thickness 0.15)
				)
				(justify right top)
			)
		)
		(property "Datasheet" "https://www.murata.com/products/productdetail?partno=GRM155C61E475ME15%23"
			(at 0 0 90)
			(layer "F.Fab")
			(hide yes)
			(effects
				(font
					(size 1.27 1.27)
					(thickness 0.15)
				)
			)
		)
		(property "Description" "SMD Multilayer Ceramic Capacitor"
			(at 0 0 90)
			(layer "F.Fab")
			(hide yes)
			(effects
				(font
					(size 1.27 1.27)
					(thickness 0.15)
				)
			)
		)
		(property "MPN" "GRM155C61E475ME15J"
			(at 0 0 270)
			(unlocked yes)
			(layer "F.Fab")
			(hide yes)
			(effects
				(font
					(size 1 1)
					(thickness 0.15)
				)
			)
		)
		(property "Manufacturer" "Murata"
			(at 0 0 270)
			(unlocked yes)
			(layer "F.Fab")
			(hide yes)
			(effects
				(font
					(size 1 1)
					(thickness 0.15)
				)
			)
		)
		(property "License" "Apache-2.0"
			(at 0 0 270)
			(unlocked yes)
			(layer "F.Fab")
			(hide yes)
			(effects
				(font
					(size 1 1)
					(thickness 0.15)
				)
			)
		)
		(property "Author" "Antmicro"
			(at 0 0 270)
			(unlocked yes)
			(layer "F.Fab")
			(hide yes)
			(effects
				(font
					(size 1 1)
					(thickness 0.15)
				)
			)
		)
		(property "Val" "4u7"
			(at 0 0 270)
			(unlocked yes)
			(layer "F.Fab")
			(hide yes)
			(effects
				(font
					(size 1 1)
					(thickness 0.15)
				)
			)
		)
		(property "Voltage" "25V"
			(at 0 0 270)
			(unlocked yes)
			(layer "F.Fab")
			(hide yes)
			(effects
				(font
					(size 1 1)
					(thickness 0.15)
				)
			)
		)
		(property "Dielectric" "X5S"
			(at 0 0 270)
			(unlocked yes)
			(layer "F.Fab")
			(hide yes)
			(effects
				(font
					(size 1 1)
					(thickness 0.15)
				)
			)
		)
		(sheetname "/DCDC/")
		(sheetfile "dcdc.kicad_sch")
		(attr smd)
		(fp_rect
			(start -0.925 -0.47)
			(end 0.925 0.47)
			(stroke
				(width 0.05)
				(type default)
			)
			(fill no)
			(layer "F.CrtYd")
		)
		(fp_line
			(start -0.494 0.248)
			(end -0.494 -0.25)
			(stroke
				(width 0.15)
				(type solid)
			)
			(layer "F.Fab")
		)
		(fp_line
			(start 0.504 0.248)
			(end -0.494 0.248)
			(stroke
				(width 0.15)
				(type solid)
			)
			(layer "F.Fab")
		)
		(fp_line
			(start -0.494 -0.25)
			(end 0.504 -0.25)
			(stroke
				(width 0.15)
				(type solid)
			)
			(layer "F.Fab")
		)
		(fp_line
			(start 0.504 -0.25)
			(end 0.504 0.248)
			(stroke
				(width 0.15)
				(type solid)
			)
			(layer "F.Fab")
		)
		(fp_text user "License: Apache-2.0"
			(at -0.939 5.799 90)
			(layer "F.Fab")
			(effects
				(font
					(size 0.7 0.7)
					(thickness 0.15)
				)
				(justify right top)
			)
		)
		(fp_text user "Author: Antmicro"
			(at -0.939 3.399 90)
			(layer "F.Fab")
			(effects
				(font
					(size 0.7 0.7)
					(thickness 0.15)
				)
				(justify right top)
			)
		)
		(fp_text user "${REFERENCE}"
			(at -0.939 4.599 90)
			(layer "F.Fab")
			(effects
				(font
					(size 0.7 0.7)
					(thickness 0.15)
				)
				(justify right top)
			)
		)
		(pad "1" smd roundrect
			(at -0.48 0 270)
			(size 0.59 0.64)
			(layers "F.Cu" "F.Mask" "F.Paste")
			(roundrect_rratio 0.25)
			(net 1 "GND")
			(pintype "passive")
		)
		(pad "2" smd roundrect
			(at 0.48 0 270)
			(size 0.59 0.64)
			(layers "F.Cu" "F.Mask" "F.Paste")
			(roundrect_rratio 0.25)
			(net 578 "/DCDC/12V_VDRV")
			(pintype "passive")
		)
	)
	(footprint "antmicro-footprints:C_0402_1005Metric"
		(layer "F.Cu")
		(at 147.634391 129.03)
		(descr "Capacitor SMD 0402")
		(tags "capacitor SMD 0402")
		(property "Reference" "C33"
			(at 0.965609 0.47 0)
			(layer "F.SilkS")
			(effects
				(font
					(size 0.7 0.7)
					(thickness 0.15)
				)
				(justify left bottom)
			)
		)
		(property "Value" "C_100n_0402"
			(at -1.022927 2.155213 0)
			(layer "F.Fab")
			(effects
				(font
					(size 0.7 0.7)
					(thickness 0.15)
				)
				(justify left bottom)
			)
		)
		(property "Datasheet" "https://www.murata.com/products/productdetail?partno=GRM155R61H104KE14%23"
			(at 0 0 0)
			(layer "F.Fab")
			(hide yes)
			(effects
				(font
					(size 1.27 1.27)
					(thickness 0.15)
				)
			)
		)
		(property "Description" "SMD Multilayer Ceramic Capacitor, 0.1 µF, 50 V, 0402 [1005 Metric], ± 10%, X5R, GRM Series"
			(at 0 0 0)
			(layer "F.Fab")
			(hide yes)
			(effects
				(font
					(size 1.27 1.27)
					(thickness 0.15)
				)
			)
		)
		(property "MPN" "GRM155R61H104KE14D"
			(at 0 0 0)
			(unlocked yes)
			(layer "F.Fab")
			(hide yes)
			(effects
				(font
					(size 1 1)
					(thickness 0.15)
				)
			)
		)
		(property "Manufacturer" "Murata"
			(at 0 0 0)
			(unlocked yes)
			(layer "F.Fab")
			(hide yes)
			(effects
				(font
					(size 1 1)
					(thickness 0.15)
				)
			)
		)
		(property "License" "Apache-2.0"
			(at 0 0 0)
			(unlocked yes)
			(layer "F.Fab")
			(hide yes)
			(effects
				(font
					(size 1 1)
					(thickness 0.15)
				)
			)
		)
		(property "Author" "Antmicro"
			(at 0 0 0)
			(unlocked yes)
			(layer "F.Fab")
			(hide yes)
			(effects
				(font
					(size 1 1)
					(thickness 0.15)
				)
			)
		)
		(property "Val" "100n"
			(at 0 0 0)
			(unlocked yes)
			(layer "F.Fab")
			(hide yes)
			(effects
				(font
					(size 1 1)
					(thickness 0.15)
				)
			)
		)
		(property "Voltage" "50V"
			(at 0 0 0)
			(unlocked yes)
			(layer "F.Fab")
			(hide yes)
			(effects
				(font
					(size 1 1)
					(thickness 0.15)
				)
			)
		)
		(property "Dielectric" "X5R"
			(at 0 0 0)
			(unlocked yes)
			(layer "F.Fab")
			(hide yes)
			(effects
				(font
					(size 1 1)
					(thickness 0.15)
				)
			)
		)
		(property "Public" "False"
			(at 0 0 0)
			(unlocked yes)
			(layer "F.Fab")
			(hide yes)
			(effects
				(font
					(size 1 1)
					(thickness 0.15)
				)
			)
		)
		(component_classes
			(class "DCDC_1V8")
		)
		(sheetname "/DCDC/")
		(sheetfile "dcdc.kicad_sch")
		(attr smd)
		(fp_rect
			(start -0.925 -0.47)
			(end 0.925 0.47)
			(stroke
				(width 0.05)
				(type default)
			)
			(fill no)
			(layer "F.CrtYd")
		)
		(fp_line
			(start -0.494 -0.25)
			(end 0.504 -0.25)
			(stroke
				(width 0.15)
				(type solid)
			)
			(layer "F.Fab")
		)
		(fp_line
			(start -0.494 0.248)
			(end -0.494 -0.25)
			(stroke
				(width 0.15)
				(type solid)
			)
			(layer "F.Fab")
		)
		(fp_line
			(start 0.504 -0.25)
			(end 0.504 0.248)
			(stroke
				(width 0.15)
				(type solid)
			)
			(layer "F.Fab")
		)
		(fp_line
			(start 0.504 0.248)
			(end -0.494 0.248)
			(stroke
				(width 0.15)
				(type solid)
			)
			(layer "F.Fab")
		)
		(fp_text user "${REFERENCE}"
			(at -0.939 4.599 0)
			(layer "F.Fab")
			(effects
				(font
					(size 0.7 0.7)
					(thickness 0.15)
				)
				(justify left bottom)
			)
		)
		(fp_text user "Author: Antmicro"
			(at -0.939 3.399 0)
			(layer "F.Fab")
			(effects
				(font
					(size 0.7 0.7)
					(thickness 0.15)
				)
				(justify left bottom)
			)
		)
		(fp_text user "License: Apache-2.0"
			(at -0.939 5.799 0)
			(layer "F.Fab")
			(effects
				(font
					(size 0.7 0.7)
					(thickness 0.15)
				)
				(justify left bottom)
			)
		)
		(pad "1" smd roundrect
			(at -0.48 0)
			(size 0.59 0.64)
			(layers "F.Cu" "F.Mask" "F.Paste")
			(roundrect_rratio 0.25)
			(net 1 "GND")
			(pintype "passive")
		)
		(pad "2" smd roundrect
			(at 0.48 0)
			(size 0.59 0.64)
			(layers "F.Cu" "F.Mask" "F.Paste")
			(roundrect_rratio 0.25)
			(net 17 "/DCDC/1V8_OUT")
			(pintype "passive")
		)
	)
	(footprint "antmicro-footprints:USON-10_2.5x1mm_P0.5mm"
		(layer "F.Cu")
		(at 221.402132 92.66 180)
		(descr "USON-10 2.5x1mm_ Pitch 0.5mm")
		(tags "USON-10 2.5x1mm Pitch 0.5mm")
		(property "Reference" "U41"
			(at -1.07 1.118 90)
			(layer "F.SilkS")
			(effects
				(font
					(size 0.7 0.7)
					(thickness 0.15)
				)
				(justify right top)
			)
		)
		(property "Value" "TPD4E05U06QDQARQ1"
			(at 0.018 2.499 0)
			(layer "F.Fab")
			(effects
				(font
					(size 0.7 0.7)
					(thickness 0.15)
				)
				(justify right top)
			)
		)
		(property "Datasheet" "https://www.ti.com/lit/ds/symlink/tpd4e05u06-q1.pdf?HQS=dis-mous-null-mousermode-dsf-pf-null-wwe&ts=1663591265741&ref_url=https%253A%252F%252Fwww.mouser.com%252F"
			(at 0 0 0)
			(layer "F.Fab")
			(hide yes)
			(effects
				(font
					(size 1.27 1.27)
					(thickness 0.15)
				)
			)
		)
		(property "Description" "TVS diode array, 12 kV, USON-10, 5.5 V, 0.5 pF"
			(at 0 0 0)
			(layer "F.Fab")
			(hide yes)
			(effects
				(font
					(size 1.27 1.27)
					(thickness 0.15)
				)
			)
		)
		(property "Manufacturer" "Texas Instruments"
			(at 0 0 180)
			(unlocked yes)
			(layer "F.Fab")
			(hide yes)
			(effects
				(font
					(size 1 1)
					(thickness 0.15)
				)
			)
		)
		(property "MPN" "TPD4E05U06QDQARQ1"
			(at 0 0 180)
			(unlocked yes)
			(layer "F.Fab")
			(hide yes)
			(effects
				(font
					(size 1 1)
					(thickness 0.15)
				)
			)
		)
		(property "Author" "Antmicro"
			(at 0 0 180)
			(unlocked yes)
			(layer "F.Fab")
			(hide yes)
			(effects
				(font
					(size 1 1)
					(thickness 0.15)
				)
			)
		)
		(property "License" "Apache-2.0"
			(at 0 0 180)
			(unlocked yes)
			(layer "F.Fab")
			(hide yes)
			(effects
				(font
					(size 1 1)
					(thickness 0.15)
				)
			)
		)
		(sheetname "/USB DP Alt mode/")
		(sheetfile "usb_dp.kicad_sch")
		(attr smd)
		(fp_line
			(start 0.498 1.398)
			(end -0.5 1.398)
			(stroke
				(width 0.15)
				(type solid)
			)
			(layer "F.SilkS")
		)
		(fp_line
			(start 0.498 -1.401)
			(end -0.5 -1.401)
			(stroke
				(width 0.15)
				(type solid)
			)
			(layer "F.SilkS")
		)
		(fp_circle
			(center -0.68 -1.27)
			(end -0.63 -1.27)
			(stroke
				(width 0.15)
				(type solid)
			)
			(fill yes)
			(layer "F.SilkS")
		)
		(fp_rect
			(start -0.8 -1.5)
			(end 0.8 1.499)
			(stroke
				(width 0.05)
				(type solid)
			)
			(fill no)
			(layer "F.CrtYd")
		)
		(fp_line
			(start 0.498 -1.25)
			(end 0.498 1.249)
			(stroke
				(width 0.15)
				(type solid)
			)
			(layer "F.Fab")
		)
		(fp_line
			(start 0.498 -1.25)
			(end -0.25 -1.25)
			(stroke
				(width 0.15)
				(type solid)
			)
			(layer "F.Fab")
		)
		(fp_line
			(start -0.25 -1.25)
			(end -0.5 -1)
			(stroke
				(width 0.15)
				(type solid)
			)
			(layer "F.Fab")
		)
		(fp_line
			(start -0.5 1.249)
			(end 0.498 1.249)
			(stroke
				(width 0.15)
				(type solid)
			)
			(layer "F.Fab")
		)
		(fp_line
			(start -0.5 -1)
			(end -0.5 1.249)
			(stroke
				(width 0.15)
				(type solid)
			)
			(layer "F.Fab")
		)
		(fp_text user "License: Apache-2.0"
			(at -0.802 6.9 0)
			(layer "F.Fab")
			(effects
				(font
					(size 0.7 0.7)
					(thickness 0.15)
				)
				(justify right top)
			)
		)
		(fp_text user "${REFERENCE}"
			(at -0.802 4.498 0)
			(layer "F.Fab")
			(effects
				(font
					(size 0.7 0.7)
					(thickness 0.15)
				)
				(justify right top)
			)
		)
		(fp_text user "Author: Antmicro"
			(at -0.802 5.7 0)
			(layer "F.Fab")
			(effects
				(font
					(size 0.7 0.7)
					(thickness 0.15)
				)
				(justify right top)
			)
		)
		(pad "1" smd roundrect
			(at -0.387 -1 90)
			(size 0.25 0.55)
			(layers "F.Cu" "F.Mask" "F.Paste")
			(roundrect_rratio 0.25)
			(net 822 "/USB DP Alt mode/USBC1_RX1_P")
			(pintype "passive")
		)
		(pad "2" smd roundrect
			(at -0.387 -0.5 90)
			(size 0.25 0.55)
			(layers "F.Cu" "F.Mask" "F.Paste")
			(roundrect_rratio 0.25)
			(net 819 "/USB DP Alt mode/USBC1_RX1_N")
			(pintype "passive")
		)
		(pad "3" smd roundrect
			(at -0.387 0 90)
			(size 0.4 0.55)
			(layers "F.Cu" "F.Mask" "F.Paste")
			(roundrect_rratio 0.25)
			(net 1 "GND")
			(pintype "power_in")
		)
		(pad "4" smd roundrect
			(at -0.387 0.498 90)
			(size 0.25 0.55)
			(layers "F.Cu" "F.Mask" "F.Paste")
			(roundrect_rratio 0.25)
			(net 345 "/USB DP Alt mode/USBC1_CONN_TX1_P")
			(pintype "passive")
		)
		(pad "5" smd roundrect
			(at -0.387 0.998 90)
			(size 0.25 0.55)
			(layers "F.Cu" "F.Mask" "F.Paste")
			(roundrect_rratio 0.25)
			(net 361 "/USB DP Alt mode/USBC1_CONN_TX1_N")
			(pintype "passive")
		)
		(pad "6" smd roundrect
			(at 0.385 0.998 90)
			(size 0.25 0.55)
			(layers "F.Cu" "F.Mask" "F.Paste")
			(roundrect_rratio 0.25)
			(net 361 "/USB DP Alt mode/USBC1_CONN_TX1_N")
			(pintype "passive")
		)
		(pad "7" smd roundrect
			(at 0.385 0.498 90)
			(size 0.25 0.55)
			(layers "F.Cu" "F.Mask" "F.Paste")
			(roundrect_rratio 0.25)
			(net 345 "/USB DP Alt mode/USBC1_CONN_TX1_P")
			(pintype "passive")
		)
		(pad "8" smd roundrect
			(at 0.385 0 90)
			(size 0.4 0.55)
			(layers "F.Cu" "F.Mask" "F.Paste")
			(roundrect_rratio 0.25)
			(net 1 "GND")
			(pintype "passive")
		)
		(pad "9" smd roundrect
			(at 0.385 -0.5 90)
			(size 0.25 0.55)
			(layers "F.Cu" "F.Mask" "F.Paste")
			(roundrect_rratio 0.25)
			(net 819 "/USB DP Alt mode/USBC1_RX1_N")
			(pintype "passive")
		)
		(pad "10" smd roundrect
			(at 0.385 -1 90)
			(size 0.25 0.55)
			(layers "F.Cu" "F.Mask" "F.Paste")
			(roundrect_rratio 0.25)
			(net 822 "/USB DP Alt mode/USBC1_RX1_P")
			(pintype "passive")
		)
	)
	(footprint "antmicro-footprints:C_0805_2012Metric"
		(layer "F.Cu")
		(at 176.33 146.32 -90)
		(descr "Capacitor SMD 0805")
		(tags "capacitor SMD 0805")
		(property "Reference" "C222"
			(at 1.88 0.25 90)
			(layer "F.SilkS")
			(effects
				(font
					(size 0.7 0.7)
					(thickness 0.15)
				)
				(justify right top)
			)
		)
		(property "Value" "C_22u_25V_0805"
			(at -2.055717 1.963152 90)
			(layer "F.Fab")
			(effects
				(font
					(size 0.7 0.7)
					(thickness 0.15)
				)
				(justify right top)
			)
		)
		(property "Datasheet" "https://product.samsungsem.com/mlcc/CL21A226MAYNNN.do"
			(at 0 0 90)
			(layer "F.Fab")
			(hide yes)
			(effects
				(font
					(size 1.27 1.27)
					(thickness 0.15)
				)
			)
		)
		(property "Description" "SMT Multilayer Ceramic Capacitor, 22uF, +/-20%, 25V, X5R, 0805 [2012 Metric]"
			(at 0 0 90)
			(layer "F.Fab")
			(hide yes)
			(effects
				(font
					(size 1.27 1.27)
					(thickness 0.15)
				)
			)
		)
		(property "Manufacturer" "Samsung Electro-Mechanics"
			(at 0 0 270)
			(unlocked yes)
			(layer "F.Fab")
			(hide yes)
			(effects
				(font
					(size 1 1)
					(thickness 0.15)
				)
			)
		)
		(property "MPN" "CL21A226MAYNNNE"
			(at 0 0 270)
			(unlocked yes)
			(layer "F.Fab")
			(hide yes)
			(effects
				(font
					(size 1 1)
					(thickness 0.15)
				)
			)
		)
		(property "Val" "22u"
			(at 0 0 270)
			(unlocked yes)
			(layer "F.Fab")
			(hide yes)
			(effects
				(font
					(size 1 1)
					(thickness 0.15)
				)
			)
		)
		(property "License" "Apache-2.0"
			(at 0 0 270)
			(unlocked yes)
			(layer "F.Fab")
			(hide yes)
			(effects
				(font
					(size 1 1)
					(thickness 0.15)
				)
			)
		)
		(property "Author" "Antmicro"
			(at 0 0 270)
			(unlocked yes)
			(layer "F.Fab")
			(hide yes)
			(effects
				(font
					(size 1 1)
					(thickness 0.15)
				)
			)
		)
		(property "Voltage" "25V"
			(at 0 0 270)
			(unlocked yes)
			(layer "F.Fab")
			(hide yes)
			(effects
				(font
					(size 1 1)
					(thickness 0.15)
				)
			)
		)
		(property "Dielectric" "X5R"
			(at 0 0 270)
			(unlocked yes)
			(layer "F.Fab")
			(hide yes)
			(effects
				(font
					(size 1 1)
					(thickness 0.15)
				)
			)
		)
		(property "Public" "False"
			(at 0 0 270)
			(unlocked yes)
			(layer "F.Fab")
			(hide yes)
			(effects
				(font
					(size 1 1)
					(thickness 0.15)
				)
			)
		)
		(sheetname "/DCDC/")
		(sheetfile "dcdc.kicad_sch")
		(attr smd)
		(fp_line
			(start -0.3 0.7)
			(end 0.3 0.7)
			(stroke
				(width 0.15)
				(type solid)
			)
			(layer "F.SilkS")
		)
		(fp_line
			(start -0.3 -0.7)
			(end 0.3 -0.7)
			(stroke
				(width 0.15)
				(type solid)
			)
			(layer "F.SilkS")
		)
		(fp_rect
			(start 1.95 -0.9)
			(end -1.95 0.9)
			(stroke
				(width 0.05)
				(type default)
			)
			(fill no)
			(layer "F.CrtYd")
		)
		(fp_rect
			(start -0.95 -0.675)
			(end 0.95 0.675)
			(stroke
				(width 0.15)
				(type solid)
			)
			(fill no)
			(layer "F.Fab")
		)
		(fp_text user "Author: Antmicro"
			(at -1.9 5.947 90)
			(layer "F.Fab")
			(effects
				(font
					(size 0.7 0.7)
					(thickness 0.15)
				)
				(justify right top)
			)
		)
		(fp_text user "${REFERENCE}"
			(at -1.9 3.947 90)
			(layer "F.Fab")
			(effects
				(font
					(size 0.7 0.7)
					(thickness 0.15)
				)
				(justify right top)
			)
		)
		(fp_text user "License: Apache-2.0"
			(at -1.9 4.947 90)
			(layer "F.Fab")
			(effects
				(font
					(size 0.7 0.7)
					(thickness 0.15)
				)
				(justify right top)
			)
		)
		(pad "1" smd roundrect
			(at -1.1 0 270)
			(size 1.2 1.3)
			(layers "F.Cu" "F.Mask" "F.Paste")
			(roundrect_rratio 0.25)
			(net 1 "GND")
			(pintype "passive")
		)
		(pad "2" smd roundrect
			(at 1.1 0 270)
			(size 1.2 1.3)
			(layers "F.Cu" "F.Mask" "F.Paste")
			(roundrect_rratio 0.25)
			(net 880 "/DCDC/12V_OUT")
			(pintype "passive")
		)
	)
	(footprint "antmicro-footprints:R_0402_1005Metric"
		(layer "F.Cu")
		(at 88 59.5 180)
		(descr "Resistor SMD 0402")
		(tags "resistor SMD 0402")
		(property "Reference" "R302"
			(at 16.3 -8.8 0)
			(layer "F.SilkS")
			(effects
				(font
					(size 0.7 0.7)
					(thickness 0.15)
				)
				(justify right top)
			)
		)
		(property "Value" "R_0R_0402"
			(at -1.011843 1.772047 0)
			(layer "F.Fab")
			(effects
				(font
					(size 0.7 0.7)
					(thickness 0.15)
				)
				(justify right top)
			)
		)
		(property "Datasheet" "https://industrial.panasonic.com/cdbs/www-data/pdf/RDA0000/AOA0000C301.pdf"
			(at 0 0 0)
			(layer "F.Fab")
			(hide yes)
			(effects
				(font
					(size 1.27 1.27)
					(thickness 0.15)
				)
			)
		)
		(property "Description" "SMD Chip Resistor, Jumper, 0 ohm, 100 mW, 0402 [1005 Metric], Thick Film, General Purpose"
			(at 0 0 0)
			(layer "F.Fab")
			(hide yes)
			(effects
				(font
					(size 1.27 1.27)
					(thickness 0.15)
				)
			)
		)
		(property "MPN" "ERJ2GE0R00X"
			(at 0 0 180)
			(unlocked yes)
			(layer "F.Fab")
			(hide yes)
			(effects
				(font
					(size 1 1)
					(thickness 0.15)
				)
			)
		)
		(property "Manufacturer" "Panasonic"
			(at 0 0 180)
			(unlocked yes)
			(layer "F.Fab")
			(hide yes)
			(effects
				(font
					(size 1 1)
					(thickness 0.15)
				)
			)
		)
		(property "License" "Apache-2.0"
			(at 0 0 180)
			(unlocked yes)
			(layer "F.Fab")
			(hide yes)
			(effects
				(font
					(size 1 1)
					(thickness 0.15)
				)
			)
		)
		(property "Author" "Antmicro"
			(at 0 0 180)
			(unlocked yes)
			(layer "F.Fab")
			(hide yes)
			(effects
				(font
					(size 1 1)
					(thickness 0.15)
				)
			)
		)
		(property "Val" "0R"
			(at 0 0 180)
			(unlocked yes)
			(layer "F.Fab")
			(hide yes)
			(effects
				(font
					(size 1 1)
					(thickness 0.15)
				)
			)
		)
		(property "Tolerance" "~"
			(at 0 0 180)
			(unlocked yes)
			(layer "F.Fab")
			(hide yes)
			(effects
				(font
					(size 1 1)
					(thickness 0.15)
				)
			)
		)
		(property "Current" "1A"
			(at 0 0 180)
			(unlocked yes)
			(layer "F.Fab")
			(hide yes)
			(effects
				(font
					(size 1 1)
					(thickness 0.15)
				)
			)
		)
		(sheetname "/SoM_Power/")
		(sheetfile "som_power.kicad_sch")
		(attr smd)
		(fp_rect
			(start -0.925 -0.47)
			(end 0.925 0.47)
			(stroke
				(width 0.05)
				(type default)
			)
			(fill no)
			(layer "F.CrtYd")
		)
		(fp_rect
			(start -0.5 -0.25)
			(end 0.5 0.25)
			(stroke
				(width 0.15)
				(type solid)
			)
			(fill no)
			(layer "F.Fab")
		)
		(fp_text user "Author: Antmicro"
			(at -0.95 4.169 0)
			(layer "F.Fab")
			(effects
				(font
					(size 0.7 0.7)
					(thickness 0.15)
				)
				(justify right top)
			)
		)
		(fp_text user "License: Apache-2.0"
			(at -0.95 5.169 0)
			(layer "F.Fab")
			(effects
				(font
					(size 0.7 0.7)
					(thickness 0.15)
				)
				(justify right top)
			)
		)
		(fp_text user "${REFERENCE}"
			(at -0.95 3.168 0)
			(layer "F.Fab")
			(effects
				(font
					(size 0.7 0.7)
					(thickness 0.15)
				)
				(justify right top)
			)
		)
		(pad "1" smd roundrect
			(at -0.48 0 180)
			(size 0.59 0.64)
			(layers "F.Cu" "F.Mask" "F.Paste")
			(roundrect_rratio 0.25)
			(net 1035 "Net-(U70-~{INT})")
			(pintype "passive")
		)
		(pad "2" smd roundrect
			(at 0.48 0 180)
			(size 0.59 0.64)
			(layers "F.Cu" "F.Mask" "F.Paste")
			(roundrect_rratio 0.25)
			(net 85 "/SoM_Power/~{SOM_POWER_BTN}")
			(pintype "passive")
		)
	)
	(footprint "antmicro-footprints:R_0402_1005Metric"
		(layer "F.Cu")
		(at 172.869468 117.806 90)
		(descr "Resistor SMD 0402")
		(tags "resistor SMD 0402")
		(property "Reference" "R315"
			(at 2.006 -5.869468 90)
			(layer "F.SilkS")
			(effects
				(font
					(size 0.7 0.7)
					(thickness 0.15)
				)
				(justify right top)
			)
		)
		(property "Value" "R_27R_0402"
			(at -1.011843 1.772047 90)
			(layer "F.Fab")
			(effects
				(font
					(size 0.7 0.7)
					(thickness 0.15)
				)
				(justify left bottom)
			)
		)
		(property "Datasheet" "https://www.bourns.com/docs/product-datasheets/cr.pdf"
			(at 0 0 90)
			(layer "F.Fab")
			(hide yes)
			(effects
				(font
					(size 1.27 1.27)
					(thickness 0.15)
				)
			)
		)
		(property "Description" "SMD Chip Resistor, 27 ohm, ± 1%, 63 mW, 0402 [1005 Metric], Thick Film, General Purpose"
			(at 0 0 90)
			(layer "F.Fab")
			(hide yes)
			(effects
				(font
					(size 1.27 1.27)
					(thickness 0.15)
				)
			)
		)
		(property "MPN" "CR0402-FX-27R0GLF"
			(at 0 0 90)
			(unlocked yes)
			(layer "F.Fab")
			(hide yes)
			(effects
				(font
					(size 1 1)
					(thickness 0.15)
				)
			)
		)
		(property "Manufacturer" "Bourns"
			(at 0 0 90)
			(unlocked yes)
			(layer "F.Fab")
			(hide yes)
			(effects
				(font
					(size 1 1)
					(thickness 0.15)
				)
			)
		)
		(property "License" "Apache-2.0"
			(at 0 0 90)
			(unlocked yes)
			(layer "F.Fab")
			(hide yes)
			(effects
				(font
					(size 1 1)
					(thickness 0.15)
				)
			)
		)
		(property "Author" "Antmicro"
			(at 0 0 90)
			(unlocked yes)
			(layer "F.Fab")
			(hide yes)
			(effects
				(font
					(size 1 1)
					(thickness 0.15)
				)
			)
		)
		(property "Val" "27R"
			(at 0 0 90)
			(unlocked yes)
			(layer "F.Fab")
			(hide yes)
			(effects
				(font
					(size 1 1)
					(thickness 0.15)
				)
			)
		)
		(property "Tolerance" "1%"
			(at 0 0 90)
			(unlocked yes)
			(layer "F.Fab")
			(hide yes)
			(effects
				(font
					(size 1 1)
					(thickness 0.15)
				)
			)
		)
		(sheetname "/DCDC/")
		(sheetfile "dcdc.kicad_sch")
		(attr smd)
		(fp_rect
			(start -0.925 -0.47)
			(end 0.925 0.47)
			(stroke
				(width 0.05)
				(type default)
			)
			(fill no)
			(layer "F.CrtYd")
		)
		(fp_rect
			(start -0.5 -0.25)
			(end 0.5 0.25)
			(stroke
				(width 0.15)
				(type solid)
			)
			(fill no)
			(layer "F.Fab")
		)
		(fp_text user "${REFERENCE}"
			(at -0.95 3.168 90)
			(layer "F.Fab")
			(effects
				(font
					(size 0.7 0.7)
					(thickness 0.15)
				)
				(justify left bottom)
			)
		)
		(fp_text user "License: Apache-2.0"
			(at -0.95 5.169 90)
			(layer "F.Fab")
			(effects
				(font
					(size 0.7 0.7)
					(thickness 0.15)
				)
				(justify left bottom)
			)
		)
		(fp_text user "Author: Antmicro"
			(at -0.95 4.169 90)
			(layer "F.Fab")
			(effects
				(font
					(size 0.7 0.7)
					(thickness 0.15)
				)
				(justify left bottom)
			)
		)
		(pad "1" smd roundrect
			(at -0.48 0 90)
			(size 0.59 0.64)
			(layers "F.Cu" "F.Mask" "F.Paste")
			(roundrect_rratio 0.25)
			(net 1281 "Net-(U50-IN+)")
			(pintype "passive")
		)
		(pad "2" smd roundrect
			(at 0.48 0 90)
			(size 0.59 0.64)
			(layers "F.Cu" "F.Mask" "F.Paste")
			(roundrect_rratio 0.25)
			(net 253 "/DCDC/5V_OUT")
			(pintype "passive")
		)
	)
	(footprint "antmicro-footprints:TP_SMD_0.75mm"
		(layer "F.Cu")
		(at 170.75 57.14 90)
		(property "Reference" "TP7"
			(at -1.52 -0.77 90)
			(layer "F.SilkS")
			(hide yes)
			(effects
				(font
					(size 0.7 0.7)
					(thickness 0.15)
				)
				(justify left bottom)
			)
		)
		(property "Value" "TP_0.75mm_SMD"
			(at 0 1.2 90)
			(layer "F.Fab")
			(effects
				(font
					(size 0.7 0.7)
					(thickness 0.15)
				)
				(justify left bottom)
			)
		)
		(property "Description" "SMT test point"
			(at 0 0 90)
			(layer "F.Fab")
			(hide yes)
			(effects
				(font
					(size 1.27 1.27)
					(thickness 0.15)
				)
			)
		)
		(property "MPN" ""
			(at 0 0 90)
			(unlocked yes)
			(layer "F.Fab")
			(hide yes)
			(effects
				(font
					(size 1 1)
					(thickness 0.15)
				)
			)
		)
		(property "Manufacturer" ""
			(at 0 0 90)
			(unlocked yes)
			(layer "F.Fab")
			(hide yes)
			(effects
				(font
					(size 1 1)
					(thickness 0.15)
				)
			)
		)
		(property "Author" "Antmicro"
			(at 0 0 90)
			(unlocked yes)
			(layer "F.Fab")
			(hide yes)
			(effects
				(font
					(size 1 1)
					(thickness 0.15)
				)
			)
		)
		(property "License" "Apache-2.0"
			(at 0 0 90)
			(unlocked yes)
			(layer "F.Fab")
			(hide yes)
			(effects
				(font
					(size 1 1)
					(thickness 0.15)
				)
			)
		)
		(sheetname "/Power/")
		(sheetfile "power.kicad_sch")
		(attr exclude_from_pos_files exclude_from_bom)
		(fp_circle
			(center 0 0)
			(end 0.475 0)
			(stroke
				(width 0.05)
				(type default)
			)
			(fill no)
			(layer "F.CrtYd")
		)
		(fp_text user "Author: Antmicro"
			(at -0.4 3.901 90)
			(layer "F.Fab")
			(effects
				(font
					(size 0.7 0.7)
					(thickness 0.15)
				)
				(justify left bottom)
			)
		)
		(fp_text user "${REFERENCE}"
			(at -0.4 2.7 90)
			(layer "F.Fab")
			(effects
				(font
					(size 0.7 0.7)
					(thickness 0.15)
				)
				(justify left bottom)
			)
		)
		(fp_text user "License: Apache-2.0"
			(at -0.4 5.101 90)
			(layer "F.Fab")
			(effects
				(font
					(size 0.7 0.7)
					(thickness 0.15)
				)
				(justify left bottom)
			)
		)
		(pad "1" smd circle
			(at 0 0 90)
			(size 0.75 0.75)
			(layers "F.Cu" "F.Mask")
			(net 5 "+5V")
			(pinfunction "1")
			(pintype "passive")
		)
	)
	(footprint "antmicro-footprints:QFN-2L_1.6x1x0.55mm"
		(layer "F.Cu")
		(at 168.4 147.62)
		(property "Reference" "D13"
			(at -0.9 -0.72 0)
			(layer "F.SilkS")
			(effects
				(font
					(size 0.7 0.7)
					(thickness 0.15)
				)
				(justify left bottom)
			)
		)
		(property "Value" "ESDA25P35-1U1M"
			(at 0 1.7 0)
			(layer "F.Fab")
			(effects
				(font
					(size 0.7 0.7)
					(thickness 0.15)
				)
				(justify left bottom)
			)
		)
		(property "Datasheet" "https://www.st.com/resource/en/datasheet/esda25p35-1u1m.pdf"
			(at 0 0 0)
			(layer "F.Fab")
			(hide yes)
			(effects
				(font
					(size 1.27 1.27)
					(thickness 0.15)
				)
			)
		)
		(property "Description" "Unidirectional TVS, 30 kV, QFN-2L, 22 V, 195 pF"
			(at 0 0 0)
			(layer "F.Fab")
			(hide yes)
			(effects
				(font
					(size 1.27 1.27)
					(thickness 0.15)
				)
			)
		)
		(property "Manufacturer" "STMicroelectronics"
			(at 0 0 0)
			(unlocked yes)
			(layer "F.Fab")
			(hide yes)
			(effects
				(font
					(size 1 1)
					(thickness 0.15)
				)
			)
		)
		(property "MPN" "ESDA25P35-1U1M"
			(at 0 0 0)
			(unlocked yes)
			(layer "F.Fab")
			(hide yes)
			(effects
				(font
					(size 1 1)
					(thickness 0.15)
				)
			)
		)
		(property "Author" "Antmicro"
			(at 0 0 0)
			(unlocked yes)
			(layer "F.Fab")
			(hide yes)
			(effects
				(font
					(size 1 1)
					(thickness 0.15)
				)
			)
		)
		(property "License" "Apache-2.0"
			(at 0 0 0)
			(unlocked yes)
			(layer "F.Fab")
			(hide yes)
			(effects
				(font
					(size 1 1)
					(thickness 0.15)
				)
			)
		)
		(sheetname "/DCDC/")
		(sheetfile "dcdc.kicad_sch")
		(attr smd)
		(fp_line
			(start -1.2 -0.4)
			(end -1.2 0.4)
			(stroke
				(width 0.15)
				(type solid)
			)
			(layer "F.SilkS")
		)
		(fp_line
			(start 0.23 -0.45)
			(end -0.23 -0.45)
			(stroke
				(width 0.15)
				(type solid)
			)
			(layer "F.SilkS")
		)
		(fp_line
			(start 0.23 0.45)
			(end -0.23 0.45)
			(stroke
				(width 0.15)
				(type solid)
			)
			(layer "F.SilkS")
		)
		(fp_rect
			(start 1.25 0.65)
			(end -1.25 -0.65)
			(stroke
				(width 0.05)
				(type solid)
			)
			(fill no)
			(layer "F.CrtYd")
		)
		(fp_line
			(start -0.199 -0.202)
			(end -0.199 0.1)
			(stroke
				(width 0.15)
				(type solid)
			)
			(layer "F.Fab")
		)
		(fp_line
			(start -0.199 0)
			(end -0.597 0)
			(stroke
				(width 0.15)
				(type solid)
			)
			(layer "F.Fab")
		)
		(fp_line
			(start -0.199 0.2)
			(end -0.199 0.1)
			(stroke
				(width 0.15)
				(type solid)
			)
			(layer "F.Fab")
		)
		(fp_line
			(start -0.101 0)
			(end 0.201 0.2)
			(stroke
				(width 0.15)
				(type solid)
			)
			(layer "F.Fab")
		)
		(fp_line
			(start 0.201 -0.202)
			(end -0.101 0)
			(stroke
				(width 0.15)
				(type solid)
			)
			(layer "F.Fab")
		)
		(fp_line
			(start 0.201 0)
			(end 0.201 -0.202)
			(stroke
				(width 0.15)
				(type solid)
			)
			(layer "F.Fab")
		)
		(fp_line
			(start 0.201 0.2)
			(end 0.201 0)
			(stroke
				(width 0.15)
				(type solid)
			)
			(layer "F.Fab")
		)
		(fp_line
			(start 0.599 0)
			(end 0.201 0)
			(stroke
				(width 0.15)
				(type solid)
			)
			(layer "F.Fab")
		)
		(fp_rect
			(start 0.848 0.4)
			(end -0.85 -0.402)
			(stroke
				(width 0.15)
				(type solid)
			)
			(fill no)
			(layer "F.Fab")
		)
		(fp_text user "${REFERENCE}"
			(at -1.31 3.769 0)
			(layer "F.Fab")
			(effects
				(font
					(size 0.7 0.7)
					(thickness 0.15)
				)
				(justify left bottom)
			)
		)
		(fp_text user "Author: Antmicro"
			(at -1.31 4.769 0)
			(layer "F.Fab")
			(effects
				(font
					(size 0.7 0.7)
					(thickness 0.15)
				)
				(justify left bottom)
			)
		)
		(fp_text user "License: Apache-2.0"
			(at -1.31 5.769 0)
			(layer "F.Fab")
			(effects
				(font
					(size 0.7 0.7)
					(thickness 0.15)
				)
				(justify left bottom)
			)
		)
		(pad "1" smd roundrect
			(at -0.7 0 180)
			(size 0.8 1)
			(layers "F.Cu" "F.Mask" "F.Paste")
			(roundrect_rratio 0.2)
			(net 634 "+12V")
			(pinfunction "C")
			(pintype "passive")
		)
		(pad "2" smd roundrect
			(at 0.7 0 180)
			(size 0.8 1)
			(layers "F.Cu" "F.Mask" "F.Paste")
			(roundrect_rratio 0.2)
			(net 1 "GND")
			(pinfunction "A")
			(pintype "passive")
		)
	)
	(footprint "antmicro-footprints:R_0402_1005Metric"
		(layer "F.Cu")
		(at 179.146569 123.837356 180)
		(descr "Resistor SMD 0402")
		(tags "resistor SMD 0402")
		(property "Reference" "R38"
			(at -0.95 1.25 0)
			(layer "F.SilkS")
			(effects
				(font
					(size 0.7 0.7)
					(thickness 0.15)
				)
				(justify right top)
			)
		)
		(property "Value" "R_499k_0402"
			(at -1.011843 1.772047 0)
			(layer "F.Fab")
			(effects
				(font
					(size 0.7 0.7)
					(thickness 0.15)
				)
				(justify right top)
			)
		)
		(property "Datasheet" "https://www.mouser.com/datasheet/2/54/cr-1858361.pdf"
			(at 0 0 0)
			(layer "F.Fab")
			(hide yes)
			(effects
				(font
					(size 1.27 1.27)
					(thickness 0.15)
				)
			)
		)
		(property "Description" "SMD Chip Resistor, 499 kohm, ± 1%, 63 mW, 0402 [1005 Metric], Thick Film, General Purpose"
			(at 0 0 0)
			(layer "F.Fab")
			(hide yes)
			(effects
				(font
					(size 1.27 1.27)
					(thickness 0.15)
				)
			)
		)
		(property "MPN" "CR0402-FX-4993GLF"
			(at 0 0 180)
			(unlocked yes)
			(layer "F.Fab")
			(hide yes)
			(effects
				(font
					(size 1 1)
					(thickness 0.15)
				)
			)
		)
		(property "Manufacturer" "Bourns"
			(at 0 0 180)
			(unlocked yes)
			(layer "F.Fab")
			(hide yes)
			(effects
				(font
					(size 1 1)
					(thickness 0.15)
				)
			)
		)
		(property "License" "Apache-2.0"
			(at 0 0 180)
			(unlocked yes)
			(layer "F.Fab")
			(hide yes)
			(effects
				(font
					(size 1 1)
					(thickness 0.15)
				)
			)
		)
		(property "Author" "Antmicro"
			(at 0 0 180)
			(unlocked yes)
			(layer "F.Fab")
			(hide yes)
			(effects
				(font
					(size 1 1)
					(thickness 0.15)
				)
			)
		)
		(property "Val" "499k"
			(at 0 0 180)
			(unlocked yes)
			(layer "F.Fab")
			(hide yes)
			(effects
				(font
					(size 1 1)
					(thickness 0.15)
				)
			)
		)
		(property "Tolerance" "1%"
			(at 0 0 180)
			(unlocked yes)
			(layer "F.Fab")
			(hide yes)
			(effects
				(font
					(size 1 1)
					(thickness 0.15)
				)
			)
		)
		(sheetname "/DCDC/")
		(sheetfile "dcdc.kicad_sch")
		(attr smd exclude_from_pos_files exclude_from_bom dnp)
		(fp_rect
			(start -0.925 -0.47)
			(end 0.925 0.47)
			(stroke
				(width 0.05)
				(type default)
			)
			(fill no)
			(layer "F.CrtYd")
		)
		(fp_rect
			(start -0.5 -0.25)
			(end 0.5 0.25)
			(stroke
				(width 0.15)
				(type solid)
			)
			(fill no)
			(layer "F.Fab")
		)
		(fp_text user "Author: Antmicro"
			(at -0.95 4.169 0)
			(layer "F.Fab")
			(effects
				(font
					(size 0.7 0.7)
					(thickness 0.15)
				)
				(justify right top)
			)
		)
		(fp_text user "${REFERENCE}"
			(at -0.95 3.168 0)
			(layer "F.Fab")
			(effects
				(font
					(size 0.7 0.7)
					(thickness 0.15)
				)
				(justify right top)
			)
		)
		(fp_text user "License: Apache-2.0"
			(at -0.95 5.169 0)
			(layer "F.Fab")
			(effects
				(font
					(size 0.7 0.7)
					(thickness 0.15)
				)
				(justify right top)
			)
		)
		(pad "1" smd roundrect
			(at -0.48 0 180)
			(size 0.59 0.64)
			(layers "F.Cu" "F.Mask" "F.Paste")
			(roundrect_rratio 0.25)
			(net 1213 "/DCDC/3V3_MODE1")
			(pintype "passive")
		)
		(pad "2" smd roundrect
			(at 0.48 0 180)
			(size 0.59 0.64)
			(layers "F.Cu" "F.Mask" "F.Paste")
			(roundrect_rratio 0.25)
			(net 19 "/DCDC/3V3_VDD")
			(pintype "passive")
		)
	)
	(footprint "antmicro-footprints:C_0402_1005Metric"
		(layer "F.Cu")
		(at 219.564132 92.337)
		(descr "Capacitor SMD 0402")
		(tags "capacitor SMD 0402")
		(property "Reference" "C141"
			(at -1.81 1.445 0)
			(layer "F.SilkS")
			(effects
				(font
					(size 0.7 0.7)
					(thickness 0.15)
				)
				(justify left bottom)
			)
		)
		(property "Value" "C_100n_0402"
			(at -1.022927 2.155213 0)
			(layer "F.Fab")
			(effects
				(font
					(size 0.7 0.7)
					(thickness 0.15)
				)
				(justify left bottom)
			)
		)
		(property "Datasheet" "https://www.murata.com/products/productdetail?partno=GRM155R61H104KE14%23"
			(at 0 0 0)
			(layer "F.Fab")
			(hide yes)
			(effects
				(font
					(size 1.27 1.27)
					(thickness 0.15)
				)
			)
		)
		(property "Description" "SMD Multilayer Ceramic Capacitor, 0.1 µF, 50 V, 0402 [1005 Metric], ± 10%, X5R, GRM Series"
			(at 0 0 0)
			(layer "F.Fab")
			(hide yes)
			(effects
				(font
					(size 1.27 1.27)
					(thickness 0.15)
				)
			)
		)
		(property "Manufacturer" "Murata"
			(at 0 0 0)
			(unlocked yes)
			(layer "F.Fab")
			(hide yes)
			(effects
				(font
					(size 1 1)
					(thickness 0.15)
				)
			)
		)
		(property "MPN" "GRM155R61H104KE14D"
			(at 0 0 0)
			(unlocked yes)
			(layer "F.Fab")
			(hide yes)
			(effects
				(font
					(size 1 1)
					(thickness 0.15)
				)
			)
		)
		(property "Val" "100n"
			(at 0 0 0)
			(unlocked yes)
			(layer "F.Fab")
			(hide yes)
			(effects
				(font
					(size 1 1)
					(thickness 0.15)
				)
			)
		)
		(property "License" "Apache-2.0"
			(at 0 0 0)
			(unlocked yes)
			(layer "F.Fab")
			(hide yes)
			(effects
				(font
					(size 1 1)
					(thickness 0.15)
				)
			)
		)
		(property "Author" "Antmicro"
			(at 0 0 0)
			(unlocked yes)
			(layer "F.Fab")
			(hide yes)
			(effects
				(font
					(size 1 1)
					(thickness 0.15)
				)
			)
		)
		(property "Voltage" "50V"
			(at 0 0 0)
			(unlocked yes)
			(layer "F.Fab")
			(hide yes)
			(effects
				(font
					(size 1 1)
					(thickness 0.15)
				)
			)
		)
		(property "Dielectric" "X5R"
			(at 0 0 0)
			(unlocked yes)
			(layer "F.Fab")
			(hide yes)
			(effects
				(font
					(size 1 1)
					(thickness 0.15)
				)
			)
		)
		(sheetname "/USB DP Alt mode/")
		(sheetfile "usb_dp.kicad_sch")
		(attr smd)
		(fp_rect
			(start -0.925 -0.47)
			(end 0.925 0.47)
			(stroke
				(width 0.05)
				(type default)
			)
			(fill no)
			(layer "F.CrtYd")
		)
		(fp_line
			(start -0.494 -0.25)
			(end 0.504 -0.25)
			(stroke
				(width 0.15)
				(type solid)
			)
			(layer "F.Fab")
		)
		(fp_line
			(start -0.494 0.248)
			(end -0.494 -0.25)
			(stroke
				(width 0.15)
				(type solid)
			)
			(layer "F.Fab")
		)
		(fp_line
			(start 0.504 -0.25)
			(end 0.504 0.248)
			(stroke
				(width 0.15)
				(type solid)
			)
			(layer "F.Fab")
		)
		(fp_line
			(start 0.504 0.248)
			(end -0.494 0.248)
			(stroke
				(width 0.15)
				(type solid)
			)
			(layer "F.Fab")
		)
		(fp_text user "Author: Antmicro"
			(at -0.939 3.399 0)
			(layer "F.Fab")
			(effects
				(font
					(size 0.7 0.7)
					(thickness 0.15)
				)
				(justify left bottom)
			)
		)
		(fp_text user "License: Apache-2.0"
			(at -0.939 5.799 0)
			(layer "F.Fab")
			(effects
				(font
					(size 0.7 0.7)
					(thickness 0.15)
				)
				(justify left bottom)
			)
		)
		(fp_text user "${REFERENCE}"
			(at -0.939 4.599 0)
			(layer "F.Fab")
			(effects
				(font
					(size 0.7 0.7)
					(thickness 0.15)
				)
				(justify left bottom)
			)
		)
		(pad "1" smd roundrect
			(at -0.48 0)
			(size 0.59 0.64)
			(layers "F.Cu" "F.Mask" "F.Paste")
			(roundrect_rratio 0.25)
			(net 344 "/USB DP Alt mode/USBC1_TX1_P")
			(pintype "passive")
		)
		(pad "2" smd roundrect
			(at 0.48 0)
			(size 0.59 0.64)
			(layers "F.Cu" "F.Mask" "F.Paste")
			(roundrect_rratio 0.25)
			(net 345 "/USB DP Alt mode/USBC1_CONN_TX1_P")
			(pintype "passive")
		)
	)
	(footprint "antmicro-footprints:C_0805_2012Metric"
		(layer "F.Cu")
		(at 109.510001 56.74 -90)
		(descr "Capacitor SMD 0805")
		(tags "capacitor SMD 0805")
		(property "Reference" "C381"
			(at -1.87 2.650001 0)
			(layer "F.SilkS")
			(effects
				(font
					(size 0.7 0.7)
					(thickness 0.15)
				)
				(justify left bottom)
			)
		)
		(property "Value" "C_22u_25V_0805"
			(at -2.055717 1.963153 90)
			(layer "F.Fab")
			(effects
				(font
					(size 0.7 0.7)
					(thickness 0.15)
				)
				(justify right top)
			)
		)
		(property "Datasheet" "https://product.samsungsem.com/mlcc/CL21A226MAYNNN.do"
			(at 0 0 90)
			(layer "F.Fab")
			(hide yes)
			(effects
				(font
					(size 1.27 1.27)
					(thickness 0.15)
				)
			)
		)
		(property "Description" "SMT Multilayer Ceramic Capacitor, 22uF, +/-20%, 25V, X5R, 0805 [2012 Metric]"
			(at 0 0 90)
			(layer "F.Fab")
			(hide yes)
			(effects
				(font
					(size 1.27 1.27)
					(thickness 0.15)
				)
			)
		)
		(property "MPN" "CL21A226MAYNNNE"
			(at 0 0 270)
			(unlocked yes)
			(layer "F.Fab")
			(hide yes)
			(effects
				(font
					(size 1 1)
					(thickness 0.15)
				)
			)
		)
		(property "Manufacturer" "Samsung Electro-Mechanics"
			(at 0 0 270)
			(unlocked yes)
			(layer "F.Fab")
			(hide yes)
			(effects
				(font
					(size 1 1)
					(thickness 0.15)
				)
			)
		)
		(property "License" "Apache-2.0"
			(at 0 0 270)
			(unlocked yes)
			(layer "F.Fab")
			(hide yes)
			(effects
				(font
					(size 1 1)
					(thickness 0.15)
				)
			)
		)
		(property "Author" "Antmicro"
			(at 0 0 270)
			(unlocked yes)
			(layer "F.Fab")
			(hide yes)
			(effects
				(font
					(size 1 1)
					(thickness 0.15)
				)
			)
		)
		(property "Val" "22u"
			(at 0 0 270)
			(unlocked yes)
			(layer "F.Fab")
			(hide yes)
			(effects
				(font
					(size 1 1)
					(thickness 0.15)
				)
			)
		)
		(property "Voltage" "25V"
			(at 0 0 270)
			(unlocked yes)
			(layer "F.Fab")
			(hide yes)
			(effects
				(font
					(size 1 1)
					(thickness 0.15)
				)
			)
		)
		(property "Dielectric" "X5R"
			(at 0 0 270)
			(unlocked yes)
			(layer "F.Fab")
			(hide yes)
			(effects
				(font
					(size 1 1)
					(thickness 0.15)
				)
			)
		)
		(property "Public" "False"
			(at 0 0 270)
			(unlocked yes)
			(layer "F.Fab")
			(hide yes)
			(effects
				(font
					(size 1 1)
					(thickness 0.15)
				)
			)
		)
		(sheetname "/DCDC/")
		(sheetfile "dcdc.kicad_sch")
		(attr smd)
		(fp_line
			(start -0.3 0.7)
			(end 0.3 0.7)
			(stroke
				(width 0.15)
				(type solid)
			)
			(layer "F.SilkS")
		)
		(fp_line
			(start -0.3 -0.7)
			(end 0.3 -0.7)
			(stroke
				(width 0.15)
				(type solid)
			)
			(layer "F.SilkS")
		)
		(fp_poly
			(pts
				(xy 1.95 -0.9) (xy 1.95 0.9) (xy -1.95 0.9) (xy -1.95 -0.9)
			)
			(stroke
				(width 0.05)
				(type default)
			)
			(fill no)
			(layer "F.CrtYd")
		)
		(fp_poly
			(pts
				(xy -0.95 -0.675001) (xy -0.95 0.675001) (xy 0.95 0.675001) (xy 0.95 -0.675001)
			)
			(stroke
				(width 0.15)
				(type solid)
			)
			(fill no)
			(layer "F.Fab")
		)
		(fp_text user "Author: Antmicro"
			(at -1.9 5.947 90)
			(layer "F.Fab")
			(effects
				(font
					(size 0.7 0.7)
					(thickness 0.15)
				)
				(justify right top)
			)
		)
		(fp_text user "${REFERENCE}"
			(at -1.899999 3.947 90)
			(layer "F.Fab")
			(effects
				(font
					(size 0.7 0.7)
					(thickness 0.15)
				)
				(justify right top)
			)
		)
		(fp_text user "License: Apache-2.0"
			(at -1.9 4.947 90)
			(layer "F.Fab")
			(effects
				(font
					(size 0.7 0.7)
					(thickness 0.15)
				)
				(justify right top)
			)
		)
		(pad "1" smd roundrect
			(at -1.099999 0 270)
			(size 1.2 1.3)
			(layers "F.Cu" "F.Mask" "F.Paste")
			(roundrect_rratio 0.25)
			(net 1 "GND")
			(pintype "passive")
		)
		(pad "2" smd roundrect
			(at 1.099999 0 270)
			(size 1.2 1.3)
			(layers "F.Cu" "F.Mask" "F.Paste")
			(roundrect_rratio 0.25)
			(net 1278 "/DCDC/5V_{AON}_OUT")
			(pintype "passive")
		)
	)
	(footprint "antmicro-footprints:SOIJ-8_5.28x5.28x2.0mm_P1.27mm"
		(layer "F.Cu")
		(at 190.75 118.5 180)
		(descr "8-Pin SOIJ, 1.27 Pitch")
		(property "Reference" "U52"
			(at -4.85 1.8 180)
			(layer "F.SilkS")
			(effects
				(font
					(size 0.7 0.7)
					(thickness 0.15)
				)
				(justify left bottom)
			)
		)
		(property "Value" "SST26VF064B"
			(at 0 3.8 180)
			(layer "F.Fab")
			(effects
				(font
					(size 0.7 0.7)
					(thickness 0.15)
				)
				(justify left bottom)
			)
		)
		(property "Datasheet" "https://www.mouser.com/datasheet/3/282/1/SST26VF064B-SST26VF064BA-2-5V-3-0V-64-Mbit-Serial-Quad-IO--SQI--Flash-Memory-20005119K.pdf"
			(at 0 0 180)
			(layer "F.Fab")
			(hide yes)
			(effects
				(font
					(size 1.27 1.27)
					(thickness 0.15)
				)
			)
		)
		(property "Description" "64-Mbit 2.3V-3.6V, SQI Flash Memory, -40°C to +85°C"
			(at 0 0 180)
			(layer "F.Fab")
			(hide yes)
			(effects
				(font
					(size 1.27 1.27)
					(thickness 0.15)
				)
			)
		)
		(property "MPN" "SST26VF064B-104I/SM"
			(at 0 0 180)
			(unlocked yes)
			(layer "F.Fab")
			(hide yes)
			(effects
				(font
					(size 1 1)
					(thickness 0.15)
				)
			)
		)
		(property "Manufacturer" "Microchip Technology"
			(at 0 0 180)
			(unlocked yes)
			(layer "F.Fab")
			(hide yes)
			(effects
				(font
					(size 1 1)
					(thickness 0.15)
				)
			)
		)
		(property "Author" "Antmicro"
			(at 0 0 180)
			(unlocked yes)
			(layer "F.Fab")
			(hide yes)
			(effects
				(font
					(size 1 1)
					(thickness 0.15)
				)
			)
		)
		(property "License" "Apache-2.0"
			(at 0 0 180)
			(unlocked yes)
			(layer "F.Fab")
			(hide yes)
			(effects
				(font
					(size 1 1)
					(thickness 0.15)
				)
			)
		)
		(sheetname "/USB Hub/")
		(sheetfile "usb_hub.kicad_sch")
		(attr smd exclude_from_pos_files exclude_from_bom dnp)
		(fp_circle
			(center -4.2 -2.6)
			(end -4.15 -2.55)
			(stroke
				(width 0.15)
				(type solid)
			)
			(fill yes)
			(layer "F.SilkS")
		)
		(fp_poly
			(pts
				(xy -2.665 -2.69) (xy -2.665 2.69) (xy 2.665 2.69) (xy 2.665 -2.69)
			)
			(stroke
				(width 0.15)
				(type solid)
			)
			(fill no)
			(layer "F.SilkS")
		)
		(fp_poly
			(pts
				(xy 4.675 -3) (xy 4.675 3) (xy -4.675 3) (xy -4.675 -3)
			)
			(stroke
				(width 0.05)
				(type solid)
			)
			(fill no)
			(layer "F.CrtYd")
		)
		(fp_line
			(start 2.64 2.64)
			(end -2.641 2.64)
			(stroke
				(width 0.15)
				(type solid)
			)
			(layer "F.Fab")
		)
		(fp_line
			(start 2.64 -2.641)
			(end 2.64 2.64)
			(stroke
				(width 0.15)
				(type solid)
			)
			(layer "F.Fab")
		)
		(fp_line
			(start -2.641 2.64)
			(end -2.641 -2.641)
			(stroke
				(width 0.15)
				(type solid)
			)
			(layer "F.Fab")
		)
		(fp_line
			(start -2.641 -1.370999)
			(end -1.370999 -2.641)
			(stroke
				(width 0.15)
				(type solid)
			)
			(layer "F.Fab")
		)
		(fp_line
			(start -2.641 -2.641)
			(end 2.64 -2.641)
			(stroke
				(width 0.15)
				(type solid)
			)
			(layer "F.Fab")
		)
		(fp_text user "License: Apache-2.0"
			(at -4.675 6.938 180)
			(layer "F.Fab")
			(effects
				(font
					(size 0.7 0.7)
					(thickness 0.15)
				)
				(justify left bottom)
			)
		)
		(fp_text user "${REFERENCE}"
			(at -4.675 4.938 180)
			(layer "F.Fab")
			(effects
				(font
					(size 0.7 0.7)
					(thickness 0.15)
				)
				(justify left bottom)
			)
		)
		(fp_text user "Author: Antmicro"
			(at -4.675 5.938 180)
			(layer "F.Fab")
			(effects
				(font
					(size 0.7 0.7)
					(thickness 0.15)
				)
				(justify left bottom)
			)
		)
		(pad "1" smd rect
			(at -3.65 -1.905 270)
			(size 0.65 1.7)
			(layers "F.Cu" "F.Mask" "F.Paste")
			(net 929 "/USB Debug, PD/SPI_{HUB_DEBUG}.~{CS0}")
			(pinfunction "CE#")
			(pintype "input")
		)
		(pad "2" smd rect
			(at -3.65 -0.635 270)
			(size 0.65 1.7)
			(layers "F.Cu" "F.Mask" "F.Paste")
			(net 926 "/USB Debug, PD/SPI_{HUB_DEBUG}.MOSI")
			(pinfunction "SO")
			(pintype "output")
		)
		(pad "3" smd rect
			(at -3.65 0.635 270)
			(size 0.65 1.7)
			(layers "F.Cu" "F.Mask" "F.Paste")
			(net 1166 "/USB Hub/HUB_~{WP}")
			(pinfunction "WP#")
			(pintype "input")
		)
		(pad "4" smd rect
			(at -3.65 1.905 270)
			(size 0.65 1.7)
			(layers "F.Cu" "F.Mask" "F.Paste")
			(net 1 "GND")
			(pinfunction "V_{SS}")
			(pintype "power_in")
		)
		(pad "5" smd rect
			(at 3.65 1.905 270)
			(size 0.65 1.7)
			(layers "F.Cu" "F.Mask" "F.Paste")
			(net 923 "/USB Debug, PD/SPI_{HUB_DEBUG}.MISO")
			(pinfunction "SI")
			(pintype "input")
		)
		(pad "6" smd rect
			(at 3.65 0.635 270)
			(size 0.65 1.7)
			(layers "F.Cu" "F.Mask" "F.Paste")
			(net 928 "/USB Debug, PD/SPI_{HUB_DEBUG}.SCK")
			(pinfunction "SCK")
			(pintype "input")
		)
		(pad "7" smd rect
			(at 3.65 -0.635 270)
			(size 0.65 1.7)
			(layers "F.Cu" "F.Mask" "F.Paste")
			(net 1165 "/USB Hub/HUB_~{HOLD}")
			(pinfunction "HOLD#")
			(pintype "input")
		)
		(pad "8" smd rect
			(at 3.65 -1.905 270)
			(size 0.65 1.7)
			(layers "F.Cu" "F.Mask" "F.Paste")
			(net 271 "FLASH_PWR")
			(pinfunction "V_{DD}")
			(pintype "power_in")
		)
	)
	(footprint "antmicro-footprints:R_0402_1005Metric"
		(layer "F.Cu")
		(at 197.38 85.92 -90)
		(descr "Resistor SMD 0402")
		(tags "resistor SMD 0402")
		(property "Reference" "R109"
			(at -0.92 -0.92 90)
			(layer "F.SilkS")
			(effects
				(font
					(size 0.7 0.7)
					(thickness 0.15)
				)
				(justify right top)
			)
		)
		(property "Value" "R_200R_0402"
			(at -1.011843 1.772047 90)
			(layer "F.Fab")
			(effects
				(font
					(size 0.7 0.7)
					(thickness 0.15)
				)
				(justify right top)
			)
		)
		(property "Datasheet" "https://www.bourns.com/docs/product-datasheets/cr.pdf"
			(at 0 0 90)
			(layer "F.Fab")
			(hide yes)
			(effects
				(font
					(size 1.27 1.27)
					(thickness 0.15)
				)
			)
		)
		(property "Description" "SMD Chip Resistor, 200 ohm, ± 1%, 62.5 mW, 0402 [1005 Metric], Thick Film, General Purpose"
			(at 0 0 90)
			(layer "F.Fab")
			(hide yes)
			(effects
				(font
					(size 1.27 1.27)
					(thickness 0.15)
				)
			)
		)
		(property "Manufacturer" "Bourns"
			(at 0 0 270)
			(unlocked yes)
			(layer "F.Fab")
			(hide yes)
			(effects
				(font
					(size 1 1)
					(thickness 0.15)
				)
			)
		)
		(property "MPN" "CR0402-FX-2000GLF"
			(at 0 0 270)
			(unlocked yes)
			(layer "F.Fab")
			(hide yes)
			(effects
				(font
					(size 1 1)
					(thickness 0.15)
				)
			)
		)
		(property "Val" "200R"
			(at 0 0 270)
			(unlocked yes)
			(layer "F.Fab")
			(hide yes)
			(effects
				(font
					(size 1 1)
					(thickness 0.15)
				)
			)
		)
		(property "License" "Apache-2.0"
			(at 0 0 270)
			(unlocked yes)
			(layer "F.Fab")
			(hide yes)
			(effects
				(font
					(size 1 1)
					(thickness 0.15)
				)
			)
		)
		(property "Author" "Antmicro"
			(at 0 0 270)
			(unlocked yes)
			(layer "F.Fab")
			(hide yes)
			(effects
				(font
					(size 1 1)
					(thickness 0.15)
				)
			)
		)
		(property "Tolerance" "1%"
			(at 0 0 270)
			(unlocked yes)
			(layer "F.Fab")
			(hide yes)
			(effects
				(font
					(size 1 1)
					(thickness 0.15)
				)
			)
		)
		(sheetname "/USB Debug, PD/")
		(sheetfile "usb_debug_pd.kicad_sch")
		(attr smd)
		(fp_rect
			(start -0.925 -0.47)
			(end 0.925 0.47)
			(stroke
				(width 0.05)
				(type default)
			)
			(fill no)
			(layer "F.CrtYd")
		)
		(fp_rect
			(start -0.5 -0.25)
			(end 0.5 0.25)
			(stroke
				(width 0.15)
				(type solid)
			)
			(fill no)
			(layer "F.Fab")
		)
		(fp_text user "Author: Antmicro"
			(at -0.95 4.169 90)
			(layer "F.Fab")
			(effects
				(font
					(size 0.7 0.7)
					(thickness 0.15)
				)
				(justify right top)
			)
		)
		(fp_text user "${REFERENCE}"
			(at -0.95 3.168 90)
			(layer "F.Fab")
			(effects
				(font
					(size 0.7 0.7)
					(thickness 0.15)
				)
				(justify right top)
			)
		)
		(fp_text user "License: Apache-2.0"
			(at -0.95 5.169 90)
			(layer "F.Fab")
			(effects
				(font
					(size 0.7 0.7)
					(thickness 0.15)
				)
				(justify right top)
			)
		)
		(pad "1" smd roundrect
			(at -0.48 0 270)
			(size 0.59 0.64)
			(layers "F.Cu" "F.Mask" "F.Paste")
			(roundrect_rratio 0.25)
			(net 952 "/USB Debug, PD/PDC_GPIO15")
			(pintype "passive")
		)
		(pad "2" smd roundrect
			(at 0.48 0 270)
			(size 0.59 0.64)
			(layers "F.Cu" "F.Mask" "F.Paste")
			(roundrect_rratio 0.25)
			(net 534 "Net-(D19-A)")
			(pintype "passive")
		)
	)
	(footprint "antmicro-footprints:LED_0603_1608Metric_G"
		(layer "F.Cu")
		(at 164 55.3 -90)
		(descr "LED SMD 0603 Green")
		(tags "LED SMD 0603 Green")
		(property "Reference" "D43"
			(at -0.85 1.44 90)
			(layer "F.SilkS")
			(effects
				(font
					(size 0.7 0.7)
					(thickness 0.15)
				)
				(justify right top)
			)
		)
		(property "Value" "LED_G_0603_LTST-C190GKT"
			(at -0.001 1.599 90)
			(layer "F.Fab")
			(effects
				(font
					(size 0.7 0.7)
					(thickness 0.15)
				)
				(justify right top)
			)
		)
		(property "Datasheet" "https://media.digikey.com/pdf/Data%20Sheets/Lite-On%20PDFs/LTST-C190GKT.pdf"
			(at 0 0 90)
			(layer "F.Fab")
			(hide yes)
			(effects
				(font
					(size 1.27 1.27)
					(thickness 0.15)
				)
			)
		)
		(property "Description" "LED, Green, SMD, 0603, 20 mA, 2.1 V, 569 nm"
			(at 0 0 90)
			(layer "F.Fab")
			(hide yes)
			(effects
				(font
					(size 1.27 1.27)
					(thickness 0.15)
				)
			)
		)
		(property "MPN" "LTST-C190GKT"
			(at 0 0 270)
			(unlocked yes)
			(layer "F.Fab")
			(hide yes)
			(effects
				(font
					(size 1 1)
					(thickness 0.15)
				)
			)
		)
		(property "Manufacturer" "Lite-On"
			(at 0 0 270)
			(unlocked yes)
			(layer "F.Fab")
			(hide yes)
			(effects
				(font
					(size 1 1)
					(thickness 0.15)
				)
			)
		)
		(property "Author" "Antmicro"
			(at 0 0 270)
			(unlocked yes)
			(layer "F.Fab")
			(hide yes)
			(effects
				(font
					(size 1 1)
					(thickness 0.15)
				)
			)
		)
		(property "License" "Apache-2.0"
			(at 0 0 270)
			(unlocked yes)
			(layer "F.Fab")
			(hide yes)
			(effects
				(font
					(size 1 1)
					(thickness 0.15)
				)
			)
		)
		(property "Color" "Green"
			(at 0 0 270)
			(unlocked yes)
			(layer "F.Fab")
			(hide yes)
			(effects
				(font
					(size 1 1)
					(thickness 0.15)
				)
			)
		)
		(sheetname "/Power/")
		(sheetfile "power.kicad_sch")
		(attr smd)
		(fp_line
			(start 0.22 0.35)
			(end -0.22 0.35)
			(stroke
				(width 0.15)
				(type solid)
			)
			(layer "F.SilkS")
		)
		(fp_line
			(start -0.094672 0.201008)
			(end -0.094672 -0.198992)
			(stroke
				(width 0.1)
				(type solid)
			)
			(layer "F.SilkS")
		)
		(fp_line
			(start 0.105328 0.201008)
			(end -0.094672 0.001008)
			(stroke
				(width 0.1)
				(type solid)
			)
			(layer "F.SilkS")
		)
		(fp_line
			(start 0.105328 0.201008)
			(end 0.105328 -0.198992)
			(stroke
				(width 0.1)
				(type solid)
			)
			(layer "F.SilkS")
		)
		(fp_line
			(start -0.094672 0.001008)
			(end -0.24 0.001008)
			(stroke
				(width 0.1)
				(type solid)
			)
			(layer "F.SilkS")
		)
		(fp_line
			(start -0.094672 0.001008)
			(end 0.105328 -0.198992)
			(stroke
				(width 0.1)
				(type solid)
			)
			(layer "F.SilkS")
		)
		(fp_line
			(start 0.105328 0.001008)
			(end 0.24 0.001)
			(stroke
				(width 0.1)
				(type solid)
			)
			(layer "F.SilkS")
		)
		(fp_line
			(start -1.18 -0.319)
			(end -1.18 0.321)
			(stroke
				(width 0.15)
				(type solid)
			)
			(layer "F.SilkS")
		)
		(fp_line
			(start 0.22 -0.35)
			(end -0.22 -0.35)
			(stroke
				(width 0.15)
				(type solid)
			)
			(layer "F.SilkS")
		)
		(fp_rect
			(start 1.25 0.65)
			(end -1.25 -0.65)
			(stroke
				(width 0.05)
				(type solid)
			)
			(fill no)
			(layer "F.CrtYd")
		)
		(fp_line
			(start -0.199 0.2)
			(end -0.199 0.1)
			(stroke
				(width 0.15)
				(type solid)
			)
			(layer "F.Fab")
		)
		(fp_line
			(start 0.201 0.2)
			(end 0.201 0)
			(stroke
				(width 0.15)
				(type solid)
			)
			(layer "F.Fab")
		)
		(fp_line
			(start -0.199 0)
			(end -0.597 0)
			(stroke
				(width 0.15)
				(type solid)
			)
			(layer "F.Fab")
		)
		(fp_line
			(start -0.101 0)
			(end 0.201 0.2)
			(stroke
				(width 0.15)
				(type solid)
			)
			(layer "F.Fab")
		)
		(fp_line
			(start 0.201 0)
			(end 0.201 -0.202)
			(stroke
				(width 0.15)
				(type solid)
			)
			(layer "F.Fab")
		)
		(fp_line
			(start 0.599 0)
			(end 0.201 0)
			(stroke
				(width 0.15)
				(type solid)
			)
			(layer "F.Fab")
		)
		(fp_line
			(start -0.199 -0.202)
			(end -0.199 0.1)
			(stroke
				(width 0.15)
				(type solid)
			)
			(layer "F.Fab")
		)
		(fp_line
			(start 0.201 -0.202)
			(end -0.101 0)
			(stroke
				(width 0.15)
				(type solid)
			)
			(layer "F.Fab")
		)
		(fp_rect
			(start 0.848 0.4)
			(end -0.85 -0.402)
			(stroke
				(width 0.15)
				(type solid)
			)
			(fill no)
			(layer "F.Fab")
		)
		(fp_text user "Author: Antmicro"
			(at -1.4224 4.799 90)
			(layer "F.Fab")
			(effects
				(font
					(size 0.7 0.7)
					(thickness 0.15)
				)
				(justify right top)
			)
		)
		(fp_text user "${REFERENCE}"
			(at -1.4224 5.999 90)
			(layer "F.Fab")
			(effects
				(font
					(size 0.7 0.7)
					(thickness 0.15)
				)
				(justify right top)
			)
		)
		(fp_text user "License: Apache-2.0"
			(at -1.4224 3.599 90)
			(layer "F.Fab")
			(effects
				(font
					(size 0.7 0.7)
					(thickness 0.15)
				)
				(justify right top)
			)
		)
		(pad "1" smd roundrect
			(at -0.7 0 90)
			(size 0.8 1)
			(layers "F.Cu" "F.Mask" "F.Paste")
			(roundrect_rratio 0.2)
			(net 644 "Net-(D43-C)")
			(pinfunction "C")
			(pintype "passive")
		)
		(pad "2" smd roundrect
			(at 0.7 0 90)
			(size 0.8 1)
			(layers "F.Cu" "F.Mask" "F.Paste")
			(roundrect_rratio 0.2)
			(net 645 "Net-(D43-A)")
			(pinfunction "A")
			(pintype "passive")
		)
	)
	(footprint "antmicro-footprints:C_0402_1005Metric"
		(layer "F.Cu")
		(at 177.945 127.58 -90)
		(descr "Capacitor SMD 0402")
		(tags "capacitor SMD 0402")
		(property "Reference" "C49"
			(at -2.89 0.47 90)
			(layer "F.SilkS")
			(effects
				(font
					(size 0.7 0.7)
					(thickness 0.15)
				)
				(justify right top)
			)
		)
		(property "Value" "C_100n_0402"
			(at -1.022927 2.155213 90)
			(layer "F.Fab")
			(effects
				(font
					(size 0.7 0.7)
					(thickness 0.15)
				)
				(justify right top)
			)
		)
		(property "Datasheet" "https://www.murata.com/products/productdetail?partno=GRM155R61H104KE14%23"
			(at 0 0 90)
			(layer "F.Fab")
			(hide yes)
			(effects
				(font
					(size 1.27 1.27)
					(thickness 0.15)
				)
			)
		)
		(property "Description" "SMD Multilayer Ceramic Capacitor, 0.1 µF, 50 V, 0402 [1005 Metric], ± 10%, X5R, GRM Series"
			(at 0 0 90)
			(layer "F.Fab")
			(hide yes)
			(effects
				(font
					(size 1.27 1.27)
					(thickness 0.15)
				)
			)
		)
		(property "Manufacturer" "Murata"
			(at 0 0 270)
			(unlocked yes)
			(layer "F.Fab")
			(hide yes)
			(effects
				(font
					(size 1 1)
					(thickness 0.15)
				)
			)
		)
		(property "MPN" "GRM155R61H104KE14D"
			(at 0 0 270)
			(unlocked yes)
			(layer "F.Fab")
			(hide yes)
			(effects
				(font
					(size 1 1)
					(thickness 0.15)
				)
			)
		)
		(property "Val" "100n"
			(at 0 0 270)
			(unlocked yes)
			(layer "F.Fab")
			(hide yes)
			(effects
				(font
					(size 1 1)
					(thickness 0.15)
				)
			)
		)
		(property "License" "Apache-2.0"
			(at 0 0 270)
			(unlocked yes)
			(layer "F.Fab")
			(hide yes)
			(effects
				(font
					(size 1 1)
					(thickness 0.15)
				)
			)
		)
		(property "Author" "Antmicro"
			(at 0 0 270)
			(unlocked yes)
			(layer "F.Fab")
			(hide yes)
			(effects
				(font
					(size 1 1)
					(thickness 0.15)
				)
			)
		)
		(property "Voltage" "50V"
			(at 0 0 270)
			(unlocked yes)
			(layer "F.Fab")
			(hide yes)
			(effects
				(font
					(size 1 1)
					(thickness 0.15)
				)
			)
		)
		(property "Dielectric" "X5R"
			(at 0 0 270)
			(unlocked yes)
			(layer "F.Fab")
			(hide yes)
			(effects
				(font
					(size 1 1)
					(thickness 0.15)
				)
			)
		)
		(sheetname "/DCDC/")
		(sheetfile "dcdc.kicad_sch")
		(attr smd)
		(fp_rect
			(start -0.925 -0.47)
			(end 0.925 0.47)
			(stroke
				(width 0.05)
				(type default)
			)
			(fill no)
			(layer "F.CrtYd")
		)
		(fp_line
			(start -0.494 0.248)
			(end -0.494 -0.25)
			(stroke
				(width 0.15)
				(type solid)
			)
			(layer "F.Fab")
		)
		(fp_line
			(start 0.504 0.248)
			(end -0.494 0.248)
			(stroke
				(width 0.15)
				(type solid)
			)
			(layer "F.Fab")
		)
		(fp_line
			(start -0.494 -0.25)
			(end 0.504 -0.25)
			(stroke
				(width 0.15)
				(type solid)
			)
			(layer "F.Fab")
		)
		(fp_line
			(start 0.504 -0.25)
			(end 0.504 0.248)
			(stroke
				(width 0.15)
				(type solid)
			)
			(layer "F.Fab")
		)
		(fp_text user "License: Apache-2.0"
			(at -0.939 5.799 90)
			(layer "F.Fab")
			(effects
				(font
					(size 0.7 0.7)
					(thickness 0.15)
				)
				(justify right top)
			)
		)
		(fp_text user "${REFERENCE}"
			(at -0.939 4.599 90)
			(layer "F.Fab")
			(effects
				(font
					(size 0.7 0.7)
					(thickness 0.15)
				)
				(justify right top)
			)
		)
		(fp_text user "Author: Antmicro"
			(at -0.939 3.399 90)
			(layer "F.Fab")
			(effects
				(font
					(size 0.7 0.7)
					(thickness 0.15)
				)
				(justify right top)
			)
		)
		(pad "1" smd roundrect
			(at -0.48 0 270)
			(size 0.59 0.64)
			(layers "F.Cu" "F.Mask" "F.Paste")
			(roundrect_rratio 0.25)
			(net 13 "VCC")
			(pintype "passive")
		)
		(pad "2" smd roundrect
			(at 0.48 0 270)
			(size 0.59 0.64)
			(layers "F.Cu" "F.Mask" "F.Paste")
			(roundrect_rratio 0.25)
			(net 1 "GND")
			(pintype "passive")
		)
	)
	(footprint "antmicro-footprints:LED_0603_1608Metric_G"
		(layer "F.Cu")
		(at 235.540532 108.71 180)
		(descr "LED SMD 0603 Green")
		(tags "LED SMD 0603 Green")
		(property "Reference" "D51"
			(at -1.059468 -0.799999 0)
			(layer "F.SilkS")
			(effects
				(font
					(size 0.7 0.7)
					(thickness 0.15)
				)
				(justify right top)
			)
		)
		(property "Value" "LED_G_0603_LTST-C190GKT"
			(at -0.001 1.599 0)
			(layer "F.Fab")
			(effects
				(font
					(size 0.7 0.7)
					(thickness 0.15)
				)
				(justify right top)
			)
		)
		(property "Datasheet" "https://media.digikey.com/pdf/Data%20Sheets/Lite-On%20PDFs/LTST-C190GKT.pdf"
			(at 0 0 0)
			(layer "F.Fab")
			(hide yes)
			(effects
				(font
					(size 1.27 1.27)
					(thickness 0.15)
				)
			)
		)
		(property "Description" "LED, Green, SMD, 0603, 20 mA, 2.1 V, 569 nm"
			(at 0 0 0)
			(layer "F.Fab")
			(hide yes)
			(effects
				(font
					(size 1.27 1.27)
					(thickness 0.15)
				)
			)
		)
		(property "MPN" "LTST-C190GKT"
			(at 0 0 180)
			(unlocked yes)
			(layer "F.Fab")
			(hide yes)
			(effects
				(font
					(size 1 1)
					(thickness 0.15)
				)
			)
		)
		(property "Manufacturer" "Lite-On"
			(at 0 0 180)
			(unlocked yes)
			(layer "F.Fab")
			(hide yes)
			(effects
				(font
					(size 1 1)
					(thickness 0.15)
				)
			)
		)
		(property "Author" "Antmicro"
			(at 0 0 180)
			(unlocked yes)
			(layer "F.Fab")
			(hide yes)
			(effects
				(font
					(size 1 1)
					(thickness 0.15)
				)
			)
		)
		(property "License" "Apache-2.0"
			(at 0 0 180)
			(unlocked yes)
			(layer "F.Fab")
			(hide yes)
			(effects
				(font
					(size 1 1)
					(thickness 0.15)
				)
			)
		)
		(property "Color" "Green"
			(at 0 0 180)
			(unlocked yes)
			(layer "F.Fab")
			(hide yes)
			(effects
				(font
					(size 1 1)
					(thickness 0.15)
				)
			)
		)
		(sheetname "/Recovery USB/")
		(sheetfile "recovery_usb.kicad_sch")
		(attr smd)
		(fp_line
			(start 0.22 0.35)
			(end -0.22 0.35)
			(stroke
				(width 0.15)
				(type solid)
			)
			(layer "F.SilkS")
		)
		(fp_line
			(start 0.22 -0.35)
			(end -0.22 -0.35)
			(stroke
				(width 0.15)
				(type solid)
			)
			(layer "F.SilkS")
		)
		(fp_line
			(start 0.105328 0.201008)
			(end 0.105329 -0.198992)
			(stroke
				(width 0.1)
				(type solid)
			)
			(layer "F.SilkS")
		)
		(fp_line
			(start 0.105328 0.201008)
			(end -0.094672 0.001008)
			(stroke
				(width 0.1)
				(type solid)
			)
			(layer "F.SilkS")
		)
		(fp_line
			(start 0.105328 0.001008)
			(end 0.240001 0.001)
			(stroke
				(width 0.1)
				(type solid)
			)
			(layer "F.SilkS")
		)
		(fp_line
			(start -0.094672 0.201008)
			(end -0.094672 -0.198992)
			(stroke
				(width 0.1)
				(type solid)
			)
			(layer "F.SilkS")
		)
		(fp_line
			(start -0.094672 0.001008)
			(end 0.105329 -0.198992)
			(stroke
				(width 0.1)
				(type solid)
			)
			(layer "F.SilkS")
		)
		(fp_line
			(start -0.094672 0.001008)
			(end -0.24 0.001008)
			(stroke
				(width 0.1)
				(type solid)
			)
			(layer "F.SilkS")
		)
		(fp_line
			(start -1.18 -0.319)
			(end -1.18 0.321)
			(stroke
				(width 0.15)
				(type solid)
			)
			(layer "F.SilkS")
		)
		(fp_poly
			(pts
				(xy 1.25 0.65) (xy -1.25 0.65) (xy -1.25 -0.65) (xy 1.25 -0.65)
			)
			(stroke
				(width 0.05)
				(type solid)
			)
			(fill no)
			(layer "F.CrtYd")
		)
		(fp_line
			(start 0.599 0)
			(end 0.200999 0)
			(stroke
				(width 0.15)
				(type solid)
			)
			(layer "F.Fab")
		)
		(fp_line
			(start 0.201 0.2)
			(end 0.200999 0)
			(stroke
				(width 0.15)
				(type solid)
			)
			(layer "F.Fab")
		)
		(fp_line
			(start 0.201 -0.202)
			(end -0.101 0)
			(stroke
				(width 0.15)
				(type solid)
			)
			(layer "F.Fab")
		)
		(fp_line
			(start 0.200999 0)
			(end 0.201 -0.202)
			(stroke
				(width 0.15)
				(type solid)
			)
			(layer "F.Fab")
		)
		(fp_line
			(start -0.101 0)
			(end 0.201 0.2)
			(stroke
				(width 0.15)
				(type solid)
			)
			(layer "F.Fab")
		)
		(fp_line
			(start -0.199 0.2)
			(end -0.199 0.1)
			(stroke
				(width 0.15)
				(type solid)
			)
			(layer "F.Fab")
		)
		(fp_line
			(start -0.199 0)
			(end -0.597 0)
			(stroke
				(width 0.15)
				(type solid)
			)
			(layer "F.Fab")
		)
		(fp_line
			(start -0.199 -0.202)
			(end -0.199 0.1)
			(stroke
				(width 0.15)
				(type solid)
			)
			(layer "F.Fab")
		)
		(fp_poly
			(pts
				(xy 0.848 0.4) (xy -0.85 0.4) (xy -0.85 -0.402) (xy 0.848 -0.401999)
			)
			(stroke
				(width 0.15)
				(type solid)
			)
			(fill no)
			(layer "F.Fab")
		)
		(fp_text user "Author: Antmicro"
			(at -1.4224 4.799 0)
			(layer "F.Fab")
			(effects
				(font
					(size 0.7 0.7)
					(thickness 0.15)
				)
				(justify right top)
			)
		)
		(fp_text user "License: Apache-2.0"
			(at -1.4224 3.599 0)
			(layer "F.Fab")
			(effects
				(font
					(size 0.7 0.7)
					(thickness 0.15)
				)
				(justify right top)
			)
		)
		(fp_text user "${REFERENCE}"
			(at -1.4224 5.999 0)
			(layer "F.Fab")
			(effects
				(font
					(size 0.7 0.7)
					(thickness 0.15)
				)
				(justify right top)
			)
		)
		(pad "1" smd roundrect
			(at -0.7 0)
			(size 0.8 1)
			(layers "F.Cu" "F.Mask" "F.Paste")
			(roundrect_rratio 0.2)
			(net 1 "GND")
			(pinfunction "C")
			(pintype "passive")
		)
		(pad "2" smd roundrect
			(at 0.7 0)
			(size 0.8 1)
			(layers "F.Cu" "F.Mask" "F.Paste")
			(roundrect_rratio 0.2)
			(net 1391 "Net-(D51-A)")
			(pinfunction "A")
			(pintype "passive")
		)
	)
	(footprint "antmicro-footprints:C_0402_1005Metric"
		(layer "F.Cu")
		(at 179.152101 124.827356)
		(descr "Capacitor SMD 0402")
		(tags "capacitor SMD 0402")
		(property "Reference" "C60"
			(at -3.075 -0.23 0)
			(layer "F.SilkS")
			(effects
				(font
					(size 0.7 0.7)
					(thickness 0.15)
				)
				(justify left bottom)
			)
		)
		(property "Value" "C_100n_0402"
			(at -1.022927 2.155213 0)
			(layer "F.Fab")
			(effects
				(font
					(size 0.7 0.7)
					(thickness 0.15)
				)
				(justify left bottom)
			)
		)
		(property "Datasheet" "https://www.murata.com/products/productdetail?partno=GRM155R61H104KE14%23"
			(at 0 0 0)
			(layer "F.Fab")
			(hide yes)
			(effects
				(font
					(size 1.27 1.27)
					(thickness 0.15)
				)
			)
		)
		(property "Description" "SMD Multilayer Ceramic Capacitor, 0.1 µF, 50 V, 0402 [1005 Metric], ± 10%, X5R, GRM Series"
			(at 0 0 0)
			(layer "F.Fab")
			(hide yes)
			(effects
				(font
					(size 1.27 1.27)
					(thickness 0.15)
				)
			)
		)
		(property "Manufacturer" "Murata"
			(at 0 0 0)
			(unlocked yes)
			(layer "F.Fab")
			(hide yes)
			(effects
				(font
					(size 1 1)
					(thickness 0.15)
				)
			)
		)
		(property "MPN" "GRM155R61H104KE14D"
			(at 0 0 0)
			(unlocked yes)
			(layer "F.Fab")
			(hide yes)
			(effects
				(font
					(size 1 1)
					(thickness 0.15)
				)
			)
		)
		(property "Val" "100n"
			(at 0 0 0)
			(unlocked yes)
			(layer "F.Fab")
			(hide yes)
			(effects
				(font
					(size 1 1)
					(thickness 0.15)
				)
			)
		)
		(property "License" "Apache-2.0"
			(at 0 0 0)
			(unlocked yes)
			(layer "F.Fab")
			(hide yes)
			(effects
				(font
					(size 1 1)
					(thickness 0.15)
				)
			)
		)
		(property "Author" "Antmicro"
			(at 0 0 0)
			(unlocked yes)
			(layer "F.Fab")
			(hide yes)
			(effects
				(font
					(size 1 1)
					(thickness 0.15)
				)
			)
		)
		(property "Voltage" "50V"
			(at 0 0 0)
			(unlocked yes)
			(layer "F.Fab")
			(hide yes)
			(effects
				(font
					(size 1 1)
					(thickness 0.15)
				)
			)
		)
		(property "Dielectric" "X5R"
			(at 0 0 0)
			(unlocked yes)
			(layer "F.Fab")
			(hide yes)
			(effects
				(font
					(size 1 1)
					(thickness 0.15)
				)
			)
		)
		(sheetname "/DCDC/")
		(sheetfile "dcdc.kicad_sch")
		(attr smd)
		(fp_rect
			(start -0.925 -0.47)
			(end 0.925 0.47)
			(stroke
				(width 0.05)
				(type default)
			)
			(fill no)
			(layer "F.CrtYd")
		)
		(fp_line
			(start -0.494 -0.25)
			(end 0.504 -0.25)
			(stroke
				(width 0.15)
				(type solid)
			)
			(layer "F.Fab")
		)
		(fp_line
			(start -0.494 0.248)
			(end -0.494 -0.25)
			(stroke
				(width 0.15)
				(type solid)
			)
			(layer "F.Fab")
		)
		(fp_line
			(start 0.504 -0.25)
			(end 0.504 0.248)
			(stroke
				(width 0.15)
				(type solid)
			)
			(layer "F.Fab")
		)
		(fp_line
			(start 0.504 0.248)
			(end -0.494 0.248)
			(stroke
				(width 0.15)
				(type solid)
			)
			(layer "F.Fab")
		)
		(fp_text user "Author: Antmicro"
			(at -0.939 3.399 0)
			(layer "F.Fab")
			(effects
				(font
					(size 0.7 0.7)
					(thickness 0.15)
				)
				(justify left bottom)
			)
		)
		(fp_text user "License: Apache-2.0"
			(at -0.939 5.799 0)
			(layer "F.Fab")
			(effects
				(font
					(size 0.7 0.7)
					(thickness 0.15)
				)
				(justify left bottom)
			)
		)
		(fp_text user "${REFERENCE}"
			(at -0.939 4.599 0)
			(layer "F.Fab")
			(effects
				(font
					(size 0.7 0.7)
					(thickness 0.15)
				)
				(justify left bottom)
			)
		)
		(pad "1" smd roundrect
			(at -0.48 0)
			(size 0.59 0.64)
			(layers "F.Cu" "F.Mask" "F.Paste")
			(roundrect_rratio 0.25)
			(net 29 "/DCDC/3V3_PHASE")
			(pintype "passive")
		)
		(pad "2" smd roundrect
			(at 0.48 0)
			(size 0.59 0.64)
			(layers "F.Cu" "F.Mask" "F.Paste")
			(roundrect_rratio 0.25)
			(net 28 "/DCDC/3V3_BOOT")
			(pintype "passive")
		)
	)
	(footprint "antmicro-footprints:C_0805_2012Metric"
		(layer "F.Cu")
		(at 167.72 99.81 90)
		(descr "Capacitor SMD 0805")
		(tags "capacitor SMD 0805")
		(property "Reference" "C250"
			(at -4.595 0.345 90)
			(layer "F.SilkS")
			(effects
				(font
					(size 0.7 0.7)
					(thickness 0.15)
				)
				(justify left bottom)
			)
		)
		(property "Value" "C_22u_25V_0805"
			(at -2.055717 1.963152 90)
			(layer "F.Fab")
			(effects
				(font
					(size 0.7 0.7)
					(thickness 0.15)
				)
				(justify left bottom)
			)
		)
		(property "Datasheet" "https://product.samsungsem.com/mlcc/CL21A226MAYNNN.do"
			(at 0 0 90)
			(layer "F.Fab")
			(hide yes)
			(effects
				(font
					(size 1.27 1.27)
					(thickness 0.15)
				)
			)
		)
		(property "Description" "SMT Multilayer Ceramic Capacitor, 22uF, +/-20%, 25V, X5R, 0805 [2012 Metric]"
			(at 0 0 90)
			(layer "F.Fab")
			(hide yes)
			(effects
				(font
					(size 1.27 1.27)
					(thickness 0.15)
				)
			)
		)
		(property "MPN" "CL21A226MAYNNNE"
			(at 0 0 90)
			(unlocked yes)
			(layer "F.Fab")
			(hide yes)
			(effects
				(font
					(size 1 1)
					(thickness 0.15)
				)
			)
		)
		(property "Manufacturer" "Samsung Electro-Mechanics"
			(at 0 0 90)
			(unlocked yes)
			(layer "F.Fab")
			(hide yes)
			(effects
				(font
					(size 1 1)
					(thickness 0.15)
				)
			)
		)
		(property "License" "Apache-2.0"
			(at 0 0 90)
			(unlocked yes)
			(layer "F.Fab")
			(hide yes)
			(effects
				(font
					(size 1 1)
					(thickness 0.15)
				)
			)
		)
		(property "Author" "Antmicro"
			(at 0 0 90)
			(unlocked yes)
			(layer "F.Fab")
			(hide yes)
			(effects
				(font
					(size 1 1)
					(thickness 0.15)
				)
			)
		)
		(property "Val" "22u"
			(at 0 0 90)
			(unlocked yes)
			(layer "F.Fab")
			(hide yes)
			(effects
				(font
					(size 1 1)
					(thickness 0.15)
				)
			)
		)
		(property "Voltage" "25V"
			(at 0 0 90)
			(unlocked yes)
			(layer "F.Fab")
			(hide yes)
			(effects
				(font
					(size 1 1)
					(thickness 0.15)
				)
			)
		)
		(property "Dielectric" "X5R"
			(at 0 0 90)
			(unlocked yes)
			(layer "F.Fab")
			(hide yes)
			(effects
				(font
					(size 1 1)
					(thickness 0.15)
				)
			)
		)
		(property "Public" "False"
			(at 0 0 90)
			(unlocked yes)
			(layer "F.Fab")
			(hide yes)
			(effects
				(font
					(size 1 1)
					(thickness 0.15)
				)
			)
		)
		(component_classes
			(class "DCDC_SOM")
		)
		(sheetname "/DCDC/")
		(sheetfile "dcdc.kicad_sch")
		(attr smd)
		(fp_line
			(start -0.3 -0.7)
			(end 0.3 -0.7)
			(stroke
				(width 0.15)
				(type solid)
			)
			(layer "F.SilkS")
		)
		(fp_line
			(start -0.3 0.7)
			(end 0.3 0.7)
			(stroke
				(width 0.15)
				(type solid)
			)
			(layer "F.SilkS")
		)
		(fp_rect
			(start 1.95 -0.9)
			(end -1.95 0.9)
			(stroke
				(width 0.05)
				(type default)
			)
			(fill no)
			(layer "F.CrtYd")
		)
		(fp_rect
			(start -0.95 -0.675)
			(end 0.95 0.675)
			(stroke
				(width 0.15)
				(type solid)
			)
			(fill no)
			(layer "F.Fab")
		)
		(fp_text user "Author: Antmicro"
			(at -1.9 5.947 90)
			(layer "F.Fab")
			(effects
				(font
					(size 0.7 0.7)
					(thickness 0.15)
				)
				(justify left bottom)
			)
		)
		(fp_text user "License: Apache-2.0"
			(at -1.9 4.947 90)
			(layer "F.Fab")
			(effects
				(font
					(size 0.7 0.7)
					(thickness 0.15)
				)
				(justify left bottom)
			)
		)
		(fp_text user "${REFERENCE}"
			(at -1.9 3.947 90)
			(layer "F.Fab")
			(effects
				(font
					(size 0.7 0.7)
					(thickness 0.15)
				)
				(justify left bottom)
			)
		)
		(pad "1" smd roundrect
			(at -1.1 0 90)
			(size 1.2 1.3)
			(layers "F.Cu" "F.Mask" "F.Paste")
			(roundrect_rratio 0.25)
			(net 1 "GND")
			(pintype "passive")
		)
		(pad "2" smd roundrect
			(at 1.1 0 90)
			(size 1.2 1.3)
			(layers "F.Cu" "F.Mask" "F.Paste")
			(roundrect_rratio 0.25)
			(net 903 "/DCDC/16V_OUT")
			(pintype "passive")
		)
	)
	(footprint "antmicro-footprints:R_0402_1005Metric"
		(layer "F.Cu")
		(at 88 58.5)
		(descr "Resistor SMD 0402")
		(tags "resistor SMD 0402")
		(property "Reference" "R304"
			(at -19.15 9.55 0)
			(layer "F.SilkS")
			(effects
				(font
					(size 0.7 0.7)
					(thickness 0.15)
				)
				(justify left bottom)
			)
		)
		(property "Value" "R_10k_0402"
			(at -1.011843 1.772046 0)
			(layer "F.Fab")
			(effects
				(font
					(size 0.7 0.7)
					(thickness 0.15)
				)
				(justify left bottom)
			)
		)
		(property "Datasheet" "https://www.bourns.com/docs/product-datasheets/cr.pdf"
			(at 0 0 0)
			(layer "F.Fab")
			(hide yes)
			(effects
				(font
					(size 1.27 1.27)
					(thickness 0.15)
				)
			)
		)
		(property "Description" "SMD Chip Resistor, 10 kohm, ± 1%, 62.5 mW, 0402 [1005 Metric], Thick Film, General Purpose"
			(at 0 0 0)
			(layer "F.Fab")
			(hide yes)
			(effects
				(font
					(size 1.27 1.27)
					(thickness 0.15)
				)
			)
		)
		(property "MPN" "CR0402-FX-1002GLF"
			(at 0 0 0)
			(unlocked yes)
			(layer "F.Fab")
			(hide yes)
			(effects
				(font
					(size 1 1)
					(thickness 0.15)
				)
			)
		)
		(property "Manufacturer" "Bourns"
			(at 0 0 0)
			(unlocked yes)
			(layer "F.Fab")
			(hide yes)
			(effects
				(font
					(size 1 1)
					(thickness 0.15)
				)
			)
		)
		(property "License" "Apache-2.0"
			(at 0 0 0)
			(unlocked yes)
			(layer "F.Fab")
			(hide yes)
			(effects
				(font
					(size 1 1)
					(thickness 0.15)
				)
			)
		)
		(property "Author" "Antmicro"
			(at 0 0 0)
			(unlocked yes)
			(layer "F.Fab")
			(hide yes)
			(effects
				(font
					(size 1 1)
					(thickness 0.15)
				)
			)
		)
		(property "Val" "10k"
			(at 0 0 0)
			(unlocked yes)
			(layer "F.Fab")
			(hide yes)
			(effects
				(font
					(size 1 1)
					(thickness 0.15)
				)
			)
		)
		(property "Tolerance" "1%"
			(at 0 0 0)
			(unlocked yes)
			(layer "F.Fab")
			(hide yes)
			(effects
				(font
					(size 1 1)
					(thickness 0.15)
				)
			)
		)
		(sheetname "/SoM_Power/")
		(sheetfile "som_power.kicad_sch")
		(attr smd)
		(fp_poly
			(pts
				(xy -0.925 -0.47) (xy -0.925 0.47) (xy 0.925 0.47) (xy 0.925 -0.47)
			)
			(stroke
				(width 0.05)
				(type default)
			)
			(fill no)
			(layer "F.CrtYd")
		)
		(fp_poly
			(pts
				(xy -0.5 -0.25) (xy -0.5 0.25) (xy 0.5 0.25) (xy 0.5 -0.25)
			)
			(stroke
				(width 0.15)
				(type solid)
			)
			(fill no)
			(layer "F.Fab")
		)
		(fp_text user "Author: Antmicro"
			(at -0.95 4.169 0)
			(layer "F.Fab")
			(effects
				(font
					(size 0.7 0.7)
					(thickness 0.15)
				)
				(justify left bottom)
			)
		)
		(fp_text user "${REFERENCE}"
			(at -0.95 3.168 0)
			(layer "F.Fab")
			(effects
				(font
					(size 0.7 0.7)
					(thickness 0.15)
				)
				(justify left bottom)
			)
		)
		(fp_text user "License: Apache-2.0"
			(at -0.949999 5.169 0)
			(layer "F.Fab")
			(effects
				(font
					(size 0.7 0.7)
					(thickness 0.15)
				)
				(justify left bottom)
			)
		)
		(pad "1" smd roundrect
			(at -0.48 0)
			(size 0.59 0.64)
			(layers "F.Cu" "F.Mask" "F.Paste")
			(roundrect_rratio 0.25)
			(net 1382 "Net-(R300-Pad2)")
			(pintype "passive")
		)
		(pad "2" smd roundrect
			(at 0.48 0)
			(size 0.59 0.64)
			(layers "F.Cu" "F.Mask" "F.Paste")
			(roundrect_rratio 0.25)
			(net 4 "+3V3_AON")
			(pintype "passive")
		)
	)
	(footprint "antmicro-footprints:MLP44-24L_4x4x0.75mm"
		(layer "F.Cu")
		(at 179.7 90.45)
		(property "Reference" "U11"
			(at -2.675532 2.785 90)
			(layer "F.SilkS")
			(effects
				(font
					(size 0.7 0.7)
					(thickness 0.15)
				)
				(justify left bottom)
			)
		)
		(property "Value" "SIC437AED-T1-GE3"
			(at -2.7 3.6 0)
			(layer "F.Fab")
			(effects
				(font
					(size 0.7 0.7)
					(thickness 0.15)
				)
				(justify left bottom)
			)
		)
		(property "Datasheet" "https://www.vishay.com/docs/75921/sic437.pdf"
			(at 0 0 0)
			(layer "F.Fab")
			(hide yes)
			(effects
				(font
					(size 1.27 1.27)
					(thickness 0.15)
				)
			)
		)
		(property "Description" "DC/DC Buck Step Down Regulator Adjustable, 4.5-28V In, 0.6V to 20V/12A Out, 1MHz, PowerPAK MLP44-24"
			(at 0 0 0)
			(layer "F.Fab")
			(hide yes)
			(effects
				(font
					(size 1.27 1.27)
					(thickness 0.15)
				)
			)
		)
		(property "Manufacturer" "Vishay"
			(at 0 0 0)
			(unlocked yes)
			(layer "F.Fab")
			(hide yes)
			(effects
				(font
					(size 1 1)
					(thickness 0.15)
				)
			)
		)
		(property "MPN" "SIC437AED-T1-GE3"
			(at 0 0 0)
			(unlocked yes)
			(layer "F.Fab")
			(hide yes)
			(effects
				(font
					(size 1 1)
					(thickness 0.15)
				)
			)
		)
		(property "Author" "Antmicro"
			(at 0 0 0)
			(unlocked yes)
			(layer "F.Fab")
			(hide yes)
			(effects
				(font
					(size 1 1)
					(thickness 0.15)
				)
			)
		)
		(property "License" "Apache-2.0"
			(at 0 0 0)
			(unlocked yes)
			(layer "F.Fab")
			(hide yes)
			(effects
				(font
					(size 1 1)
					(thickness 0.15)
				)
			)
		)
		(component_classes
			(class "DCDC_SOM")
		)
		(sheetname "/DCDC/")
		(sheetfile "dcdc.kicad_sch")
		(attr smd)
		(net_tie_pad_groups "1,2,26" "3,4,27" "5,6,7,8,9")
		(fp_line
			(start -2.11 -1.38)
			(end -2.11 -2.1)
			(stroke
				(width 0.15)
				(type solid)
			)
			(layer "F.SilkS")
		)
		(fp_line
			(start -2.11 2.11)
			(end -2.11 1.39)
			(stroke
				(width 0.15)
				(type solid)
			)
			(layer "F.SilkS")
		)
		(fp_line
			(start -1.89 -2.1)
			(end -2.11 -2.1)
			(stroke
				(width 0.15)
				(type solid)
			)
			(layer "F.SilkS")
		)
		(fp_line
			(start -1.89 2.11)
			(end -2.11 2.11)
			(stroke
				(width 0.15)
				(type solid)
			)
			(layer "F.SilkS")
		)
		(fp_line
			(start 1.44 2.11)
			(end 2.11 2.11)
			(stroke
				(width 0.15)
				(type solid)
			)
			(layer "F.SilkS")
		)
		(fp_line
			(start 1.89 -2.11)
			(end 2.11 -2.11)
			(stroke
				(width 0.15)
				(type solid)
			)
			(layer "F.SilkS")
		)
		(fp_line
			(start 2.11 -2.11)
			(end 2.11 -1.69)
			(stroke
				(width 0.15)
				(type solid)
			)
			(layer "F.SilkS")
		)
		(fp_line
			(start 2.11 2.11)
			(end 2.11 1.84)
			(stroke
				(width 0.15)
				(type solid)
			)
			(layer "F.SilkS")
		)
		(fp_circle
			(center -2.25 -1.15)
			(end -2.2 -1.15)
			(stroke
				(width 0.15)
				(type solid)
			)
			(fill yes)
			(layer "F.SilkS")
		)
		(fp_line
			(start -2.55 -2.55)
			(end 2.55 -2.55)
			(stroke
				(width 0.05)
				(type solid)
			)
			(layer "F.CrtYd")
		)
		(fp_line
			(start -2.55 2.55)
			(end -2.55 -2.55)
			(stroke
				(width 0.05)
				(type solid)
			)
			(layer "F.CrtYd")
		)
		(fp_line
			(start 2.55 -2.55)
			(end 2.55 2.55)
			(stroke
				(width 0.05)
				(type solid)
			)
			(layer "F.CrtYd")
		)
		(fp_line
			(start 2.55 2.55)
			(end -2.55 2.55)
			(stroke
				(width 0.05)
				(type solid)
			)
			(layer "F.CrtYd")
		)
		(fp_line
			(start -2 -1)
			(end -2 2)
			(stroke
				(width 0.15)
				(type solid)
			)
			(layer "F.Fab")
		)
		(fp_line
			(start -2 2)
			(end 2 2)
			(stroke
				(width 0.15)
				(type solid)
			)
			(layer "F.Fab")
		)
		(fp_line
			(start -1 -2)
			(end -2 -1)
			(stroke
				(width 0.15)
				(type solid)
			)
			(layer "F.Fab")
		)
		(fp_line
			(start 2 -2)
			(end -1 -2)
			(stroke
				(width 0.15)
				(type solid)
			)
			(layer "F.Fab")
		)
		(fp_line
			(start 2 2)
			(end 2 -2)
			(stroke
				(width 0.15)
				(type solid)
			)
			(layer "F.Fab")
		)
		(fp_text user "License: Apache-2.0"
			(at -2.7 5.6 0)
			(layer "F.Fab")
			(effects
				(font
					(size 0.7 0.7)
					(thickness 0.15)
				)
				(justify left bottom)
			)
		)
		(fp_text user "Author: Antmicro"
			(at -2.7 8 0)
			(layer "F.Fab")
			(effects
				(font
					(size 0.7 0.7)
					(thickness 0.15)
				)
				(justify left bottom)
			)
		)
		(fp_text user "${REFERENCE}"
			(at -2.7 6.8 0)
			(layer "F.Fab")
			(effects
				(font
					(size 0.7 0.7)
					(thickness 0.15)
				)
				(justify left bottom)
			)
		)
		(pad "1" smd roundrect
			(at -1.94 -0.825 90)
			(size 0.3 0.725)
			(layers "F.Cu" "F.Mask" "F.Paste")
			(roundrect_rratio 0.25)
			(net 13 "VCC")
			(pinfunction "V_{IN}")
			(pintype "power_in")
		)
		(pad "2" smd roundrect
			(at -1.94 -0.375 90)
			(size 0.3 0.725)
			(layers "F.Cu" "F.Mask" "F.Paste")
			(roundrect_rratio 0.25)
			(net 13 "VCC")
			(pinfunction "V_{IN}")
			(pintype "passive")
		)
		(pad "3" smd roundrect
			(at -1.94 0.525 90)
			(size 0.3 0.725)
			(layers "F.Cu" "F.Mask" "F.Paste")
			(roundrect_rratio 0.25)
			(net 1 "GND")
			(pinfunction "P_{GND}")
			(pintype "passive")
		)
		(pad "4" smd roundrect
			(at -1.94 0.975 90)
			(size 0.3 0.725)
			(layers "F.Cu" "F.Mask" "F.Paste")
			(roundrect_rratio 0.25)
			(net 1 "GND")
			(pinfunction "P_{GND}")
			(pintype "passive")
		)
		(pad "5" smd custom
			(at -1.475 1.94)
			(size 0.3 0.3)
			(layers "F.Cu" "F.Mask" "F.Paste")
			(net 1183 "/DCDC/16V_SW")
			(pinfunction "SW")
			(pintype "passive")
			(options
				(clearance outline)
				(anchor circle)
			)
			(primitives
				(gr_poly
					(pts
						(xy -0.15 -0.2875) (xy -0.144291 -0.316201) (xy -0.128033 -0.340533) (xy -0.103701 -0.356791)
						(xy -0.075 -0.3625) (xy 0.075 -0.3625) (xy 0.103701 -0.356791) (xy 0.128033 -0.340533) (xy 0.144291 -0.316201)
						(xy 0.15 -0.2875) (xy 0.15 0.2875) (xy 0.144291 0.316201) (xy 0.128033 0.340533) (xy 0.103701 0.356791)
						(xy 0.075 0.3625) (xy -0.075 0.3625) (xy -0.103701 0.356791) (xy -0.128033 0.340533) (xy -0.144291 0.316201)
						(xy -0.15 0.2875)
					)
					(width 0)
					(fill yes)
				)
				(gr_poly
					(pts
						(xy -0.15 -0.3625) (xy 2.2 -0.3625) (xy 2.2 -0.0875) (xy -0.15 -0.0875)
					)
					(width 0)
					(fill yes)
				)
			)
		)
		(pad "6" smd roundrect
			(at -1.025 1.94)
			(size 0.3 0.725)
			(layers "F.Cu" "F.Mask" "F.Paste")
			(roundrect_rratio 0.25)
			(net 1183 "/DCDC/16V_SW")
			(pinfunction "SW")
			(pintype "passive")
		)
		(pad "7" smd roundrect
			(at -0.575 1.94)
			(size 0.3 0.725)
			(layers "F.Cu" "F.Mask" "F.Paste")
			(roundrect_rratio 0.25)
			(net 1183 "/DCDC/16V_SW")
			(pinfunction "SW")
			(pintype "passive")
		)
		(pad "8" smd roundrect
			(at 0.125 1.94)
			(size 0.3 0.725)
			(layers "F.Cu" "F.Mask" "F.Paste")
			(roundrect_rratio 0.25)
			(net 1183 "/DCDC/16V_SW")
			(pinfunction "SW")
			(pintype "passive")
		)
		(pad "9" smd roundrect
			(at 0.575 1.94)
			(size 0.3 0.725)
			(layers "F.Cu" "F.Mask" "F.Paste")
			(roundrect_rratio 0.25)
			(net 1183 "/DCDC/16V_SW")
			(pinfunction "SW")
			(pintype "passive")
		)
		(pad "10" smd roundrect
			(at 1.025 1.935)
			(size 0.3 0.725)
			(layers "F.Cu" "F.Mask" "F.Paste")
			(roundrect_rratio 0.25)
			(net 1189 "unconnected-(U11-GL-Pad10)_1")
			(pinfunction "GL")
			(pintype "passive+no_connect")
		)
		(pad "11" smd roundrect
			(at 1.94 1.425 90)
			(size 0.3 0.725)
			(layers "F.Cu" "F.Mask" "F.Paste")
			(roundrect_rratio 0.25)
			(net 1188 "unconnected-(U11-GL-Pad10)")
			(pinfunction "GL")
			(pintype "passive+no_connect")
		)
		(pad "12" smd roundrect
			(at 1.94 0.975 90)
			(size 0.3 0.725)
			(layers "F.Cu" "F.Mask" "F.Paste")
			(roundrect_rratio 0.25)
			(net 900 "/DCDC/16V_VDRV")
			(pinfunction "V_{DRV}")
			(pintype "passive")
		)
		(pad "13" smd roundrect
			(at 1.94 0.525 90)
			(size 0.3 0.725)
			(layers "F.Cu" "F.Mask" "F.Paste")
			(roundrect_rratio 0.25)
			(net 1 "GND")
			(pinfunction "P_{GND}")
			(pintype "power_in")
		)
		(pad "14" smd roundrect
			(at 1.94 0.075 90)
			(size 0.3 0.725)
			(layers "F.Cu" "F.Mask" "F.Paste")
			(roundrect_rratio 0.25)
			(net 246 "/SoM_Power/~{VDDIN_PWR_BAD}")
			(pinfunction "P_{GOOD}")
			(pintype "output")
		)
		(pad "15" smd roundrect
			(at 1.94 -0.375 90)
			(size 0.3 0.725)
			(layers "F.Cu" "F.Mask" "F.Paste")
			(roundrect_rratio 0.25)
			(net 896 "/DCDC/16V_VDD")
			(pinfunction "V_{DD}")
			(pintype "passive")
		)
		(pad "16" smd roundrect
			(at 1.94 -0.825 90)
			(size 0.3 0.725)
			(layers "F.Cu" "F.Mask" "F.Paste")
			(roundrect_rratio 0.25)
			(net 1 "GND")
			(pinfunction "A_{GND}")
			(pintype "power_in")
		)
		(pad "17" smd roundrect
			(at 1.94 -1.275 90)
			(size 0.3 0.725)
			(layers "F.Cu" "F.Mask" "F.Paste")
			(roundrect_rratio 0.25)
			(net 1219 "/DCDC/16V_FB")
			(pinfunction "FB")
			(pintype "passive")
		)
		(pad "18" smd roundrect
			(at 1.475 -1.94)
			(size 0.3 0.725)
			(layers "F.Cu" "F.Mask" "F.Paste")
			(roundrect_rratio 0.25)
			(net 903 "/DCDC/16V_OUT")
			(pinfunction "V_{OUT}")
			(pintype "passive")
		)
		(pad "19" smd roundrect
			(at 1.025 -1.94)
			(size 0.3 0.725)
			(layers "F.Cu" "F.Mask" "F.Paste")
			(roundrect_rratio 0.25)
			(net 1285 "/SoM_Power/VIN_PWR_ON")
			(pinfunction "EN")
			(pintype "input")
		)
		(pad "20" smd roundrect
			(at 0.575 -1.94)
			(size 0.3 0.725)
			(layers "F.Cu" "F.Mask" "F.Paste")
			(roundrect_rratio 0.25)
			(net 1214 "/DCDC/16V_MODE2")
			(pinfunction "MODE2")
			(pintype "input")
		)
		(pad "21" smd roundrect
			(at 0.125 -1.94)
			(size 0.3 0.725)
			(layers "F.Cu" "F.Mask" "F.Paste")
			(roundrect_rratio 0.25)
			(net 1207 "/DCDC/16V_MODE1")
			(pinfunction "MODE1")
			(pintype "input")
		)
		(pad "22" smd roundrect
			(at -0.575 -1.94)
			(size 0.3 0.725)
			(layers "F.Cu" "F.Mask" "F.Paste")
			(roundrect_rratio 0.25)
			(net 13 "VCC")
			(pinfunction "V_{IN}")
			(pintype "passive")
		)
		(pad "23" smd roundrect
			(at -1.025 -1.94)
			(size 0.3 0.725)
			(layers "F.Cu" "F.Mask" "F.Paste")
			(roundrect_rratio 0.25)
			(net 901 "/DCDC/16V_BOOT")
			(pinfunction "BOOT")
			(pintype "passive")
		)
		(pad "24" smd roundrect
			(at -1.475 -1.94)
			(size 0.3 0.725)
			(layers "F.Cu" "F.Mask" "F.Paste")
			(roundrect_rratio 0.25)
			(net 902 "/DCDC/16V_PHASE")
			(pinfunction "PHASE")
			(pintype "passive")
		)
		(pad "25" smd rect
			(at 0.49 -0.75 180)
			(size 1.575 1.05)
			(layers "F.Cu" "F.Mask" "F.Paste")
			(net 1 "GND")
			(pinfunction "A_{GND}")
			(pintype "passive")
		)
		(pad "26" smd rect
			(at -1.175 -0.75 180)
			(size 1.15 1.05)
			(layers "F.Cu" "F.Mask" "F.Paste")
			(net 13 "VCC")
			(pinfunction "V_{IN}")
			(pintype "passive")
		)
		(pad "27" smd custom
			(at -0.75 0.775)
			(size 1 1)
			(layers "F.Cu" "F.Mask" "F.Paste")
			(net 1 "GND")
			(pinfunction "P_{GND}")
			(pintype "passive")
			(options
				(clearance outline)
				(anchor rect)
			)
			(primitives
				(gr_poly
					(pts
						(xy -1 0.5) (xy -1 -0.7) (xy 1.825 -0.7) (xy 1.825 -0.245) (xy 1.175 -0.245) (xy 1.175 0.5)
					)
					(width 0)
					(fill yes)
				)
			)
		)
		(pad "28" smd rect
			(at 0.985 0.99 180)
			(size 0.58 0.38)
			(layers "F.Cu" "F.Mask" "F.Paste")
			(net 1190 "unconnected-(U11-GL-Pad10)_2")
			(pinfunction "GL")
			(pintype "passive+no_connect")
		)
	)
	(footprint "antmicro-footprints:SOT-23-6"
		(layer "F.Cu")
		(at 91 59.5 90)
		(property "Reference" "U70"
			(at 2.45 1.05 0)
			(layer "F.SilkS")
			(effects
				(font
					(size 0.7 0.7)
					(thickness 0.15)
				)
				(justify right top)
			)
		)
		(property "Value" "MAX16150A_SOT"
			(at -1.75 2.693 90)
			(layer "F.Fab")
			(effects
				(font
					(size 0.7 0.7)
					(thickness 0.15)
				)
				(justify left bottom)
			)
		)
		(property "Datasheet" "https://datasheets.maximintegrated.com/en/ds/MAX16150.pdf"
			(at 0 -0.057 90)
			(layer "F.Fab")
			(hide yes)
			(effects
				(font
					(size 1.27 1.27)
					(thickness 0.15)
				)
			)
		)
		(property "Description" "Pushbutton On/Off Controller, Latched Output, 1.3 to 5.5 V Supply, 50 ms Debounce Time, SOT-23-6"
			(at 0 -0.057 90)
			(layer "F.Fab")
			(hide yes)
			(effects
				(font
					(size 1.27 1.27)
					(thickness 0.15)
				)
			)
		)
		(property "Manufacturer" "Maxim Integrated Products"
			(at 0 0 90)
			(unlocked yes)
			(layer "F.Fab")
			(hide yes)
			(effects
				(font
					(size 1 1)
					(thickness 0.15)
				)
			)
		)
		(property "MPN" "MAX16150AUT+T"
			(at 0 0 90)
			(unlocked yes)
			(layer "F.Fab")
			(hide yes)
			(effects
				(font
					(size 1 1)
					(thickness 0.15)
				)
			)
		)
		(property "License" "Apache-2.0"
			(at 0 0 90)
			(unlocked yes)
			(layer "F.Fab")
			(hide yes)
			(effects
				(font
					(size 1 1)
					(thickness 0.15)
				)
			)
		)
		(property "Author" "Antmicro"
			(at 0 0 90)
			(unlocked yes)
			(layer "F.Fab")
			(hide yes)
			(effects
				(font
					(size 1 1)
					(thickness 0.15)
				)
			)
		)
		(sheetname "/SoM_Power/")
		(sheetfile "som_power.kicad_sch")
		(attr smd)
		(fp_line
			(start 1.45 -0.757)
			(end 1.45 -0.457)
			(stroke
				(width 0.12)
				(type solid)
			)
			(layer "F.SilkS")
		)
		(fp_line
			(start 1.3 -0.757)
			(end 1.45 -0.757)
			(stroke
				(width 0.12)
				(type solid)
			)
			(layer "F.SilkS")
		)
		(fp_line
			(start -1.3 -0.757)
			(end -1.45 -0.757)
			(stroke
				(width 0.12)
				(type solid)
			)
			(layer "F.SilkS")
		)
		(fp_line
			(start -1.45 -0.757)
			(end -1.45 -0.457)
			(stroke
				(width 0.12)
				(type solid)
			)
			(layer "F.SilkS")
		)
		(fp_line
			(start 1.45 0.643)
			(end 1.45 0.343)
			(stroke
				(width 0.12)
				(type solid)
			)
			(layer "F.SilkS")
		)
		(fp_line
			(start 1.3 0.643)
			(end 1.45 0.643)
			(stroke
				(width 0.12)
				(type solid)
			)
			(layer "F.SilkS")
		)
		(fp_line
			(start -1.45 0.643)
			(end -1.45 0.343)
			(stroke
				(width 0.12)
				(type solid)
			)
			(layer "F.SilkS")
		)
		(fp_rect
			(start -1.55 -1.85)
			(end 1.55 1.75)
			(stroke
				(width 0.05)
				(type solid)
			)
			(fill no)
			(layer "F.CrtYd")
		)
		(fp_line
			(start 1.5 -0.757)
			(end 1.5 0.643)
			(stroke
				(width 0.1)
				(type solid)
			)
			(layer "F.Fab")
		)
		(fp_line
			(start -1.5 -0.757)
			(end 1.5 -0.757)
			(stroke
				(width 0.1)
				(type solid)
			)
			(layer "F.Fab")
		)
		(fp_line
			(start 1.5 0.643)
			(end -1.5 0.643)
			(stroke
				(width 0.1)
				(type solid)
			)
			(layer "F.Fab")
		)
		(fp_line
			(start -1.5 0.643)
			(end -1.5 -0.757)
			(stroke
				(width 0.1)
				(type solid)
			)
			(layer "F.Fab")
		)
		(fp_text user "."
			(at -1.4 1.143 90)
			(layer "F.SilkS")
			(effects
				(font
					(size 1 1)
					(thickness 0.15)
				)
			)
		)
		(fp_text user "License: Apache-2.0"
			(at -1.75 6.5 90)
			(layer "F.Fab")
			(effects
				(font
					(size 0.7 0.7)
					(thickness 0.15)
				)
				(justify left bottom)
			)
		)
		(fp_text user "Author: Antmicro"
			(at -1.829 5.25 90)
			(layer "F.Fab")
			(effects
				(font
					(size 0.7 0.7)
					(thickness 0.15)
				)
				(justify left bottom)
			)
		)
		(fp_text user "${REFERENCE}"
			(at -1.75 4 90)
			(layer "F.Fab")
			(effects
				(font
					(size 0.7 0.7)
					(thickness 0.15)
				)
				(justify left bottom)
			)
		)
		(pad "1" smd roundrect
			(at -0.954 1.1 90)
			(size 0.55 1)
			(layers "F.Cu" "F.Mask" "F.Paste")
			(roundrect_rratio 0.15)
			(net 610 "/SoM_Power/~{PWR_BTN}")
			(pinfunction "~{PB_IN}")
			(pintype "input")
		)
		(pad "2" smd roundrect
			(at -0.003 1.1 90)
			(size 0.55 1)
			(layers "F.Cu" "F.Mask" "F.Paste")
			(roundrect_rratio 0.15)
			(net 1 "GND")
			(pinfunction "GND")
			(pintype "power_in")
		)
		(pad "3" smd roundrect
			(at 0.947 1.1 90)
			(size 0.55 1)
			(layers "F.Cu" "F.Mask" "F.Paste")
			(roundrect_rratio 0.15)
			(net 491 "+5V_AON")
			(pinfunction "VCC")
			(pintype "power_in")
		)
		(pad "4" smd roundrect
			(at 0.947 -1.214 90)
			(size 0.55 1)
			(layers "F.Cu" "F.Mask" "F.Paste")
			(roundrect_rratio 0.15)
			(net 1033 "Net-(U70-OUT)")
			(pinfunction "OUT")
			(pintype "output")
		)
		(pad "5" smd roundrect
			(at -0.003 -1.214 90)
			(size 0.55 1)
			(layers "F.Cu" "F.Mask" "F.Paste")
			(roundrect_rratio 0.15)
			(net 1035 "Net-(U70-~{INT})")
			(pinfunction "~{INT}")
			(pintype "output")
		)
		(pad "6" smd roundrect
			(at -0.954 -1.214 90)
			(size 0.55 1)
			(layers "F.Cu" "F.Mask" "F.Paste")
			(roundrect_rratio 0.15)
			(net 1027 "Net-(U70-~{CLR})")
			(pinfunction "~{CLR}")
			(pintype "input")
		)
	)
	(footprint "antmicro-footprints:R_0402_1005Metric"
		(layer "F.Cu")
		(at 87.95 64.5 180)
		(descr "Resistor SMD 0402")
		(tags "resistor SMD 0402")
		(property "Reference" "R300"
			(at 16.3 -8.65 0)
			(layer "F.SilkS")
			(effects
				(font
					(size 0.7 0.7)
					(thickness 0.15)
				)
				(justify right top)
			)
		)
		(property "Value" "R_10k_0402"
			(at -1.011843 1.772046 0)
			(layer "F.Fab")
			(effects
				(font
					(size 0.7 0.7)
					(thickness 0.15)
				)
				(justify right top)
			)
		)
		(property "Datasheet" "https://www.bourns.com/docs/product-datasheets/cr.pdf"
			(at 0 0 0)
			(layer "F.Fab")
			(hide yes)
			(effects
				(font
					(size 1.27 1.27)
					(thickness 0.15)
				)
			)
		)
		(property "Description" "SMD Chip Resistor, 10 kohm, ± 1%, 62.5 mW, 0402 [1005 Metric], Thick Film, General Purpose"
			(at 0 0 0)
			(layer "F.Fab")
			(hide yes)
			(effects
				(font
					(size 1.27 1.27)
					(thickness 0.15)
				)
			)
		)
		(property "MPN" "CR0402-FX-1002GLF"
			(at 0 0 180)
			(unlocked yes)
			(layer "F.Fab")
			(hide yes)
			(effects
				(font
					(size 1 1)
					(thickness 0.15)
				)
			)
		)
		(property "Manufacturer" "Bourns"
			(at 0 0 180)
			(unlocked yes)
			(layer "F.Fab")
			(hide yes)
			(effects
				(font
					(size 1 1)
					(thickness 0.15)
				)
			)
		)
		(property "License" "Apache-2.0"
			(at 0 0 180)
			(unlocked yes)
			(layer "F.Fab")
			(hide yes)
			(effects
				(font
					(size 1 1)
					(thickness 0.15)
				)
			)
		)
		(property "Author" "Antmicro"
			(at 0 0 180)
			(unlocked yes)
			(layer "F.Fab")
			(hide yes)
			(effects
				(font
					(size 1 1)
					(thickness 0.15)
				)
			)
		)
		(property "Val" "10k"
			(at 0 0 180)
			(unlocked yes)
			(layer "F.Fab")
			(hide yes)
			(effects
				(font
					(size 1 1)
					(thickness 0.15)
				)
			)
		)
		(property "Tolerance" "1%"
			(at 0 0 180)
			(unlocked yes)
			(layer "F.Fab")
			(hide yes)
			(effects
				(font
					(size 1 1)
					(thickness 0.15)
				)
			)
		)
		(sheetname "/SoM_Power/")
		(sheetfile "som_power.kicad_sch")
		(attr smd)
		(fp_poly
			(pts
				(xy -0.925 -0.47) (xy -0.925 0.47) (xy 0.925 0.47) (xy 0.925 -0.47)
			)
			(stroke
				(width 0.05)
				(type default)
			)
			(fill no)
			(layer "F.CrtYd")
		)
		(fp_poly
			(pts
				(xy -0.5 -0.25) (xy -0.5 0.25) (xy 0.5 0.25) (xy 0.5 -0.25)
			)
			(stroke
				(width 0.15)
				(type solid)
			)
			(fill no)
			(layer "F.Fab")
		)
		(fp_text user "License: Apache-2.0"
			(at -0.949999 5.169 0)
			(layer "F.Fab")
			(effects
				(font
					(size 0.7 0.7)
					(thickness 0.15)
				)
				(justify right top)
			)
		)
		(fp_text user "${REFERENCE}"
			(at -0.95 3.168 0)
			(layer "F.Fab")
			(effects
				(font
					(size 0.7 0.7)
					(thickness 0.15)
				)
				(justify right top)
			)
		)
		(fp_text user "Author: Antmicro"
			(at -0.95 4.169 0)
			(layer "F.Fab")
			(effects
				(font
					(size 0.7 0.7)
					(thickness 0.15)
				)
				(justify right top)
			)
		)
		(pad "1" smd roundrect
			(at -0.48 0 180)
			(size 0.59 0.64)
			(layers "F.Cu" "F.Mask" "F.Paste")
			(roundrect_rratio 0.25)
			(net 1032 "/SoM_Power/~{FORCE_SHDN}")
			(pintype "passive")
		)
		(pad "2" smd roundrect
			(at 0.48 0 180)
			(size 0.59 0.64)
			(layers "F.Cu" "F.Mask" "F.Paste")
			(roundrect_rratio 0.25)
			(net 1382 "Net-(R300-Pad2)")
			(pintype "passive")
		)
	)
	(footprint "antmicro-footprints:C_0402_1005Metric"
		(layer "F.Cu")
		(at 89.12 91.4)
		(descr "Capacitor SMD 0402")
		(tags "capacitor SMD 0402")
		(property "Reference" "C334"
			(at -3.82 0.45 0)
			(layer "F.SilkS")
			(effects
				(font
					(size 0.7 0.7)
					(thickness 0.15)
				)
				(justify left bottom)
			)
		)
		(property "Value" "C_100n_0402"
			(at -1.022927 2.155213 0)
			(layer "F.Fab")
			(effects
				(font
					(size 0.7 0.7)
					(thickness 0.15)
				)
				(justify left bottom)
			)
		)
		(property "Datasheet" "https://www.murata.com/products/productdetail?partno=GRM155R61H104KE14%23"
			(at 0 0 0)
			(layer "F.Fab")
			(hide yes)
			(effects
				(font
					(size 1.27 1.27)
					(thickness 0.15)
				)
			)
		)
		(property "Description" "SMD Multilayer Ceramic Capacitor, 0.1 µF, 50 V, 0402 [1005 Metric], ± 10%, X5R, GRM Series"
			(at 0 0 0)
			(layer "F.Fab")
			(hide yes)
			(effects
				(font
					(size 1.27 1.27)
					(thickness 0.15)
				)
			)
		)
		(property "Manufacturer" "Murata"
			(at 0 0 0)
			(unlocked yes)
			(layer "F.Fab")
			(hide yes)
			(effects
				(font
					(size 1 1)
					(thickness 0.15)
				)
			)
		)
		(property "MPN" "GRM155R61H104KE14D"
			(at 0 0 0)
			(unlocked yes)
			(layer "F.Fab")
			(hide yes)
			(effects
				(font
					(size 1 1)
					(thickness 0.15)
				)
			)
		)
		(property "Val" "100n"
			(at 0 0 0)
			(unlocked yes)
			(layer "F.Fab")
			(hide yes)
			(effects
				(font
					(size 1 1)
					(thickness 0.15)
				)
			)
		)
		(property "License" "Apache-2.0"
			(at 0 0 0)
			(unlocked yes)
			(layer "F.Fab")
			(hide yes)
			(effects
				(font
					(size 1 1)
					(thickness 0.15)
				)
			)
		)
		(property "Author" "Antmicro"
			(at 0 0 0)
			(unlocked yes)
			(layer "F.Fab")
			(hide yes)
			(effects
				(font
					(size 1 1)
					(thickness 0.15)
				)
			)
		)
		(property "Voltage" "50V"
			(at 0 0 0)
			(unlocked yes)
			(layer "F.Fab")
			(hide yes)
			(effects
				(font
					(size 1 1)
					(thickness 0.15)
				)
			)
		)
		(property "Dielectric" "X5R"
			(at 0 0 0)
			(unlocked yes)
			(layer "F.Fab")
			(hide yes)
			(effects
				(font
					(size 1 1)
					(thickness 0.15)
				)
			)
		)
		(sheetname "/SoM_IO2/")
		(sheetfile "som_io2.kicad_sch")
		(attr smd)
		(fp_rect
			(start -0.925 -0.47)
			(end 0.925 0.47)
			(stroke
				(width 0.05)
				(type default)
			)
			(fill no)
			(layer "F.CrtYd")
		)
		(fp_line
			(start -0.494 -0.25)
			(end 0.504 -0.25)
			(stroke
				(width 0.15)
				(type solid)
			)
			(layer "F.Fab")
		)
		(fp_line
			(start -0.494 0.248)
			(end -0.494 -0.25)
			(stroke
				(width 0.15)
				(type solid)
			)
			(layer "F.Fab")
		)
		(fp_line
			(start 0.504 -0.25)
			(end 0.504 0.248)
			(stroke
				(width 0.15)
				(type solid)
			)
			(layer "F.Fab")
		)
		(fp_line
			(start 0.504 0.248)
			(end -0.494 0.248)
			(stroke
				(width 0.15)
				(type solid)
			)
			(layer "F.Fab")
		)
		(fp_text user "${REFERENCE}"
			(at -0.939 4.599 0)
			(layer "F.Fab")
			(effects
				(font
					(size 0.7 0.7)
					(thickness 0.15)
				)
				(justify left bottom)
			)
		)
		(fp_text user "Author: Antmicro"
			(at -0.939 3.399 0)
			(layer "F.Fab")
			(effects
				(font
					(size 0.7 0.7)
					(thickness 0.15)
				)
				(justify left bottom)
			)
		)
		(fp_text user "License: Apache-2.0"
			(at -0.939 5.799 0)
			(layer "F.Fab")
			(effects
				(font
					(size 0.7 0.7)
					(thickness 0.15)
				)
				(justify left bottom)
			)
		)
		(pad "1" smd roundrect
			(at -0.48 0)
			(size 0.59 0.64)
			(layers "F.Cu" "F.Mask" "F.Paste")
			(roundrect_rratio 0.25)
			(net 591 "/Expansion connector/DP2.TX0+")
			(pintype "passive")
		)
		(pad "2" smd roundrect
			(at 0.48 0)
			(size 0.59 0.64)
			(layers "F.Cu" "F.Mask" "F.Paste")
			(roundrect_rratio 0.25)
			(net 1254 "/SoM_IO2/DP2.TX0_C+")
			(pintype "passive")
		)
	)
	(footprint "antmicro-footprints:R_0402_1005Metric"
		(layer "F.Cu")
		(at 179.4 106.95 180)
		(descr "Resistor SMD 0402")
		(tags "resistor SMD 0402")
		(property "Reference" "R36"
			(at -0.9 1.45 0)
			(layer "F.SilkS")
			(effects
				(font
					(size 0.7 0.7)
					(thickness 0.15)
				)
				(justify right top)
			)
		)
		(property "Value" "R_499k_0402"
			(at -1.011843 1.772047 0)
			(layer "F.Fab")
			(effects
				(font
					(size 0.7 0.7)
					(thickness 0.15)
				)
				(justify right top)
			)
		)
		(property "Datasheet" "https://www.mouser.com/datasheet/2/54/cr-1858361.pdf"
			(at 0 0 0)
			(layer "F.Fab")
			(hide yes)
			(effects
				(font
					(size 1.27 1.27)
					(thickness 0.15)
				)
			)
		)
		(property "Description" "SMD Chip Resistor, 499 kohm, ± 1%, 63 mW, 0402 [1005 Metric], Thick Film, General Purpose"
			(at 0 0 0)
			(layer "F.Fab")
			(hide yes)
			(effects
				(font
					(size 1.27 1.27)
					(thickness 0.15)
				)
			)
		)
		(property "MPN" "CR0402-FX-4993GLF"
			(at 0 0 180)
			(unlocked yes)
			(layer "F.Fab")
			(hide yes)
			(effects
				(font
					(size 1 1)
					(thickness 0.15)
				)
			)
		)
		(property "Manufacturer" "Bourns"
			(at 0 0 180)
			(unlocked yes)
			(layer "F.Fab")
			(hide yes)
			(effects
				(font
					(size 1 1)
					(thickness 0.15)
				)
			)
		)
		(property "License" "Apache-2.0"
			(at 0 0 180)
			(unlocked yes)
			(layer "F.Fab")
			(hide yes)
			(effects
				(font
					(size 1 1)
					(thickness 0.15)
				)
			)
		)
		(property "Author" "Antmicro"
			(at 0 0 180)
			(unlocked yes)
			(layer "F.Fab")
			(hide yes)
			(effects
				(font
					(size 1 1)
					(thickness 0.15)
				)
			)
		)
		(property "Val" "499k"
			(at 0 0 180)
			(unlocked yes)
			(layer "F.Fab")
			(hide yes)
			(effects
				(font
					(size 1 1)
					(thickness 0.15)
				)
			)
		)
		(property "Tolerance" "1%"
			(at 0 0 180)
			(unlocked yes)
			(layer "F.Fab")
			(hide yes)
			(effects
				(font
					(size 1 1)
					(thickness 0.15)
				)
			)
		)
		(sheetname "/DCDC/")
		(sheetfile "dcdc.kicad_sch")
		(attr smd exclude_from_pos_files exclude_from_bom dnp)
		(fp_rect
			(start -0.925 -0.47)
			(end 0.925 0.47)
			(stroke
				(width 0.05)
				(type default)
			)
			(fill no)
			(layer "F.CrtYd")
		)
		(fp_rect
			(start -0.5 -0.25)
			(end 0.5 0.25)
			(stroke
				(width 0.15)
				(type solid)
			)
			(fill no)
			(layer "F.Fab")
		)
		(fp_text user "Author: Antmicro"
			(at -0.95 4.169 0)
			(layer "F.Fab")
			(effects
				(font
					(size 0.7 0.7)
					(thickness 0.15)
				)
				(justify right top)
			)
		)
		(fp_text user "${REFERENCE}"
			(at -0.95 3.168 0)
			(layer "F.Fab")
			(effects
				(font
					(size 0.7 0.7)
					(thickness 0.15)
				)
				(justify right top)
			)
		)
		(fp_text user "License: Apache-2.0"
			(at -0.95 5.169 0)
			(layer "F.Fab")
			(effects
				(font
					(size 0.7 0.7)
					(thickness 0.15)
				)
				(justify right top)
			)
		)
		(pad "1" smd roundrect
			(at -0.48 0 180)
			(size 0.59 0.64)
			(layers "F.Cu" "F.Mask" "F.Paste")
			(roundrect_rratio 0.25)
			(net 1212 "/DCDC/5V_MODE1")
			(pintype "passive")
		)
		(pad "2" smd roundrect
			(at 0.48 0 180)
			(size 0.59 0.64)
			(layers "F.Cu" "F.Mask" "F.Paste")
			(roundrect_rratio 0.25)
			(net 18 "/DCDC/5V_VDD")
			(pintype "passive")
		)
	)
	(footprint "antmicro-footprints:SOD-523"
		(layer "F.Cu")
		(at 198.3 95.1)
		(property "Reference" "D16"
			(at -3.111 0.33 0)
			(layer "F.SilkS")
			(effects
				(font
					(size 0.7 0.7)
					(thickness 0.15)
				)
				(justify left bottom)
			)
		)
		(property "Value" "RB521S30T1G"
			(at 0 1.499 0)
			(layer "F.Fab")
			(effects
				(font
					(size 0.7 0.7)
					(thickness 0.15)
				)
				(justify left bottom)
			)
		)
		(property "Datasheet" "https://www.onsemi.com/pdf/datasheet/rb521s30t1-d.pdf"
			(at 0 0 0)
			(layer "F.Fab")
			(hide yes)
			(effects
				(font
					(size 1.27 1.27)
					(thickness 0.15)
				)
			)
		)
		(property "Description" "Small Signal Schottky Diode, Single, 30 V, 200 mA, 500 mV, 1 A, 125 °C"
			(at 0 0 0)
			(layer "F.Fab")
			(hide yes)
			(effects
				(font
					(size 1.27 1.27)
					(thickness 0.15)
				)
			)
		)
		(property "MPN" "RB521S30T1G"
			(at 0 0 0)
			(unlocked yes)
			(layer "F.Fab")
			(hide yes)
			(effects
				(font
					(size 1 1)
					(thickness 0.15)
				)
			)
		)
		(property "Manufacturer" "ON Semiconductor"
			(at 0 0 0)
			(unlocked yes)
			(layer "F.Fab")
			(hide yes)
			(effects
				(font
					(size 1 1)
					(thickness 0.15)
				)
			)
		)
		(property "Author" "Antmicro"
			(at 0 0 0)
			(unlocked yes)
			(layer "F.Fab")
			(hide yes)
			(effects
				(font
					(size 1 1)
					(thickness 0.15)
				)
			)
		)
		(property "License" "Apache-2.0"
			(at 0 0 0)
			(unlocked yes)
			(layer "F.Fab")
			(hide yes)
			(effects
				(font
					(size 1 1)
					(thickness 0.15)
				)
			)
		)
		(sheetname "/USB Debug, PD/")
		(sheetfile "usb_debug_pd.kicad_sch")
		(attr smd)
		(fp_line
			(start -0.35 -0.5)
			(end -0.35 0.5)
			(stroke
				(width 0.15)
				(type solid)
			)
			(layer "F.SilkS")
		)
		(fp_poly
			(pts
				(xy -1 -0.6) (xy 1 -0.6) (xy 1 0.6) (xy -1 0.6)
			)
			(stroke
				(width 0.05)
				(type solid)
			)
			(fill no)
			(layer "F.CrtYd")
		)
		(fp_line
			(start -0.652 -0.425)
			(end 0.65 -0.425)
			(stroke
				(width 0.15)
				(type solid)
			)
			(layer "F.Fab")
		)
		(fp_line
			(start -0.652 0.423)
			(end -0.652 -0.425)
			(stroke
				(width 0.15)
				(type solid)
			)
			(layer "F.Fab")
		)
		(fp_line
			(start -0.652 0.423)
			(end 0.65 0.423)
			(stroke
				(width 0.15)
				(type solid)
			)
			(layer "F.Fab")
		)
		(fp_line
			(start -0.35 -0.4)
			(end -0.35 0.4)
			(stroke
				(width 0.15)
				(type solid)
			)
			(layer "F.Fab")
		)
		(fp_line
			(start 0.65 -0.425)
			(end 0.65 0.423)
			(stroke
				(width 0.15)
				(type solid)
			)
			(layer "F.Fab")
		)
		(fp_text user "Author: Antmicro"
			(at -1.276 4.7 0)
			(layer "F.Fab")
			(effects
				(font
					(size 0.7 0.7)
					(thickness 0.15)
				)
				(justify left bottom)
			)
		)
		(fp_text user "License: Apache-2.0"
			(at -1.276 5.9 0)
			(layer "F.Fab")
			(effects
				(font
					(size 0.7 0.7)
					(thickness 0.15)
				)
				(justify left bottom)
			)
		)
		(fp_text user "${REFERENCE}"
			(at -1.276 3.499 0)
			(layer "F.Fab")
			(effects
				(font
					(size 0.7 0.7)
					(thickness 0.15)
				)
				(justify left bottom)
			)
		)
		(pad "1" smd roundrect
			(at -0.701 0)
			(size 0.5 0.6)
			(layers "F.Cu" "F.Mask" "F.Paste")
			(roundrect_rratio 0.25)
			(net 532 "/USB Debug, PD/SCK")
			(pinfunction "C")
			(pintype "passive")
		)
		(pad "2" smd roundrect
			(at 0.699001 0)
			(size 0.5 0.6)
			(layers "F.Cu" "F.Mask" "F.Paste")
			(roundrect_rratio 0.25)
			(net 531 "Net-(D16-A)")
			(pinfunction "A")
			(pintype "passive")
		)
	)
	(footprint "antmicro-footprints:LED_0603_1608Metric_G"
		(layer "F.Cu")
		(at 172.1 63.2 -90)
		(descr "LED SMD 0603 Green")
		(tags "LED SMD 0603 Green")
		(property "Reference" "D36"
			(at -0.89 -1.72 90)
			(layer "F.SilkS")
			(effects
				(font
					(size 0.7 0.7)
					(thickness 0.15)
				)
				(justify right top)
			)
		)
		(property "Value" "LED_G_0603_LTST-C190GKT"
			(at -0.001 1.599 90)
			(layer "F.Fab")
			(effects
				(font
					(size 0.7 0.7)
					(thickness 0.15)
				)
				(justify right top)
			)
		)
		(property "Datasheet" "https://media.digikey.com/pdf/Data%20Sheets/Lite-On%20PDFs/LTST-C190GKT.pdf"
			(at 0 0 90)
			(layer "F.Fab")
			(hide yes)
			(effects
				(font
					(size 1.27 1.27)
					(thickness 0.15)
				)
			)
		)
		(property "Description" "LED, Green, SMD, 0603, 20 mA, 2.1 V, 569 nm"
			(at 0 0 90)
			(layer "F.Fab")
			(hide yes)
			(effects
				(font
					(size 1.27 1.27)
					(thickness 0.15)
				)
			)
		)
		(property "MPN" "LTST-C190GKT"
			(at 0 0 270)
			(unlocked yes)
			(layer "F.Fab")
			(hide yes)
			(effects
				(font
					(size 1 1)
					(thickness 0.15)
				)
			)
		)
		(property "Manufacturer" "Lite-On"
			(at 0 0 270)
			(unlocked yes)
			(layer "F.Fab")
			(hide yes)
			(effects
				(font
					(size 1 1)
					(thickness 0.15)
				)
			)
		)
		(property "Author" "Antmicro"
			(at 0 0 270)
			(unlocked yes)
			(layer "F.Fab")
			(hide yes)
			(effects
				(font
					(size 1 1)
					(thickness 0.15)
				)
			)
		)
		(property "License" "Apache-2.0"
			(at 0 0 270)
			(unlocked yes)
			(layer "F.Fab")
			(hide yes)
			(effects
				(font
					(size 1 1)
					(thickness 0.15)
				)
			)
		)
		(property "Color" "Green"
			(at 0 0 270)
			(unlocked yes)
			(layer "F.Fab")
			(hide yes)
			(effects
				(font
					(size 1 1)
					(thickness 0.15)
				)
			)
		)
		(sheetname "/Peripherals/")
		(sheetfile "peripherals.kicad_sch")
		(attr smd)
		(fp_line
			(start 0.22 0.35)
			(end -0.22 0.35)
			(stroke
				(width 0.15)
				(type solid)
			)
			(layer "F.SilkS")
		)
		(fp_line
			(start -0.094672 0.201008)
			(end -0.094672 -0.198992)
			(stroke
				(width 0.1)
				(type solid)
			)
			(layer "F.SilkS")
		)
		(fp_line
			(start 0.105328 0.201008)
			(end -0.094672 0.001008)
			(stroke
				(width 0.1)
				(type solid)
			)
			(layer "F.SilkS")
		)
		(fp_line
			(start 0.105328 0.201008)
			(end 0.105328 -0.198992)
			(stroke
				(width 0.1)
				(type solid)
			)
			(layer "F.SilkS")
		)
		(fp_line
			(start -0.094672 0.001008)
			(end -0.24 0.001008)
			(stroke
				(width 0.1)
				(type solid)
			)
			(layer "F.SilkS")
		)
		(fp_line
			(start -0.094672 0.001008)
			(end 0.105328 -0.198992)
			(stroke
				(width 0.1)
				(type solid)
			)
			(layer "F.SilkS")
		)
		(fp_line
			(start 0.105328 0.001008)
			(end 0.24 0.001)
			(stroke
				(width 0.1)
				(type solid)
			)
			(layer "F.SilkS")
		)
		(fp_line
			(start -1.18 -0.319)
			(end -1.18 0.321)
			(stroke
				(width 0.15)
				(type solid)
			)
			(layer "F.SilkS")
		)
		(fp_line
			(start 0.22 -0.35)
			(end -0.22 -0.35)
			(stroke
				(width 0.15)
				(type solid)
			)
			(layer "F.SilkS")
		)
		(fp_rect
			(start 1.25 0.65)
			(end -1.25 -0.65)
			(stroke
				(width 0.05)
				(type solid)
			)
			(fill no)
			(layer "F.CrtYd")
		)
		(fp_line
			(start -0.199 0.2)
			(end -0.199 0.1)
			(stroke
				(width 0.15)
				(type solid)
			)
			(layer "F.Fab")
		)
		(fp_line
			(start 0.201 0.2)
			(end 0.201 0)
			(stroke
				(width 0.15)
				(type solid)
			)
			(layer "F.Fab")
		)
		(fp_line
			(start -0.199 0)
			(end -0.597 0)
			(stroke
				(width 0.15)
				(type solid)
			)
			(layer "F.Fab")
		)
		(fp_line
			(start -0.101 0)
			(end 0.201 0.2)
			(stroke
				(width 0.15)
				(type solid)
			)
			(layer "F.Fab")
		)
		(fp_line
			(start 0.201 0)
			(end 0.201 -0.202)
			(stroke
				(width 0.15)
				(type solid)
			)
			(layer "F.Fab")
		)
		(fp_line
			(start 0.599 0)
			(end 0.201 0)
			(stroke
				(width 0.15)
				(type solid)
			)
			(layer "F.Fab")
		)
		(fp_line
			(start -0.199 -0.202)
			(end -0.199 0.1)
			(stroke
				(width 0.15)
				(type solid)
			)
			(layer "F.Fab")
		)
		(fp_line
			(start 0.201 -0.202)
			(end -0.101 0)
			(stroke
				(width 0.15)
				(type solid)
			)
			(layer "F.Fab")
		)
		(fp_rect
			(start 0.848 0.4)
			(end -0.85 -0.402)
			(stroke
				(width 0.15)
				(type solid)
			)
			(fill no)
			(layer "F.Fab")
		)
		(fp_text user "License: Apache-2.0"
			(at -1.4224 3.599 90)
			(layer "F.Fab")
			(effects
				(font
					(size 0.7 0.7)
					(thickness 0.15)
				)
				(justify right top)
			)
		)
		(fp_text user "Author: Antmicro"
			(at -1.4224 4.799 90)
			(layer "F.Fab")
			(effects
				(font
					(size 0.7 0.7)
					(thickness 0.15)
				)
				(justify right top)
			)
		)
		(fp_text user "${REFERENCE}"
			(at -1.4224 5.999 90)
			(layer "F.Fab")
			(effects
				(font
					(size 0.7 0.7)
					(thickness 0.15)
				)
				(justify right top)
			)
		)
		(pad "1" smd roundrect
			(at -0.7 0 90)
			(size 0.8 1)
			(layers "F.Cu" "F.Mask" "F.Paste")
			(roundrect_rratio 0.2)
			(net 39 "Net-(D36-C)")
			(pinfunction "C")
			(pintype "passive")
		)
		(pad "2" smd roundrect
			(at 0.7 0 90)
			(size 0.8 1)
			(layers "F.Cu" "F.Mask" "F.Paste")
			(roundrect_rratio 0.2)
			(net 38 "Net-(D36-A)")
			(pinfunction "A")
			(pintype "passive")
		)
	)
	(footprint "antmicro-footprints:LED_0603_1608Metric_G"
		(layer "F.Cu")
		(at 169.98 63.2 -90)
		(descr "LED SMD 0603 Green")
		(tags "LED SMD 0603 Green")
		(property "Reference" "D35"
			(at -0.9 2.58 90)
			(layer "F.SilkS")
			(effects
				(font
					(size 0.7 0.7)
					(thickness 0.15)
				)
				(justify right top)
			)
		)
		(property "Value" "LED_G_0603_LTST-C190GKT"
			(at -0.001 1.599 90)
			(layer "F.Fab")
			(effects
				(font
					(size 0.7 0.7)
					(thickness 0.15)
				)
				(justify right top)
			)
		)
		(property "Datasheet" "https://media.digikey.com/pdf/Data%20Sheets/Lite-On%20PDFs/LTST-C190GKT.pdf"
			(at 0 0 90)
			(layer "F.Fab")
			(hide yes)
			(effects
				(font
					(size 1.27 1.27)
					(thickness 0.15)
				)
			)
		)
		(property "Description" "LED, Green, SMD, 0603, 20 mA, 2.1 V, 569 nm"
			(at 0 0 90)
			(layer "F.Fab")
			(hide yes)
			(effects
				(font
					(size 1.27 1.27)
					(thickness 0.15)
				)
			)
		)
		(property "MPN" "LTST-C190GKT"
			(at 0 0 270)
			(unlocked yes)
			(layer "F.Fab")
			(hide yes)
			(effects
				(font
					(size 1 1)
					(thickness 0.15)
				)
			)
		)
		(property "Manufacturer" "Lite-On"
			(at 0 0 270)
			(unlocked yes)
			(layer "F.Fab")
			(hide yes)
			(effects
				(font
					(size 1 1)
					(thickness 0.15)
				)
			)
		)
		(property "Author" "Antmicro"
			(at 0 0 270)
			(unlocked yes)
			(layer "F.Fab")
			(hide yes)
			(effects
				(font
					(size 1 1)
					(thickness 0.15)
				)
			)
		)
		(property "License" "Apache-2.0"
			(at 0 0 270)
			(unlocked yes)
			(layer "F.Fab")
			(hide yes)
			(effects
				(font
					(size 1 1)
					(thickness 0.15)
				)
			)
		)
		(property "Color" "Green"
			(at 0 0 270)
			(unlocked yes)
			(layer "F.Fab")
			(hide yes)
			(effects
				(font
					(size 1 1)
					(thickness 0.15)
				)
			)
		)
		(sheetname "/Peripherals/")
		(sheetfile "peripherals.kicad_sch")
		(attr smd)
		(fp_line
			(start 0.22 0.35)
			(end -0.22 0.35)
			(stroke
				(width 0.15)
				(type solid)
			)
			(layer "F.SilkS")
		)
		(fp_line
			(start -0.094672 0.201008)
			(end -0.094672 -0.198992)
			(stroke
				(width 0.1)
				(type solid)
			)
			(layer "F.SilkS")
		)
		(fp_line
			(start 0.105328 0.201008)
			(end -0.094672 0.001008)
			(stroke
				(width 0.1)
				(type solid)
			)
			(layer "F.SilkS")
		)
		(fp_line
			(start 0.105328 0.201008)
			(end 0.105328 -0.198992)
			(stroke
				(width 0.1)
				(type solid)
			)
			(layer "F.SilkS")
		)
		(fp_line
			(start -0.094672 0.001008)
			(end -0.24 0.001008)
			(stroke
				(width 0.1)
				(type solid)
			)
			(layer "F.SilkS")
		)
		(fp_line
			(start -0.094672 0.001008)
			(end 0.105328 -0.198992)
			(stroke
				(width 0.1)
				(type solid)
			)
			(layer "F.SilkS")
		)
		(fp_line
			(start 0.105328 0.001008)
			(end 0.24 0.001)
			(stroke
				(width 0.1)
				(type solid)
			)
			(layer "F.SilkS")
		)
		(fp_line
			(start -1.18 -0.319)
			(end -1.18 0.321)
			(stroke
				(width 0.15)
				(type solid)
			)
			(layer "F.SilkS")
		)
		(fp_line
			(start 0.22 -0.35)
			(end -0.22 -0.35)
			(stroke
				(width 0.15)
				(type solid)
			)
			(layer "F.SilkS")
		)
		(fp_rect
			(start 1.25 0.65)
			(end -1.25 -0.65)
			(stroke
				(width 0.05)
				(type solid)
			)
			(fill no)
			(layer "F.CrtYd")
		)
		(fp_line
			(start -0.199 0.2)
			(end -0.199 0.1)
			(stroke
				(width 0.15)
				(type solid)
			)
			(layer "F.Fab")
		)
		(fp_line
			(start 0.201 0.2)
			(end 0.201 0)
			(stroke
				(width 0.15)
				(type solid)
			)
			(layer "F.Fab")
		)
		(fp_line
			(start -0.199 0)
			(end -0.597 0)
			(stroke
				(width 0.15)
				(type solid)
			)
			(layer "F.Fab")
		)
		(fp_line
			(start -0.101 0)
			(end 0.201 0.2)
			(stroke
				(width 0.15)
				(type solid)
			)
			(layer "F.Fab")
		)
		(fp_line
			(start 0.201 0)
			(end 0.201 -0.202)
			(stroke
				(width 0.15)
				(type solid)
			)
			(layer "F.Fab")
		)
		(fp_line
			(start 0.599 0)
			(end 0.201 0)
			(stroke
				(width 0.15)
				(type solid)
			)
			(layer "F.Fab")
		)
		(fp_line
			(start -0.199 -0.202)
			(end -0.199 0.1)
			(stroke
				(width 0.15)
				(type solid)
			)
			(layer "F.Fab")
		)
		(fp_line
			(start 0.201 -0.202)
			(end -0.101 0)
			(stroke
				(width 0.15)
				(type solid)
			)
			(layer "F.Fab")
		)
		(fp_rect
			(start 0.848 0.4)
			(end -0.85 -0.402)
			(stroke
				(width 0.15)
				(type solid)
			)
			(fill no)
			(layer "F.Fab")
		)
		(fp_text user "${REFERENCE}"
			(at -1.4224 5.999 90)
			(layer "F.Fab")
			(effects
				(font
					(size 0.7 0.7)
					(thickness 0.15)
				)
				(justify right top)
			)
		)
		(fp_text user "License: Apache-2.0"
			(at -1.4224 3.599 90)
			(layer "F.Fab")
			(effects
				(font
					(size 0.7 0.7)
					(thickness 0.15)
				)
				(justify right top)
			)
		)
		(fp_text user "Author: Antmicro"
			(at -1.4224 4.799 90)
			(layer "F.Fab")
			(effects
				(font
					(size 0.7 0.7)
					(thickness 0.15)
				)
				(justify right top)
			)
		)
		(pad "1" smd roundrect
			(at -0.7 0 90)
			(size 0.8 1)
			(layers "F.Cu" "F.Mask" "F.Paste")
			(roundrect_rratio 0.2)
			(net 37 "Net-(D35-C)")
			(pinfunction "C")
			(pintype "passive")
		)
		(pad "2" smd roundrect
			(at 0.7 0 90)
			(size 0.8 1)
			(layers "F.Cu" "F.Mask" "F.Paste")
			(roundrect_rratio 0.2)
			(net 36 "Net-(D35-A)")
			(pinfunction "A")
			(pintype "passive")
		)
	)
	(footprint "antmicro-footprints:C_0402_1005Metric"
		(layer "F.Cu")
		(at 160.368936 99.565 180)
		(descr "Capacitor SMD 0402")
		(tags "capacitor SMD 0402")
		(property "Reference" "C36"
			(at 3.968936 0.365 0)
			(layer "F.SilkS")
			(effects
				(font
					(size 0.7 0.7)
					(thickness 0.15)
				)
				(justify right top)
			)
		)
		(property "Value" "C_100n_0402"
			(at -1.022927 2.155213 0)
			(layer "F.Fab")
			(effects
				(font
					(size 0.7 0.7)
					(thickness 0.15)
				)
				(justify right top)
			)
		)
		(property "Datasheet" "https://www.murata.com/products/productdetail?partno=GRM155R61H104KE14%23"
			(at 0 0 0)
			(layer "F.Fab")
			(hide yes)
			(effects
				(font
					(size 1.27 1.27)
					(thickness 0.15)
				)
			)
		)
		(property "Description" "SMD Multilayer Ceramic Capacitor, 0.1 µF, 50 V, 0402 [1005 Metric], ± 10%, X5R, GRM Series"
			(at 0 0 0)
			(layer "F.Fab")
			(hide yes)
			(effects
				(font
					(size 1.27 1.27)
					(thickness 0.15)
				)
			)
		)
		(property "MPN" "GRM155R61H104KE14D"
			(at 0 0 180)
			(unlocked yes)
			(layer "F.Fab")
			(hide yes)
			(effects
				(font
					(size 1 1)
					(thickness 0.15)
				)
			)
		)
		(property "Manufacturer" "Murata"
			(at 0 0 180)
			(unlocked yes)
			(layer "F.Fab")
			(hide yes)
			(effects
				(font
					(size 1 1)
					(thickness 0.15)
				)
			)
		)
		(property "License" "Apache-2.0"
			(at 0 0 180)
			(unlocked yes)
			(layer "F.Fab")
			(hide yes)
			(effects
				(font
					(size 1 1)
					(thickness 0.15)
				)
			)
		)
		(property "Author" "Antmicro"
			(at 0 0 180)
			(unlocked yes)
			(layer "F.Fab")
			(hide yes)
			(effects
				(font
					(size 1 1)
					(thickness 0.15)
				)
			)
		)
		(property "Val" "100n"
			(at 0 0 180)
			(unlocked yes)
			(layer "F.Fab")
			(hide yes)
			(effects
				(font
					(size 1 1)
					(thickness 0.15)
				)
			)
		)
		(property "Voltage" "50V"
			(at 0 0 180)
			(unlocked yes)
			(layer "F.Fab")
			(hide yes)
			(effects
				(font
					(size 1 1)
					(thickness 0.15)
				)
			)
		)
		(property "Dielectric" "X5R"
			(at 0 0 180)
			(unlocked yes)
			(layer "F.Fab")
			(hide yes)
			(effects
				(font
					(size 1 1)
					(thickness 0.15)
				)
			)
		)
		(property "Public" "False"
			(at 0 0 180)
			(unlocked yes)
			(layer "F.Fab")
			(hide yes)
			(effects
				(font
					(size 1 1)
					(thickness 0.15)
				)
			)
		)
		(component_classes
			(class "DCDC_SOM")
		)
		(sheetname "/DCDC/")
		(sheetfile "dcdc.kicad_sch")
		(attr smd)
		(fp_rect
			(start -0.925 -0.47)
			(end 0.925 0.47)
			(stroke
				(width 0.05)
				(type default)
			)
			(fill no)
			(layer "F.CrtYd")
		)
		(fp_line
			(start 0.504 0.248)
			(end -0.494 0.248)
			(stroke
				(width 0.15)
				(type solid)
			)
			(layer "F.Fab")
		)
		(fp_line
			(start 0.504 -0.25)
			(end 0.504 0.248)
			(stroke
				(width 0.15)
				(type solid)
			)
			(layer "F.Fab")
		)
		(fp_line
			(start -0.494 0.248)
			(end -0.494 -0.25)
			(stroke
				(width 0.15)
				(type solid)
			)
			(layer "F.Fab")
		)
		(fp_line
			(start -0.494 -0.25)
			(end 0.504 -0.25)
			(stroke
				(width 0.15)
				(type solid)
			)
			(layer "F.Fab")
		)
		(fp_text user "Author: Antmicro"
			(at -0.939 3.399 0)
			(layer "F.Fab")
			(effects
				(font
					(size 0.7 0.7)
					(thickness 0.15)
				)
				(justify right top)
			)
		)
		(fp_text user "${REFERENCE}"
			(at -0.939 4.599 0)
			(layer "F.Fab")
			(effects
				(font
					(size 0.7 0.7)
					(thickness 0.15)
				)
				(justify right top)
			)
		)
		(fp_text user "License: Apache-2.0"
			(at -0.939 5.799 0)
			(layer "F.Fab")
			(effects
				(font
					(size 0.7 0.7)
					(thickness 0.15)
				)
				(justify right top)
			)
		)
		(pad "1" smd roundrect
			(at -0.48 0 180)
			(size 0.59 0.64)
			(layers "F.Cu" "F.Mask" "F.Paste")
			(roundrect_rratio 0.25)
			(net 1 "GND")
			(pintype "passive")
		)
		(pad "2" smd roundrect
			(at 0.48 0 180)
			(size 0.59 0.64)
			(layers "F.Cu" "F.Mask" "F.Paste")
			(roundrect_rratio 0.25)
			(net 4 "+3V3_AON")
			(pintype "passive")
		)
	)
	(footprint "antmicro-footprints:R_0402_1005Metric"
		(layer "F.Cu")
		(at 64.25 85.95 -90)
		(descr "Resistor SMD 0402")
		(tags "resistor SMD 0402")
		(property "Reference" "R168"
			(at -3.85 0.35 90)
			(layer "F.SilkS")
			(effects
				(font
					(size 0.7 0.7)
					(thickness 0.15)
				)
				(justify right top)
			)
		)
		(property "Value" "R_10k_0402"
			(at -1.011843 1.772047 90)
			(layer "F.Fab")
			(effects
				(font
					(size 0.7 0.7)
					(thickness 0.15)
				)
				(justify right top)
			)
		)
		(property "Datasheet" "https://www.bourns.com/docs/product-datasheets/cr.pdf"
			(at 0 0 90)
			(layer "F.Fab")
			(hide yes)
			(effects
				(font
					(size 1.27 1.27)
					(thickness 0.15)
				)
			)
		)
		(property "Description" "SMD Chip Resistor, 10 kohm, ± 1%, 62.5 mW, 0402 [1005 Metric], Thick Film, General Purpose"
			(at 0 0 90)
			(layer "F.Fab")
			(hide yes)
			(effects
				(font
					(size 1.27 1.27)
					(thickness 0.15)
				)
			)
		)
		(property "Manufacturer" "Bourns"
			(at 0 0 270)
			(unlocked yes)
			(layer "F.Fab")
			(hide yes)
			(effects
				(font
					(size 1 1)
					(thickness 0.15)
				)
			)
		)
		(property "MPN" "CR0402-FX-1002GLF"
			(at 0 0 270)
			(unlocked yes)
			(layer "F.Fab")
			(hide yes)
			(effects
				(font
					(size 1 1)
					(thickness 0.15)
				)
			)
		)
		(property "Val" "10k"
			(at 0 0 270)
			(unlocked yes)
			(layer "F.Fab")
			(hide yes)
			(effects
				(font
					(size 1 1)
					(thickness 0.15)
				)
			)
		)
		(property "License" "Apache-2.0"
			(at 0 0 270)
			(unlocked yes)
			(layer "F.Fab")
			(hide yes)
			(effects
				(font
					(size 1 1)
					(thickness 0.15)
				)
			)
		)
		(property "Author" "Antmicro"
			(at 0 0 270)
			(unlocked yes)
			(layer "F.Fab")
			(hide yes)
			(effects
				(font
					(size 1 1)
					(thickness 0.15)
				)
			)
		)
		(property "Tolerance" "1%"
			(at 0 0 270)
			(unlocked yes)
			(layer "F.Fab")
			(hide yes)
			(effects
				(font
					(size 1 1)
					(thickness 0.15)
				)
			)
		)
		(sheetname "/CSI/")
		(sheetfile "csi.kicad_sch")
		(attr smd)
		(fp_rect
			(start -0.925 -0.47)
			(end 0.925 0.47)
			(stroke
				(width 0.05)
				(type default)
			)
			(fill no)
			(layer "F.CrtYd")
		)
		(fp_rect
			(start -0.5 -0.25)
			(end 0.5 0.25)
			(stroke
				(width 0.15)
				(type solid)
			)
			(fill no)
			(layer "F.Fab")
		)
		(fp_text user "License: Apache-2.0"
			(at -0.95 5.169 90)
			(layer "F.Fab")
			(effects
				(font
					(size 0.7 0.7)
					(thickness 0.15)
				)
				(justify right top)
			)
		)
		(fp_text user "${REFERENCE}"
			(at -0.95 3.168 90)
			(layer "F.Fab")
			(effects
				(font
					(size 0.7 0.7)
					(thickness 0.15)
				)
				(justify right top)
			)
		)
		(fp_text user "Author: Antmicro"
			(at -0.95 4.169 90)
			(layer "F.Fab")
			(effects
				(font
					(size 0.7 0.7)
					(thickness 0.15)
				)
				(justify right top)
			)
		)
		(pad "1" smd roundrect
			(at -0.48 0 270)
			(size 0.59 0.64)
			(layers "F.Cu" "F.Mask" "F.Paste")
			(roundrect_rratio 0.25)
			(net 2 "+3V3")
			(pintype "passive")
		)
		(pad "2" smd roundrect
			(at 0.48 0 270)
			(size 0.59 0.64)
			(layers "F.Cu" "F.Mask" "F.Paste")
			(roundrect_rratio 0.25)
			(net 98 "/CSI/CAM_CTRL.CSIA_FLG")
			(pintype "passive")
		)
	)
	(footprint "antmicro-footprints:R_0402_1005Metric"
		(layer "F.Cu")
		(at 139.23 131.15 90)
		(descr "Resistor SMD 0402")
		(tags "resistor SMD 0402")
		(property "Reference" "R355"
			(at 0.85 0.39 90)
			(layer "F.SilkS")
			(effects
				(font
					(size 0.7 0.7)
					(thickness 0.15)
				)
				(justify left bottom)
			)
		)
		(property "Value" "R_10k_0402"
			(at -1.011843 1.772047 90)
			(layer "F.Fab")
			(effects
				(font
					(size 0.7 0.7)
					(thickness 0.15)
				)
				(justify left bottom)
			)
		)
		(property "Datasheet" "https://www.bourns.com/docs/product-datasheets/cr.pdf"
			(at 0 0 90)
			(layer "F.Fab")
			(hide yes)
			(effects
				(font
					(size 1.27 1.27)
					(thickness 0.15)
				)
			)
		)
		(property "Description" "SMD Chip Resistor, 10 kohm, ± 1%, 62.5 mW, 0402 [1005 Metric], Thick Film, General Purpose"
			(at 0 0 90)
			(layer "F.Fab")
			(hide yes)
			(effects
				(font
					(size 1.27 1.27)
					(thickness 0.15)
				)
			)
		)
		(property "Manufacturer" "Bourns"
			(at 0 0 90)
			(unlocked yes)
			(layer "F.Fab")
			(hide yes)
			(effects
				(font
					(size 1 1)
					(thickness 0.15)
				)
			)
		)
		(property "MPN" "CR0402-FX-1002GLF"
			(at 0 0 90)
			(unlocked yes)
			(layer "F.Fab")
			(hide yes)
			(effects
				(font
					(size 1 1)
					(thickness 0.15)
				)
			)
		)
		(property "Val" "10k"
			(at 0 0 90)
			(unlocked yes)
			(layer "F.Fab")
			(hide yes)
			(effects
				(font
					(size 1 1)
					(thickness 0.15)
				)
			)
		)
		(property "License" "Apache-2.0"
			(at 0 0 90)
			(unlocked yes)
			(layer "F.Fab")
			(hide yes)
			(effects
				(font
					(size 1 1)
					(thickness 0.15)
				)
			)
		)
		(property "Author" "Antmicro"
			(at 0 0 90)
			(unlocked yes)
			(layer "F.Fab")
			(hide yes)
			(effects
				(font
					(size 1 1)
					(thickness 0.15)
				)
			)
		)
		(property "Tolerance" "1%"
			(at 0 0 90)
			(unlocked yes)
			(layer "F.Fab")
			(hide yes)
			(effects
				(font
					(size 1 1)
					(thickness 0.15)
				)
			)
		)
		(sheetname "/SoM_Power/")
		(sheetfile "som_power.kicad_sch")
		(attr smd)
		(fp_rect
			(start -0.925 -0.47)
			(end 0.925 0.47)
			(stroke
				(width 0.05)
				(type default)
			)
			(fill no)
			(layer "F.CrtYd")
		)
		(fp_rect
			(start -0.5 -0.25)
			(end 0.5 0.25)
			(stroke
				(width 0.15)
				(type solid)
			)
			(fill no)
			(layer "F.Fab")
		)
		(fp_text user "Author: Antmicro"
			(at -0.95 4.169 90)
			(layer "F.Fab")
			(effects
				(font
					(size 0.7 0.7)
					(thickness 0.15)
				)
				(justify left bottom)
			)
		)
		(fp_text user "License: Apache-2.0"
			(at -0.95 5.169 90)
			(layer "F.Fab")
			(effects
				(font
					(size 0.7 0.7)
					(thickness 0.15)
				)
				(justify left bottom)
			)
		)
		(fp_text user "${REFERENCE}"
			(at -0.95 3.168 90)
			(layer "F.Fab")
			(effects
				(font
					(size 0.7 0.7)
					(thickness 0.15)
				)
				(justify left bottom)
			)
		)
		(pad "1" smd roundrect
			(at -0.48 0 90)
			(size 0.59 0.64)
			(layers "F.Cu" "F.Mask" "F.Paste")
			(roundrect_rratio 0.25)
			(net 1 "GND")
			(pintype "passive")
		)
		(pad "2" smd roundrect
			(at 0.48 0 90)
			(size 0.59 0.64)
			(layers "F.Cu" "F.Mask" "F.Paste")
			(roundrect_rratio 0.25)
			(net 1293 "/DCDC/CARRIER_PWR_ON")
			(pintype "passive")
		)
	)
	(footprint "antmicro-footprints:C_0402_1005Metric"
		(layer "F.Cu")
		(at 219.409001 99.005001 180)
		(descr "Capacitor SMD 0402")
		(tags "capacitor SMD 0402")
		(property "Reference" "C108"
			(at -1.164999 -0.634999 0)
			(layer "F.SilkS")
			(effects
				(font
					(size 0.7 0.7)
					(thickness 0.15)
				)
				(justify right top)
			)
		)
		(property "Value" "C_100n_0402"
			(at -1.022927 2.155213 0)
			(layer "F.Fab")
			(effects
				(font
					(size 0.7 0.7)
					(thickness 0.15)
				)
				(justify right top)
			)
		)
		(property "Datasheet" "https://www.murata.com/products/productdetail?partno=GRM155R61H104KE14%23"
			(at 0 0 0)
			(layer "F.Fab")
			(hide yes)
			(effects
				(font
					(size 1.27 1.27)
					(thickness 0.15)
				)
			)
		)
		(property "Description" "SMD Multilayer Ceramic Capacitor, 0.1 µF, 50 V, 0402 [1005 Metric], ± 10%, X5R, GRM Series"
			(at 0 0 0)
			(layer "F.Fab")
			(hide yes)
			(effects
				(font
					(size 1.27 1.27)
					(thickness 0.15)
				)
			)
		)
		(property "Manufacturer" "Murata"
			(at 0 0 180)
			(unlocked yes)
			(layer "F.Fab")
			(hide yes)
			(effects
				(font
					(size 1 1)
					(thickness 0.15)
				)
			)
		)
		(property "MPN" "GRM155R61H104KE14D"
			(at 0 0 180)
			(unlocked yes)
			(layer "F.Fab")
			(hide yes)
			(effects
				(font
					(size 1 1)
					(thickness 0.15)
				)
			)
		)
		(property "Val" "100n"
			(at 0 0 180)
			(unlocked yes)
			(layer "F.Fab")
			(hide yes)
			(effects
				(font
					(size 1 1)
					(thickness 0.15)
				)
			)
		)
		(property "License" "Apache-2.0"
			(at 0 0 180)
			(unlocked yes)
			(layer "F.Fab")
			(hide yes)
			(effects
				(font
					(size 1 1)
					(thickness 0.15)
				)
			)
		)
		(property "Author" "Antmicro"
			(at 0 0 180)
			(unlocked yes)
			(layer "F.Fab")
			(hide yes)
			(effects
				(font
					(size 1 1)
					(thickness 0.15)
				)
			)
		)
		(property "Voltage" "50V"
			(at 0 0 180)
			(unlocked yes)
			(layer "F.Fab")
			(hide yes)
			(effects
				(font
					(size 1 1)
					(thickness 0.15)
				)
			)
		)
		(property "Dielectric" "X5R"
			(at 0 0 180)
			(unlocked yes)
			(layer "F.Fab")
			(hide yes)
			(effects
				(font
					(size 1 1)
					(thickness 0.15)
				)
			)
		)
		(sheetname "/Recovery USB/")
		(sheetfile "recovery_usb.kicad_sch")
		(attr smd)
		(fp_rect
			(start -0.925 -0.47)
			(end 0.925 0.47)
			(stroke
				(width 0.05)
				(type default)
			)
			(fill no)
			(layer "F.CrtYd")
		)
		(fp_line
			(start 0.504 0.248)
			(end -0.494 0.248)
			(stroke
				(width 0.15)
				(type solid)
			)
			(layer "F.Fab")
		)
		(fp_line
			(start 0.504 -0.25)
			(end 0.504 0.248)
			(stroke
				(width 0.15)
				(type solid)
			)
			(layer "F.Fab")
		)
		(fp_line
			(start -0.494 0.248)
			(end -0.494 -0.25)
			(stroke
				(width 0.15)
				(type solid)
			)
			(layer "F.Fab")
		)
		(fp_line
			(start -0.494 -0.25)
			(end 0.504 -0.25)
			(stroke
				(width 0.15)
				(type solid)
			)
			(layer "F.Fab")
		)
		(fp_text user "Author: Antmicro"
			(at -0.939 3.399 0)
			(layer "F.Fab")
			(effects
				(font
					(size 0.7 0.7)
					(thickness 0.15)
				)
				(justify right top)
			)
		)
		(fp_text user "License: Apache-2.0"
			(at -0.939 5.799 0)
			(layer "F.Fab")
			(effects
				(font
					(size 0.7 0.7)
					(thickness 0.15)
				)
				(justify right top)
			)
		)
		(fp_text user "${REFERENCE}"
			(at -0.939 4.599 0)
			(layer "F.Fab")
			(effects
				(font
					(size 0.7 0.7)
					(thickness 0.15)
				)
				(justify right top)
			)
		)
		(pad "1" smd roundrect
			(at -0.48 0 180)
			(size 0.59 0.64)
			(layers "F.Cu" "F.Mask" "F.Paste")
			(roundrect_rratio 0.25)
			(net 241 "/Recovery USB/USBC2_CONN_TX2_N")
			(pintype "passive")
		)
		(pad "2" smd roundrect
			(at 0.48 0 180)
			(size 0.59 0.64)
			(layers "F.Cu" "F.Mask" "F.Paste")
			(roundrect_rratio 0.25)
			(net 237 "/Recovery USB/USBC2_TX2_N")
			(pintype "passive")
		)
	)
	(footprint "antmicro-footprints:C_0402_1005Metric"
		(layer "F.Cu")
		(at 67.4 97.075 90)
		(descr "Capacitor SMD 0402")
		(tags "capacitor SMD 0402")
		(property "Reference" "C162"
			(at -1.58 1.37 90)
			(layer "F.SilkS")
			(effects
				(font
					(size 0.7 0.7)
					(thickness 0.15)
				)
				(justify left bottom)
			)
		)
		(property "Value" "C_100n_0402"
			(at -1.022927 2.155213 90)
			(layer "F.Fab")
			(effects
				(font
					(size 0.7 0.7)
					(thickness 0.15)
				)
				(justify left bottom)
			)
		)
		(property "Datasheet" "https://www.murata.com/products/productdetail?partno=GRM155R61H104KE14%23"
			(at 0 0 90)
			(layer "F.Fab")
			(hide yes)
			(effects
				(font
					(size 1.27 1.27)
					(thickness 0.15)
				)
			)
		)
		(property "Description" "SMD Multilayer Ceramic Capacitor, 0.1 µF, 50 V, 0402 [1005 Metric], ± 10%, X5R, GRM Series"
			(at 0 0 90)
			(layer "F.Fab")
			(hide yes)
			(effects
				(font
					(size 1.27 1.27)
					(thickness 0.15)
				)
			)
		)
		(property "Manufacturer" "Murata"
			(at 0 0 90)
			(unlocked yes)
			(layer "F.Fab")
			(hide yes)
			(effects
				(font
					(size 1 1)
					(thickness 0.15)
				)
			)
		)
		(property "MPN" "GRM155R61H104KE14D"
			(at 0 0 90)
			(unlocked yes)
			(layer "F.Fab")
			(hide yes)
			(effects
				(font
					(size 1 1)
					(thickness 0.15)
				)
			)
		)
		(property "Val" "100n"
			(at 0 0 90)
			(unlocked yes)
			(layer "F.Fab")
			(hide yes)
			(effects
				(font
					(size 1 1)
					(thickness 0.15)
				)
			)
		)
		(property "License" "Apache-2.0"
			(at 0 0 90)
			(unlocked yes)
			(layer "F.Fab")
			(hide yes)
			(effects
				(font
					(size 1 1)
					(thickness 0.15)
				)
			)
		)
		(property "Author" "Antmicro"
			(at 0 0 90)
			(unlocked yes)
			(layer "F.Fab")
			(hide yes)
			(effects
				(font
					(size 1 1)
					(thickness 0.15)
				)
			)
		)
		(property "Voltage" "50V"
			(at 0 0 90)
			(unlocked yes)
			(layer "F.Fab")
			(hide yes)
			(effects
				(font
					(size 1 1)
					(thickness 0.15)
				)
			)
		)
		(property "Dielectric" "X5R"
			(at 0 0 90)
			(unlocked yes)
			(layer "F.Fab")
			(hide yes)
			(effects
				(font
					(size 1 1)
					(thickness 0.15)
				)
			)
		)
		(sheetname "/CSI/")
		(sheetfile "csi.kicad_sch")
		(attr smd)
		(fp_poly
			(pts
				(xy -0.925 -0.47) (xy -0.925 0.47) (xy 0.925 0.47) (xy 0.925 -0.47)
			)
			(stroke
				(width 0.05)
				(type default)
			)
			(fill no)
			(layer "F.CrtYd")
		)
		(fp_line
			(start 0.504 -0.25)
			(end 0.504 0.248)
			(stroke
				(width 0.15)
				(type solid)
			)
			(layer "F.Fab")
		)
		(fp_line
			(start -0.494 -0.25)
			(end 0.504 -0.25)
			(stroke
				(width 0.15)
				(type solid)
			)
			(layer "F.Fab")
		)
		(fp_line
			(start 0.504 0.248)
			(end -0.494 0.248)
			(stroke
				(width 0.15)
				(type solid)
			)
			(layer "F.Fab")
		)
		(fp_line
			(start -0.494 0.248)
			(end -0.494 -0.25)
			(stroke
				(width 0.15)
				(type solid)
			)
			(layer "F.Fab")
		)
		(fp_text user "${REFERENCE}"
			(at -0.939 4.599 90)
			(layer "F.Fab")
			(effects
				(font
					(size 0.7 0.7)
					(thickness 0.15)
				)
				(justify left bottom)
			)
		)
		(fp_text user "License: Apache-2.0"
			(at -0.939 5.799 90)
			(layer "F.Fab")
			(effects
				(font
					(size 0.7 0.7)
					(thickness 0.15)
				)
				(justify left bottom)
			)
		)
		(fp_text user "Author: Antmicro"
			(at -0.939 3.399 90)
			(layer "F.Fab")
			(effects
				(font
					(size 0.7 0.7)
					(thickness 0.15)
				)
				(justify left bottom)
			)
		)
		(pad "1" smd roundrect
			(at -0.48 0 90)
			(size 0.59 0.64)
			(layers "F.Cu" "F.Mask" "F.Paste")
			(roundrect_rratio 0.25)
			(net 1 "GND")
			(pintype "passive")
		)
		(pad "2" smd roundrect
			(at 0.48 0 90)
			(size 0.59 0.64)
			(layers "F.Cu" "F.Mask" "F.Paste")
			(roundrect_rratio 0.25)
			(net 11 "+1V8")
			(pintype "passive")
		)
	)
	(footprint "antmicro-footprints:SW_KMR211NGLFS_SMD"
		(layer "F.Cu")
		(at 191 60.6)
		(property "Reference" "S3"
			(at -1.4 2 0)
			(layer "F.SilkS")
			(hide yes)
			(effects
				(font
					(size 0.7 0.7)
					(thickness 0.15)
				)
				(justify right top)
			)
		)
		(property "Value" "SW_KMR211NGLFS_SMD"
			(at 0 2.8 0)
			(layer "F.Fab")
			(effects
				(font
					(size 0.7 0.7)
					(thickness 0.15)
				)
				(justify left bottom)
			)
		)
		(property "Datasheet" "http://www.farnell.com/datasheets/2631211.pdf"
			(at 0 0 0)
			(layer "F.Fab")
			(hide yes)
			(effects
				(font
					(size 1.27 1.27)
					(thickness 0.15)
				)
			)
		)
		(property "Description" "Tactile Switch, KMR 2 Series, Top Actuated, Surface Mount, Oval Button, 120 gf, 50mA at 32VDC"
			(at 0 0 0)
			(layer "F.Fab")
			(hide yes)
			(effects
				(font
					(size 1.27 1.27)
					(thickness 0.15)
				)
			)
		)
		(property "MPN" "KMR211NGLFS"
			(at 0 0 0)
			(unlocked yes)
			(layer "F.Fab")
			(hide yes)
			(effects
				(font
					(size 1 1)
					(thickness 0.15)
				)
			)
		)
		(property "Manufacturer" "C&K"
			(at 0 0 0)
			(unlocked yes)
			(layer "F.Fab")
			(hide yes)
			(effects
				(font
					(size 1 1)
					(thickness 0.15)
				)
			)
		)
		(property "Author" "Antmicro"
			(at 0 0 0)
			(unlocked yes)
			(layer "F.Fab")
			(hide yes)
			(effects
				(font
					(size 1 1)
					(thickness 0.15)
				)
			)
		)
		(property "License" "Apache-2.0"
			(at 0 0 0)
			(unlocked yes)
			(layer "F.Fab")
			(hide yes)
			(effects
				(font
					(size 1 1)
					(thickness 0.15)
				)
			)
		)
		(sheetname "/Peripherals/")
		(sheetfile "peripherals.kicad_sch")
		(attr smd)
		(fp_line
			(start -2.1 -1.6)
			(end -2.1 -1.499)
			(stroke
				(width 0.15)
				(type solid)
			)
			(layer "F.SilkS")
		)
		(fp_line
			(start -2.1 1.601)
			(end -2.1 1.48)
			(stroke
				(width 0.15)
				(type solid)
			)
			(layer "F.SilkS")
		)
		(fp_line
			(start 2.101 -1.6)
			(end -2.1 -1.6)
			(stroke
				(width 0.15)
				(type solid)
			)
			(layer "F.SilkS")
		)
		(fp_line
			(start 2.101 -1.58)
			(end 2.101 -1.459)
			(stroke
				(width 0.15)
				(type solid)
			)
			(layer "F.SilkS")
		)
		(fp_line
			(start 2.101 1.601)
			(end -2.1 1.601)
			(stroke
				(width 0.15)
				(type solid)
			)
			(layer "F.SilkS")
		)
		(fp_line
			(start 2.101 1.601)
			(end 2.101 1.48)
			(stroke
				(width 0.15)
				(type solid)
			)
			(layer "F.SilkS")
		)
		(fp_poly
			(pts
				(xy 2.751 1.75) (xy 2.751 -1.749) (xy -2.748 -1.749) (xy -2.748 1.749999)
			)
			(stroke
				(width 0.05)
				(type solid)
			)
			(fill no)
			(layer "F.CrtYd")
		)
		(fp_line
			(start -2.1 -1.6)
			(end -2.1 1.601)
			(stroke
				(width 0.15)
				(type solid)
			)
			(layer "F.Fab")
		)
		(fp_line
			(start -2.1 1.601)
			(end 2.101 1.601)
			(stroke
				(width 0.15)
				(type solid)
			)
			(layer "F.Fab")
		)
		(fp_line
			(start -0.248 -0.8)
			(end 0.25 -0.8)
			(stroke
				(width 0.15)
				(type solid)
			)
			(layer "F.Fab")
		)
		(fp_line
			(start 0.25 0.802)
			(end -0.248 0.802)
			(stroke
				(width 0.15)
				(type solid)
			)
			(layer "F.Fab")
		)
		(fp_line
			(start 2.101 -1.6)
			(end -2.1 -1.6)
			(stroke
				(width 0.15)
				(type solid)
			)
			(layer "F.Fab")
		)
		(fp_line
			(start 2.101 1.601)
			(end 2.101 -1.6)
			(stroke
				(width 0.15)
				(type solid)
			)
			(layer "F.Fab")
		)
		(fp_arc
			(start -0.248 0.802)
			(mid -1.050001 0.001)
			(end -0.248 -0.8)
			(stroke
				(width 0.15)
				(type solid)
			)
			(layer "F.Fab")
		)
		(fp_arc
			(start 0.25 -0.8)
			(mid 1.051001 0.001)
			(end 0.25 0.802)
			(stroke
				(width 0.15)
				(type solid)
			)
			(layer "F.Fab")
		)
		(fp_text user "Author: Antmicro"
			(at -3 5.5 0)
			(layer "F.Fab")
			(effects
				(font
					(size 0.7 0.7)
					(thickness 0.15)
				)
				(justify left bottom)
			)
		)
		(fp_text user "License: Apache-2.0"
			(at -3 6.75 0)
			(layer "F.Fab")
			(effects
				(font
					(size 0.7 0.7)
					(thickness 0.15)
				)
				(justify left bottom)
			)
		)
		(fp_text user "${REFERENCE}"
			(at -3 4.25 0)
			(layer "F.Fab")
			(effects
				(font
					(size 0.7 0.7)
					(thickness 0.15)
				)
				(justify left bottom)
			)
		)
		(pad "1" smd rect
			(at -2.048 -0.8 180)
			(size 0.9 1)
			(layers "F.Cu" "F.Mask" "F.Paste")
			(net 356 "/Expansion connector/GPIO.USER_BTN1")
			(pinfunction "1")
			(pintype "passive")
		)
		(pad "2" smd rect
			(at 2.049999 -0.8 180)
			(size 0.9 1)
			(layers "F.Cu" "F.Mask" "F.Paste")
			(net 356 "/Expansion connector/GPIO.USER_BTN1")
			(pinfunction "2")
			(pintype "passive")
		)
		(pad "3" smd rect
			(at -2.048 0.802 180)
			(size 0.9 1)
			(layers "F.Cu" "F.Mask" "F.Paste")
			(net 1 "GND")
			(pinfunction "3")
			(pintype "passive")
		)
		(pad "4" smd rect
			(at 2.05 0.802001 180)
			(size 0.9 1)
			(layers "F.Cu" "F.Mask" "F.Paste")
			(net 1 "GND")
			(pinfunction "4")
			(pintype "passive")
		)
	)
	(footprint "antmicro-footprints:R_0402_1005Metric"
		(layer "F.Cu")
		(at 215.8 120.1 -90)
		(descr "Resistor SMD 0402")
		(tags "resistor SMD 0402")
		(property "Reference" "R78"
			(at -3 0.4 90)
			(layer "F.SilkS")
			(effects
				(font
					(size 0.7 0.7)
					(thickness 0.15)
				)
				(justify right top)
			)
		)
		(property "Value" "R_200k_0402"
			(at -1.011843 1.772046 90)
			(layer "F.Fab")
			(effects
				(font
					(size 0.7 0.7)
					(thickness 0.15)
				)
				(justify right top)
			)
		)
		(property "Datasheet" "https://www.bourns.com/docs/product-datasheets/cr.pdf"
			(at 0 0 90)
			(layer "F.Fab")
			(hide yes)
			(effects
				(font
					(size 1.27 1.27)
					(thickness 0.15)
				)
			)
		)
		(property "Description" "SMD Chip Resistor, 200 kohm, ± 1%, 62.5 mW, 0402 [1005 Metric], Thick Film, General Purpose"
			(at 0 0 90)
			(layer "F.Fab")
			(hide yes)
			(effects
				(font
					(size 1.27 1.27)
					(thickness 0.15)
				)
			)
		)
		(property "MPN" "CR0402-FX-2003GLF"
			(at 0 0 270)
			(unlocked yes)
			(layer "F.Fab")
			(hide yes)
			(effects
				(font
					(size 1 1)
					(thickness 0.15)
				)
			)
		)
		(property "Manufacturer" "Bourns"
			(at 0 0 270)
			(unlocked yes)
			(layer "F.Fab")
			(hide yes)
			(effects
				(font
					(size 1 1)
					(thickness 0.15)
				)
			)
		)
		(property "License" "Apache-2.0"
			(at 0 0 270)
			(unlocked yes)
			(layer "F.Fab")
			(hide yes)
			(effects
				(font
					(size 1 1)
					(thickness 0.15)
				)
			)
		)
		(property "Author" "Antmicro"
			(at 0 0 270)
			(unlocked yes)
			(layer "F.Fab")
			(hide yes)
			(effects
				(font
					(size 1 1)
					(thickness 0.15)
				)
			)
		)
		(property "Val" "200k"
			(at 0 0 270)
			(unlocked yes)
			(layer "F.Fab")
			(hide yes)
			(effects
				(font
					(size 1 1)
					(thickness 0.15)
				)
			)
		)
		(property "Tolerance" "1%"
			(at 0 0 270)
			(unlocked yes)
			(layer "F.Fab")
			(hide yes)
			(effects
				(font
					(size 1 1)
					(thickness 0.15)
				)
			)
		)
		(sheetname "/USB Hub/")
		(sheetfile "usb_hub.kicad_sch")
		(attr smd exclude_from_pos_files exclude_from_bom dnp)
		(fp_poly
			(pts
				(xy -0.925 -0.47) (xy 0.925 -0.47) (xy 0.925 0.47) (xy -0.925 0.47)
			)
			(stroke
				(width 0.05)
				(type default)
			)
			(fill no)
			(layer "F.CrtYd")
		)
		(fp_poly
			(pts
				(xy -0.5 -0.25) (xy 0.5 -0.25) (xy 0.5 0.25) (xy -0.5 0.25)
			)
			(stroke
				(width 0.15)
				(type solid)
			)
			(fill no)
			(layer "F.Fab")
		)
		(fp_text user "License: Apache-2.0"
			(at -0.949999 5.169 90)
			(layer "F.Fab")
			(effects
				(font
					(size 0.7 0.7)
					(thickness 0.15)
				)
				(justify right top)
			)
		)
		(fp_text user "${REFERENCE}"
			(at -0.95 3.168 90)
			(layer "F.Fab")
			(effects
				(font
					(size 0.7 0.7)
					(thickness 0.15)
				)
				(justify right top)
			)
		)
		(fp_text user "Author: Antmicro"
			(at -0.95 4.169 90)
			(layer "F.Fab")
			(effects
				(font
					(size 0.7 0.7)
					(thickness 0.15)
				)
				(justify right top)
			)
		)
		(pad "1" smd roundrect
			(at -0.48 0 270)
			(size 0.59 0.64)
			(layers "F.Cu" "F.Mask" "F.Paste")
			(roundrect_rratio 0.25)
			(net 1 "GND")
			(pintype "passive")
		)
		(pad "2" smd roundrect
			(at 0.48 0 270)
			(size 0.59 0.64)
			(layers "F.Cu" "F.Mask" "F.Paste")
			(roundrect_rratio 0.25)
			(net 913 "/USB Hub/CFG_STRAP1")
			(pintype "passive")
		)
	)
	(footprint "antmicro-footprints:C_0402_1005Metric"
		(layer "F.Cu")
		(at 213.912407 98.212991 90)
		(descr "Capacitor SMD 0402")
		(tags "capacitor SMD 0402")
		(property "Reference" "C232"
			(at -1.787009 -2.612407 90)
			(layer "F.SilkS")
			(effects
				(font
					(size 0.7 0.7)
					(thickness 0.15)
				)
				(justify left bottom)
			)
		)
		(property "Value" "C_100n_0402"
			(at -1.022927 2.155213 90)
			(layer "F.Fab")
			(effects
				(font
					(size 0.7 0.7)
					(thickness 0.15)
				)
				(justify left bottom)
			)
		)
		(property "Datasheet" "https://www.murata.com/products/productdetail?partno=GRM155R61H104KE14%23"
			(at 0 0 90)
			(layer "F.Fab")
			(hide yes)
			(effects
				(font
					(size 1.27 1.27)
					(thickness 0.15)
				)
			)
		)
		(property "Description" "SMD Multilayer Ceramic Capacitor, 0.1 µF, 50 V, 0402 [1005 Metric], ± 10%, X5R, GRM Series"
			(at 0 0 90)
			(layer "F.Fab")
			(hide yes)
			(effects
				(font
					(size 1.27 1.27)
					(thickness 0.15)
				)
			)
		)
		(property "Manufacturer" "Murata"
			(at 0 0 90)
			(unlocked yes)
			(layer "F.Fab")
			(hide yes)
			(effects
				(font
					(size 1 1)
					(thickness 0.15)
				)
			)
		)
		(property "MPN" "GRM155R61H104KE14D"
			(at 0 0 90)
			(unlocked yes)
			(layer "F.Fab")
			(hide yes)
			(effects
				(font
					(size 1 1)
					(thickness 0.15)
				)
			)
		)
		(property "Val" "100n"
			(at 0 0 90)
			(unlocked yes)
			(layer "F.Fab")
			(hide yes)
			(effects
				(font
					(size 1 1)
					(thickness 0.15)
				)
			)
		)
		(property "License" "Apache-2.0"
			(at 0 0 90)
			(unlocked yes)
			(layer "F.Fab")
			(hide yes)
			(effects
				(font
					(size 1 1)
					(thickness 0.15)
				)
			)
		)
		(property "Author" "Antmicro"
			(at 0 0 90)
			(unlocked yes)
			(layer "F.Fab")
			(hide yes)
			(effects
				(font
					(size 1 1)
					(thickness 0.15)
				)
			)
		)
		(property "Voltage" "50V"
			(at 0 0 90)
			(unlocked yes)
			(layer "F.Fab")
			(hide yes)
			(effects
				(font
					(size 1 1)
					(thickness 0.15)
				)
			)
		)
		(property "Dielectric" "X5R"
			(at 0 0 90)
			(unlocked yes)
			(layer "F.Fab")
			(hide yes)
			(effects
				(font
					(size 1 1)
					(thickness 0.15)
				)
			)
		)
		(sheetname "/Recovery USB/")
		(sheetfile "recovery_usb.kicad_sch")
		(attr smd)
		(fp_poly
			(pts
				(xy -0.925 -0.47) (xy 0.925 -0.47) (xy 0.925 0.47) (xy -0.925 0.47)
			)
			(stroke
				(width 0.05)
				(type default)
			)
			(fill no)
			(layer "F.CrtYd")
		)
		(fp_line
			(start 0.504 -0.25)
			(end 0.504 0.248)
			(stroke
				(width 0.15)
				(type solid)
			)
			(layer "F.Fab")
		)
		(fp_line
			(start -0.494 -0.25)
			(end 0.504 -0.25)
			(stroke
				(width 0.15)
				(type solid)
			)
			(layer "F.Fab")
		)
		(fp_line
			(start 0.504 0.248)
			(end -0.494 0.248)
			(stroke
				(width 0.15)
				(type solid)
			)
			(layer "F.Fab")
		)
		(fp_line
			(start -0.494 0.248)
			(end -0.494 -0.25)
			(stroke
				(width 0.15)
				(type solid)
			)
			(layer "F.Fab")
		)
		(fp_text user "License: Apache-2.0"
			(at -0.939 5.799 90)
			(layer "F.Fab")
			(effects
				(font
					(size 0.7 0.7)
					(thickness 0.15)
				)
				(justify left bottom)
			)
		)
		(fp_text user "${REFERENCE}"
			(at -0.939 4.599 90)
			(layer "F.Fab")
			(effects
				(font
					(size 0.7 0.7)
					(thickness 0.15)
				)
				(justify left bottom)
			)
		)
		(fp_text user "Author: Antmicro"
			(at -0.939 3.399 90)
			(layer "F.Fab")
			(effects
				(font
					(size 0.7 0.7)
					(thickness 0.15)
				)
				(justify left bottom)
			)
		)
		(pad "1" smd roundrect
			(at -0.48 0 90)
			(size 0.59 0.64)
			(layers "F.Cu" "F.Mask" "F.Paste")
			(roundrect_rratio 0.25)
			(net 5 "+5V")
			(pintype "passive")
		)
		(pad "2" smd roundrect
			(at 0.48 0 90)
			(size 0.59 0.64)
			(layers "F.Cu" "F.Mask" "F.Paste")
			(roundrect_rratio 0.25)
			(net 1 "GND")
			(pintype "passive")
		)
	)
	(footprint "antmicro-footprints:C_0402_1005Metric"
		(layer "F.Cu")
		(at 177.94 142.88 -90)
		(descr "Capacitor SMD 0402")
		(tags "capacitor SMD 0402")
		(property "Reference" "C51"
			(at -2.93 0.47 90)
			(layer "F.SilkS")
			(effects
				(font
					(size 0.7 0.7)
					(thickness 0.15)
				)
				(justify right top)
			)
		)
		(property "Value" "C_100n_0402"
			(at -1.022927 2.155213 90)
			(layer "F.Fab")
			(effects
				(font
					(size 0.7 0.7)
					(thickness 0.15)
				)
				(justify right top)
			)
		)
		(property "Datasheet" "https://www.murata.com/products/productdetail?partno=GRM155R61H104KE14%23"
			(at 0 0 90)
			(layer "F.Fab")
			(hide yes)
			(effects
				(font
					(size 1.27 1.27)
					(thickness 0.15)
				)
			)
		)
		(property "Description" "SMD Multilayer Ceramic Capacitor, 0.1 µF, 50 V, 0402 [1005 Metric], ± 10%, X5R, GRM Series"
			(at 0 0 90)
			(layer "F.Fab")
			(hide yes)
			(effects
				(font
					(size 1.27 1.27)
					(thickness 0.15)
				)
			)
		)
		(property "Manufacturer" "Murata"
			(at 0 0 270)
			(unlocked yes)
			(layer "F.Fab")
			(hide yes)
			(effects
				(font
					(size 1 1)
					(thickness 0.15)
				)
			)
		)
		(property "MPN" "GRM155R61H104KE14D"
			(at 0 0 270)
			(unlocked yes)
			(layer "F.Fab")
			(hide yes)
			(effects
				(font
					(size 1 1)
					(thickness 0.15)
				)
			)
		)
		(property "Val" "100n"
			(at 0 0 270)
			(unlocked yes)
			(layer "F.Fab")
			(hide yes)
			(effects
				(font
					(size 1 1)
					(thickness 0.15)
				)
			)
		)
		(property "License" "Apache-2.0"
			(at 0 0 270)
			(unlocked yes)
			(layer "F.Fab")
			(hide yes)
			(effects
				(font
					(size 1 1)
					(thickness 0.15)
				)
			)
		)
		(property "Author" "Antmicro"
			(at 0 0 270)
			(unlocked yes)
			(layer "F.Fab")
			(hide yes)
			(effects
				(font
					(size 1 1)
					(thickness 0.15)
				)
			)
		)
		(property "Voltage" "50V"
			(at 0 0 270)
			(unlocked yes)
			(layer "F.Fab")
			(hide yes)
			(effects
				(font
					(size 1 1)
					(thickness 0.15)
				)
			)
		)
		(property "Dielectric" "X5R"
			(at 0 0 270)
			(unlocked yes)
			(layer "F.Fab")
			(hide yes)
			(effects
				(font
					(size 1 1)
					(thickness 0.15)
				)
			)
		)
		(sheetname "/DCDC/")
		(sheetfile "dcdc.kicad_sch")
		(attr smd)
		(fp_rect
			(start -0.925 -0.47)
			(end 0.925 0.47)
			(stroke
				(width 0.05)
				(type default)
			)
			(fill no)
			(layer "F.CrtYd")
		)
		(fp_line
			(start -0.494 0.248)
			(end -0.494 -0.25)
			(stroke
				(width 0.15)
				(type solid)
			)
			(layer "F.Fab")
		)
		(fp_line
			(start 0.504 0.248)
			(end -0.494 0.248)
			(stroke
				(width 0.15)
				(type solid)
			)
			(layer "F.Fab")
		)
		(fp_line
			(start -0.494 -0.25)
			(end 0.504 -0.25)
			(stroke
				(width 0.15)
				(type solid)
			)
			(layer "F.Fab")
		)
		(fp_line
			(start 0.504 -0.25)
			(end 0.504 0.248)
			(stroke
				(width 0.15)
				(type solid)
			)
			(layer "F.Fab")
		)
		(fp_text user "License: Apache-2.0"
			(at -0.939 5.799 90)
			(layer "F.Fab")
			(effects
				(font
					(size 0.7 0.7)
					(thickness 0.15)
				)
				(justify right top)
			)
		)
		(fp_text user "Author: Antmicro"
			(at -0.939 3.399 90)
			(layer "F.Fab")
			(effects
				(font
					(size 0.7 0.7)
					(thickness 0.15)
				)
				(justify right top)
			)
		)
		(fp_text user "${REFERENCE}"
			(at -0.939 4.599 90)
			(layer "F.Fab")
			(effects
				(font
					(size 0.7 0.7)
					(thickness 0.15)
				)
				(justify right top)
			)
		)
		(pad "1" smd roundrect
			(at -0.48 0 270)
			(size 0.59 0.64)
			(layers "F.Cu" "F.Mask" "F.Paste")
			(roundrect_rratio 0.25)
			(net 13 "VCC")
			(pintype "passive")
		)
		(pad "2" smd roundrect
			(at 0.48 0 270)
			(size 0.59 0.64)
			(layers "F.Cu" "F.Mask" "F.Paste")
			(roundrect_rratio 0.25)
			(net 1 "GND")
			(pintype "passive")
		)
	)
	(footprint "antmicro-footprints:TSOT23-6"
		(layer "F.Cu")
		(at 66.75 89 90)
		(property "Reference" "U44"
			(at -0.33 2.6 270)
			(layer "F.SilkS")
			(effects
				(font
					(size 0.7 0.7)
					(thickness 0.15)
				)
				(justify left bottom)
			)
		)
		(property "Value" "AP22615A_TSOT26"
			(at 0 2.6 90)
			(layer "F.Fab")
			(effects
				(font
					(size 0.7 0.7)
					(thickness 0.15)
				)
				(justify left bottom)
			)
		)
		(property "Datasheet" "https://www.mouser.com/datasheet/2/115/DIOD_S_A0008958405_1-2543193.pdf"
			(at 0 0 90)
			(layer "F.Fab")
			(hide yes)
			(effects
				(font
					(size 1.27 1.27)
					(thickness 0.15)
				)
			)
		)
		(property "Description" "Power Load Distribution Switch, High Side, Active High, 1 Output, 5.5 V, 3.6 A, 0.04 ohm, TSOT-26-6"
			(at 0 0 90)
			(layer "F.Fab")
			(hide yes)
			(effects
				(font
					(size 1.27 1.27)
					(thickness 0.15)
				)
			)
		)
		(property "MPN" "AP22615AWU-7"
			(at 0 0 90)
			(unlocked yes)
			(layer "F.Fab")
			(hide yes)
			(effects
				(font
					(size 1 1)
					(thickness 0.15)
				)
			)
		)
		(property "Manufacturer" "Diodes Incorporated"
			(at 0 0 90)
			(unlocked yes)
			(layer "F.Fab")
			(hide yes)
			(effects
				(font
					(size 1 1)
					(thickness 0.15)
				)
			)
		)
		(property "Author" "Antmicro"
			(at 0 0 90)
			(unlocked yes)
			(layer "F.Fab")
			(hide yes)
			(effects
				(font
					(size 1 1)
					(thickness 0.15)
				)
			)
		)
		(property "License" "Apache-2.0"
			(at 0 0 90)
			(unlocked yes)
			(layer "F.Fab")
			(hide yes)
			(effects
				(font
					(size 1 1)
					(thickness 0.15)
				)
			)
		)
		(sheetname "/CSI/")
		(sheetfile "csi.kicad_sch")
		(attr smd)
		(fp_line
			(start -1 -1.5)
			(end -1 -1.375)
			(stroke
				(width 0.15)
				(type solid)
			)
			(layer "F.SilkS")
		)
		(fp_line
			(start 1 -1.497)
			(end -1 -1.5)
			(stroke
				(width 0.15)
				(type solid)
			)
			(layer "F.SilkS")
		)
		(fp_line
			(start 1 -1.497)
			(end 1 -1.375)
			(stroke
				(width 0.15)
				(type solid)
			)
			(layer "F.SilkS")
		)
		(fp_line
			(start 1 1.55)
			(end 1 1.4)
			(stroke
				(width 0.15)
				(type solid)
			)
			(layer "F.SilkS")
		)
		(fp_line
			(start 1 1.55)
			(end -1 1.55)
			(stroke
				(width 0.15)
				(type solid)
			)
			(layer "F.SilkS")
		)
		(fp_line
			(start -1 1.55)
			(end -1 1.4)
			(stroke
				(width 0.15)
				(type solid)
			)
			(layer "F.SilkS")
		)
		(fp_circle
			(center -1.44 -1.5)
			(end -1.39 -1.5)
			(stroke
				(width 0.15)
				(type solid)
			)
			(fill yes)
			(layer "F.SilkS")
		)
		(fp_rect
			(start 1.93 -1.7)
			(end -1.93 1.7)
			(stroke
				(width 0.05)
				(type solid)
			)
			(fill no)
			(layer "F.CrtYd")
		)
		(fp_line
			(start -0.45 -1.521)
			(end -0.876 -1.096)
			(stroke
				(width 0.15)
				(type solid)
			)
			(layer "F.Fab")
		)
		(fp_rect
			(start 0.875 1.528)
			(end -0.875 -1.525)
			(stroke
				(width 0.15)
				(type solid)
			)
			(fill no)
			(layer "F.Fab")
		)
		(fp_text user "${REFERENCE}"
			(at -1.93 3.8 90)
			(layer "F.Fab")
			(effects
				(font
					(size 0.7 0.7)
					(thickness 0.15)
				)
				(justify left bottom)
			)
		)
		(fp_text user "Author: Antmicro"
			(at -1.93 5 90)
			(layer "F.Fab")
			(effects
				(font
					(size 0.7 0.7)
					(thickness 0.15)
				)
				(justify left bottom)
			)
		)
		(fp_text user "License: Apache-2.0"
			(at -1.93 6.199 90)
			(layer "F.Fab")
			(effects
				(font
					(size 0.7 0.7)
					(thickness 0.15)
				)
				(justify left bottom)
			)
		)
		(pad "1" smd rect
			(at -1.301 -0.947)
			(size 0.7 1.2)
			(layers "F.Cu" "F.Mask" "F.Paste")
			(net 7 "/CSI/CSIA_5V")
			(pinfunction "OUT")
			(pintype "power_out")
		)
		(pad "2" smd rect
			(at -1.301 0.004)
			(size 0.7 1.2)
			(layers "F.Cu" "F.Mask" "F.Paste")
			(net 1 "GND")
			(pinfunction "GND")
			(pintype "power_in")
		)
		(pad "3" smd rect
			(at -1.301 0.954)
			(size 0.7 1.2)
			(layers "F.Cu" "F.Mask" "F.Paste")
			(net 98 "/CSI/CAM_CTRL.CSIA_FLG")
			(pinfunction "FLG")
			(pintype "output")
		)
		(pad "4" smd rect
			(at 1.299 0.954)
			(size 0.7 1.2)
			(layers "F.Cu" "F.Mask" "F.Paste")
			(net 74 "/CSI/CAM_CTRL.CSIA_PEN")
			(pinfunction "EN")
			(pintype "input")
		)
		(pad "5" smd rect
			(at 1.299 0.004)
			(size 0.7 1.2)
			(layers "F.Cu" "F.Mask" "F.Paste")
			(net 995 "/CSI/CSIA_5V_ISET")
			(pinfunction "ISET")
			(pintype "passive")
		)
		(pad "6" smd rect
			(at 1.299 -0.947)
			(size 0.7 1.2)
			(layers "F.Cu" "F.Mask" "F.Paste")
			(net 5 "+5V")
			(pinfunction "IN")
			(pintype "power_in")
		)
	)
	(footprint "antmicro-footprints:C_0402_1005Metric"
		(layer "F.Cu")
		(at 219.404001 98.010001 180)
		(descr "Capacitor SMD 0402")
		(tags "capacitor SMD 0402")
		(property "Reference" "C110"
			(at -1.319999 1.420001 0)
			(layer "F.SilkS")
			(effects
				(font
					(size 0.7 0.7)
					(thickness 0.15)
				)
				(justify right top)
			)
		)
		(property "Value" "C_100n_0402"
			(at -1.022927 2.155213 0)
			(layer "F.Fab")
			(effects
				(font
					(size 0.7 0.7)
					(thickness 0.15)
				)
				(justify right top)
			)
		)
		(property "Datasheet" "https://www.murata.com/products/productdetail?partno=GRM155R61H104KE14%23"
			(at 0 0 0)
			(layer "F.Fab")
			(hide yes)
			(effects
				(font
					(size 1.27 1.27)
					(thickness 0.15)
				)
			)
		)
		(property "Description" "SMD Multilayer Ceramic Capacitor, 0.1 µF, 50 V, 0402 [1005 Metric], ± 10%, X5R, GRM Series"
			(at 0 0 0)
			(layer "F.Fab")
			(hide yes)
			(effects
				(font
					(size 1.27 1.27)
					(thickness 0.15)
				)
			)
		)
		(property "Manufacturer" "Murata"
			(at 0 0 180)
			(unlocked yes)
			(layer "F.Fab")
			(hide yes)
			(effects
				(font
					(size 1 1)
					(thickness 0.15)
				)
			)
		)
		(property "MPN" "GRM155R61H104KE14D"
			(at 0 0 180)
			(unlocked yes)
			(layer "F.Fab")
			(hide yes)
			(effects
				(font
					(size 1 1)
					(thickness 0.15)
				)
			)
		)
		(property "Val" "100n"
			(at 0 0 180)
			(unlocked yes)
			(layer "F.Fab")
			(hide yes)
			(effects
				(font
					(size 1 1)
					(thickness 0.15)
				)
			)
		)
		(property "License" "Apache-2.0"
			(at 0 0 180)
			(unlocked yes)
			(layer "F.Fab")
			(hide yes)
			(effects
				(font
					(size 1 1)
					(thickness 0.15)
				)
			)
		)
		(property "Author" "Antmicro"
			(at 0 0 180)
			(unlocked yes)
			(layer "F.Fab")
			(hide yes)
			(effects
				(font
					(size 1 1)
					(thickness 0.15)
				)
			)
		)
		(property "Voltage" "50V"
			(at 0 0 180)
			(unlocked yes)
			(layer "F.Fab")
			(hide yes)
			(effects
				(font
					(size 1 1)
					(thickness 0.15)
				)
			)
		)
		(property "Dielectric" "X5R"
			(at 0 0 180)
			(unlocked yes)
			(layer "F.Fab")
			(hide yes)
			(effects
				(font
					(size 1 1)
					(thickness 0.15)
				)
			)
		)
		(sheetname "/Recovery USB/")
		(sheetfile "recovery_usb.kicad_sch")
		(attr smd)
		(fp_rect
			(start -0.925 -0.47)
			(end 0.925 0.47)
			(stroke
				(width 0.05)
				(type default)
			)
			(fill no)
			(layer "F.CrtYd")
		)
		(fp_line
			(start 0.504 0.248)
			(end -0.494 0.248)
			(stroke
				(width 0.15)
				(type solid)
			)
			(layer "F.Fab")
		)
		(fp_line
			(start 0.504 -0.25)
			(end 0.504 0.248)
			(stroke
				(width 0.15)
				(type solid)
			)
			(layer "F.Fab")
		)
		(fp_line
			(start -0.494 0.248)
			(end -0.494 -0.25)
			(stroke
				(width 0.15)
				(type solid)
			)
			(layer "F.Fab")
		)
		(fp_line
			(start -0.494 -0.25)
			(end 0.504 -0.25)
			(stroke
				(width 0.15)
				(type solid)
			)
			(layer "F.Fab")
		)
		(fp_text user "Author: Antmicro"
			(at -0.939 3.399 0)
			(layer "F.Fab")
			(effects
				(font
					(size 0.7 0.7)
					(thickness 0.15)
				)
				(justify right top)
			)
		)
		(fp_text user "License: Apache-2.0"
			(at -0.939 5.799 0)
			(layer "F.Fab")
			(effects
				(font
					(size 0.7 0.7)
					(thickness 0.15)
				)
				(justify right top)
			)
		)
		(fp_text user "${REFERENCE}"
			(at -0.939 4.599 0)
			(layer "F.Fab")
			(effects
				(font
					(size 0.7 0.7)
					(thickness 0.15)
				)
				(justify right top)
			)
		)
		(pad "1" smd roundrect
			(at -0.48 0 180)
			(size 0.59 0.64)
			(layers "F.Cu" "F.Mask" "F.Paste")
			(roundrect_rratio 0.25)
			(net 270 "/Recovery USB/USBC2_CONN_TX2_P")
			(pintype "passive")
		)
		(pad "2" smd roundrect
			(at 0.48 0 180)
			(size 0.59 0.64)
			(layers "F.Cu" "F.Mask" "F.Paste")
			(roundrect_rratio 0.25)
			(net 260 "/Recovery USB/USBC2_TX2_P")
			(pintype "passive")
		)
	)
	(footprint "antmicro-footprints:R_0402_1005Metric"
		(layer "F.Cu")
		(at 144.484391 125.92 -90)
		(descr "Resistor SMD 0402")
		(tags "resistor SMD 0402")
		(property "Reference" "R318"
			(at -4.54 0.422 90)
			(layer "F.SilkS")
			(effects
				(font
					(size 0.7 0.7)
					(thickness 0.15)
				)
				(justify right top)
			)
		)
		(property "Value" "R_15k_0402"
			(at -1.011843 1.772047 90)
			(layer "F.Fab")
			(effects
				(font
					(size 0.7 0.7)
					(thickness 0.15)
				)
				(justify right top)
			)
		)
		(property "Datasheet" "https://www.bourns.com/docs/product-datasheets/cr.pdf"
			(at 0 0 90)
			(layer "F.Fab")
			(hide yes)
			(effects
				(font
					(size 1.27 1.27)
					(thickness 0.15)
				)
			)
		)
		(property "Description" "SMD Chip Resistor, 15 kohm, ± 1%, 62.5 mW, 0402 [1005 Metric], Thick Film, General Purpose"
			(at 0 0 90)
			(layer "F.Fab")
			(hide yes)
			(effects
				(font
					(size 1.27 1.27)
					(thickness 0.15)
				)
			)
		)
		(property "MPN" "CR0402-FX-1502GLF"
			(at 0 0 270)
			(unlocked yes)
			(layer "F.Fab")
			(hide yes)
			(effects
				(font
					(size 1 1)
					(thickness 0.15)
				)
			)
		)
		(property "Manufacturer" "Bourns"
			(at 0 0 270)
			(unlocked yes)
			(layer "F.Fab")
			(hide yes)
			(effects
				(font
					(size 1 1)
					(thickness 0.15)
				)
			)
		)
		(property "License" "Apache-2.0"
			(at 0 0 270)
			(unlocked yes)
			(layer "F.Fab")
			(hide yes)
			(effects
				(font
					(size 1 1)
					(thickness 0.15)
				)
			)
		)
		(property "Author" "Antmicro"
			(at 0 0 270)
			(unlocked yes)
			(layer "F.Fab")
			(hide yes)
			(effects
				(font
					(size 1 1)
					(thickness 0.15)
				)
			)
		)
		(property "Val" "15k"
			(at 0 0 270)
			(unlocked yes)
			(layer "F.Fab")
			(hide yes)
			(effects
				(font
					(size 1 1)
					(thickness 0.15)
				)
			)
		)
		(property "Tolerance" "1%"
			(at 0 0 270)
			(unlocked yes)
			(layer "F.Fab")
			(hide yes)
			(effects
				(font
					(size 1 1)
					(thickness 0.15)
				)
			)
		)
		(component_classes
			(class "DCDC_1V8")
		)
		(sheetname "/DCDC/")
		(sheetfile "dcdc.kicad_sch")
		(attr smd)
		(fp_rect
			(start -0.925 -0.47)
			(end 0.925 0.47)
			(stroke
				(width 0.05)
				(type default)
			)
			(fill no)
			(layer "F.CrtYd")
		)
		(fp_rect
			(start -0.5 -0.25)
			(end 0.5 0.25)
			(stroke
				(width 0.15)
				(type solid)
			)
			(fill no)
			(layer "F.Fab")
		)
		(fp_text user "${REFERENCE}"
			(at -0.95 3.168 90)
			(layer "F.Fab")
			(effects
				(font
					(size 0.7 0.7)
					(thickness 0.15)
				)
				(justify right top)
			)
		)
		(fp_text user "Author: Antmicro"
			(at -0.95 4.169 90)
			(layer "F.Fab")
			(effects
				(font
					(size 0.7 0.7)
					(thickness 0.15)
				)
				(justify right top)
			)
		)
		(fp_text user "License: Apache-2.0"
			(at -0.95 5.169 90)
			(layer "F.Fab")
			(effects
				(font
					(size 0.7 0.7)
					(thickness 0.15)
				)
				(justify right top)
			)
		)
		(pad "1" smd roundrect
			(at -0.48 0 270)
			(size 0.59 0.64)
			(layers "F.Cu" "F.Mask" "F.Paste")
			(roundrect_rratio 0.25)
			(net 1 "GND")
			(pintype "passive")
		)
		(pad "2" smd roundrect
			(at 0.48 0 270)
			(size 0.59 0.64)
			(layers "F.Cu" "F.Mask" "F.Paste")
			(roundrect_rratio 0.25)
			(net 1222 "/DCDC/1V8_FB")
			(pintype "passive")
		)
	)
	(footprint "antmicro-footprints:C_0402_1005Metric"
		(layer "F.Cu")
		(at 89.1 95.9)
		(descr "Capacitor SMD 0402")
		(tags "capacitor SMD 0402")
		(property "Reference" "C340"
			(at -3.82 0.45 0)
			(layer "F.SilkS")
			(effects
				(font
					(size 0.7 0.7)
					(thickness 0.15)
				)
				(justify left bottom)
			)
		)
		(property "Value" "C_100n_0402"
			(at -1.022927 2.155213 0)
			(layer "F.Fab")
			(effects
				(font
					(size 0.7 0.7)
					(thickness 0.15)
				)
				(justify left bottom)
			)
		)
		(property "Datasheet" "https://www.murata.com/products/productdetail?partno=GRM155R61H104KE14%23"
			(at 0 0 0)
			(layer "F.Fab")
			(hide yes)
			(effects
				(font
					(size 1.27 1.27)
					(thickness 0.15)
				)
			)
		)
		(property "Description" "SMD Multilayer Ceramic Capacitor, 0.1 µF, 50 V, 0402 [1005 Metric], ± 10%, X5R, GRM Series"
			(at 0 0 0)
			(layer "F.Fab")
			(hide yes)
			(effects
				(font
					(size 1.27 1.27)
					(thickness 0.15)
				)
			)
		)
		(property "Manufacturer" "Murata"
			(at 0 0 0)
			(unlocked yes)
			(layer "F.Fab")
			(hide yes)
			(effects
				(font
					(size 1 1)
					(thickness 0.15)
				)
			)
		)
		(property "MPN" "GRM155R61H104KE14D"
			(at 0 0 0)
			(unlocked yes)
			(layer "F.Fab")
			(hide yes)
			(effects
				(font
					(size 1 1)
					(thickness 0.15)
				)
			)
		)
		(property "Val" "100n"
			(at 0 0 0)
			(unlocked yes)
			(layer "F.Fab")
			(hide yes)
			(effects
				(font
					(size 1 1)
					(thickness 0.15)
				)
			)
		)
		(property "License" "Apache-2.0"
			(at 0 0 0)
			(unlocked yes)
			(layer "F.Fab")
			(hide yes)
			(effects
				(font
					(size 1 1)
					(thickness 0.15)
				)
			)
		)
		(property "Author" "Antmicro"
			(at 0 0 0)
			(unlocked yes)
			(layer "F.Fab")
			(hide yes)
			(effects
				(font
					(size 1 1)
					(thickness 0.15)
				)
			)
		)
		(property "Voltage" "50V"
			(at 0 0 0)
			(unlocked yes)
			(layer "F.Fab")
			(hide yes)
			(effects
				(font
					(size 1 1)
					(thickness 0.15)
				)
			)
		)
		(property "Dielectric" "X5R"
			(at 0 0 0)
			(unlocked yes)
			(layer "F.Fab")
			(hide yes)
			(effects
				(font
					(size 1 1)
					(thickness 0.15)
				)
			)
		)
		(sheetname "/SoM_IO2/")
		(sheetfile "som_io2.kicad_sch")
		(attr smd)
		(fp_rect
			(start -0.925 -0.47)
			(end 0.925 0.47)
			(stroke
				(width 0.05)
				(type default)
			)
			(fill no)
			(layer "F.CrtYd")
		)
		(fp_line
			(start -0.494 -0.25)
			(end 0.504 -0.25)
			(stroke
				(width 0.15)
				(type solid)
			)
			(layer "F.Fab")
		)
		(fp_line
			(start -0.494 0.248)
			(end -0.494 -0.25)
			(stroke
				(width 0.15)
				(type solid)
			)
			(layer "F.Fab")
		)
		(fp_line
			(start 0.504 -0.25)
			(end 0.504 0.248)
			(stroke
				(width 0.15)
				(type solid)
			)
			(layer "F.Fab")
		)
		(fp_line
			(start 0.504 0.248)
			(end -0.494 0.248)
			(stroke
				(width 0.15)
				(type solid)
			)
			(layer "F.Fab")
		)
		(fp_text user "${REFERENCE}"
			(at -0.939 4.599 0)
			(layer "F.Fab")
			(effects
				(font
					(size 0.7 0.7)
					(thickness 0.15)
				)
				(justify left bottom)
			)
		)
		(fp_text user "License: Apache-2.0"
			(at -0.939 5.799 0)
			(layer "F.Fab")
			(effects
				(font
					(size 0.7 0.7)
					(thickness 0.15)
				)
				(justify left bottom)
			)
		)
		(fp_text user "Author: Antmicro"
			(at -0.939 3.399 0)
			(layer "F.Fab")
			(effects
				(font
					(size 0.7 0.7)
					(thickness 0.15)
				)
				(justify left bottom)
			)
		)
		(pad "1" smd roundrect
			(at -0.48 0)
			(size 0.59 0.64)
			(layers "F.Cu" "F.Mask" "F.Paste")
			(roundrect_rratio 0.25)
			(net 742 "/Expansion connector/DP2.TX2-")
			(pintype "passive")
		)
		(pad "2" smd roundrect
			(at 0.48 0)
			(size 0.59 0.64)
			(layers "F.Cu" "F.Mask" "F.Paste")
			(roundrect_rratio 0.25)
			(net 1260 "/SoM_IO2/DP2.TX2_C-")
			(pintype "passive")
		)
	)
	(footprint "antmicro-footprints:C_0402_1005Metric"
		(layer "F.Cu")
		(at 207.88 134.8 90)
		(descr "Capacitor SMD 0402")
		(tags "capacitor SMD 0402")
		(property "Reference" "C254"
			(at -1.6 13.92 90)
			(layer "F.SilkS")
			(effects
				(font
					(size 0.7 0.7)
					(thickness 0.15)
				)
				(justify left bottom)
			)
		)
		(property "Value" "C_100n_0402"
			(at -1.022927 2.155213 90)
			(layer "F.Fab")
			(effects
				(font
					(size 0.7 0.7)
					(thickness 0.15)
				)
				(justify left bottom)
			)
		)
		(property "Datasheet" "https://www.murata.com/products/productdetail?partno=GRM155R61H104KE14%23"
			(at 0 0 90)
			(layer "F.Fab")
			(hide yes)
			(effects
				(font
					(size 1.27 1.27)
					(thickness 0.15)
				)
			)
		)
		(property "Description" "SMD Multilayer Ceramic Capacitor, 0.1 µF, 50 V, 0402 [1005 Metric], ± 10%, X5R, GRM Series"
			(at 0 0 90)
			(layer "F.Fab")
			(hide yes)
			(effects
				(font
					(size 1.27 1.27)
					(thickness 0.15)
				)
			)
		)
		(property "Manufacturer" "Murata"
			(at 0 0 90)
			(unlocked yes)
			(layer "F.Fab")
			(hide yes)
			(effects
				(font
					(size 1 1)
					(thickness 0.15)
				)
			)
		)
		(property "MPN" "GRM155R61H104KE14D"
			(at 0 0 90)
			(unlocked yes)
			(layer "F.Fab")
			(hide yes)
			(effects
				(font
					(size 1 1)
					(thickness 0.15)
				)
			)
		)
		(property "Val" "100n"
			(at 0 0 90)
			(unlocked yes)
			(layer "F.Fab")
			(hide yes)
			(effects
				(font
					(size 1 1)
					(thickness 0.15)
				)
			)
		)
		(property "License" "Apache-2.0"
			(at 0 0 90)
			(unlocked yes)
			(layer "F.Fab")
			(hide yes)
			(effects
				(font
					(size 1 1)
					(thickness 0.15)
				)
			)
		)
		(property "Author" "Antmicro"
			(at 0 0 90)
			(unlocked yes)
			(layer "F.Fab")
			(hide yes)
			(effects
				(font
					(size 1 1)
					(thickness 0.15)
				)
			)
		)
		(property "Voltage" "50V"
			(at 0 0 90)
			(unlocked yes)
			(layer "F.Fab")
			(hide yes)
			(effects
				(font
					(size 1 1)
					(thickness 0.15)
				)
			)
		)
		(property "Dielectric" "X5R"
			(at 0 0 90)
			(unlocked yes)
			(layer "F.Fab")
			(hide yes)
			(effects
				(font
					(size 1 1)
					(thickness 0.15)
				)
			)
		)
		(sheetname "/USB Hub/")
		(sheetfile "usb_hub.kicad_sch")
		(attr smd)
		(fp_rect
			(start -0.925 -0.47)
			(end 0.925 0.47)
			(stroke
				(width 0.05)
				(type default)
			)
			(fill no)
			(layer "F.CrtYd")
		)
		(fp_line
			(start 0.504 -0.25)
			(end 0.504 0.248)
			(stroke
				(width 0.15)
				(type solid)
			)
			(layer "F.Fab")
		)
		(fp_line
			(start -0.494 -0.25)
			(end 0.504 -0.25)
			(stroke
				(width 0.15)
				(type solid)
			)
			(layer "F.Fab")
		)
		(fp_line
			(start 0.504 0.248)
			(end -0.494 0.248)
			(stroke
				(width 0.15)
				(type solid)
			)
			(layer "F.Fab")
		)
		(fp_line
			(start -0.494 0.248)
			(end -0.494 -0.25)
			(stroke
				(width 0.15)
				(type solid)
			)
			(layer "F.Fab")
		)
		(fp_text user "License: Apache-2.0"
			(at -0.939 5.799 90)
			(layer "F.Fab")
			(effects
				(font
					(size 0.7 0.7)
					(thickness 0.15)
				)
				(justify left bottom)
			)
		)
		(fp_text user "Author: Antmicro"
			(at -0.939 3.399 90)
			(layer "F.Fab")
			(effects
				(font
					(size 0.7 0.7)
					(thickness 0.15)
				)
				(justify left bottom)
			)
		)
		(fp_text user "${REFERENCE}"
			(at -0.939 4.599 90)
			(layer "F.Fab")
			(effects
				(font
					(size 0.7 0.7)
					(thickness 0.15)
				)
				(justify left bottom)
			)
		)
		(pad "1" smd roundrect
			(at -0.48 0 90)
			(size 0.59 0.64)
			(layers "F.Cu" "F.Mask" "F.Paste")
			(roundrect_rratio 0.25)
			(net 684 "/SoM_IO2/USBSS2.TX+")
			(pintype "passive")
		)
		(pad "2" smd roundrect
			(at 0.48 0 90)
			(size 0.59 0.64)
			(layers "F.Cu" "F.Mask" "F.Paste")
			(roundrect_rratio 0.25)
			(net 1133 "/USB Hub/USBSS_RX_P")
			(pintype "passive")
		)
	)
	(footprint "antmicro-footprints:C_0805_2012Metric"
		(layer "F.Cu")
		(at 167.72 79.81 90)
		(descr "Capacitor SMD 0805")
		(tags "capacitor SMD 0805")
		(property "Reference" "C284"
			(at -4.7 0.29 90)
			(layer "F.SilkS")
			(effects
				(font
					(size 0.7 0.7)
					(thickness 0.15)
				)
				(justify left bottom)
			)
		)
		(property "Value" "C_22u_25V_0805"
			(at -2.055717 1.963152 90)
			(layer "F.Fab")
			(effects
				(font
					(size 0.7 0.7)
					(thickness 0.15)
				)
				(justify left bottom)
			)
		)
		(property "Datasheet" "https://product.samsungsem.com/mlcc/CL21A226MAYNNN.do"
			(at 0 0 90)
			(layer "F.Fab")
			(hide yes)
			(effects
				(font
					(size 1.27 1.27)
					(thickness 0.15)
				)
			)
		)
		(property "Description" "SMT Multilayer Ceramic Capacitor, 22uF, +/-20%, 25V, X5R, 0805 [2012 Metric]"
			(at 0 0 90)
			(layer "F.Fab")
			(hide yes)
			(effects
				(font
					(size 1.27 1.27)
					(thickness 0.15)
				)
			)
		)
		(property "MPN" "CL21A226MAYNNNE"
			(at 0 0 90)
			(unlocked yes)
			(layer "F.Fab")
			(hide yes)
			(effects
				(font
					(size 1 1)
					(thickness 0.15)
				)
			)
		)
		(property "Manufacturer" "Samsung Electro-Mechanics"
			(at 0 0 90)
			(unlocked yes)
			(layer "F.Fab")
			(hide yes)
			(effects
				(font
					(size 1 1)
					(thickness 0.15)
				)
			)
		)
		(property "License" "Apache-2.0"
			(at 0 0 90)
			(unlocked yes)
			(layer "F.Fab")
			(hide yes)
			(effects
				(font
					(size 1 1)
					(thickness 0.15)
				)
			)
		)
		(property "Author" "Antmicro"
			(at 0 0 90)
			(unlocked yes)
			(layer "F.Fab")
			(hide yes)
			(effects
				(font
					(size 1 1)
					(thickness 0.15)
				)
			)
		)
		(property "Val" "22u"
			(at 0 0 90)
			(unlocked yes)
			(layer "F.Fab")
			(hide yes)
			(effects
				(font
					(size 1 1)
					(thickness 0.15)
				)
			)
		)
		(property "Voltage" "25V"
			(at 0 0 90)
			(unlocked yes)
			(layer "F.Fab")
			(hide yes)
			(effects
				(font
					(size 1 1)
					(thickness 0.15)
				)
			)
		)
		(property "Dielectric" "X5R"
			(at 0 0 90)
			(unlocked yes)
			(layer "F.Fab")
			(hide yes)
			(effects
				(font
					(size 1 1)
					(thickness 0.15)
				)
			)
		)
		(property "Public" "False"
			(at 0 0 90)
			(unlocked yes)
			(layer "F.Fab")
			(hide yes)
			(effects
				(font
					(size 1 1)
					(thickness 0.15)
				)
			)
		)
		(component_classes
			(class "DCDC_20V")
		)
		(sheetname "/DCDC/")
		(sheetfile "dcdc.kicad_sch")
		(attr smd)
		(fp_line
			(start -0.3 -0.7)
			(end 0.3 -0.7)
			(stroke
				(width 0.15)
				(type solid)
			)
			(layer "F.SilkS")
		)
		(fp_line
			(start -0.3 0.7)
			(end 0.3 0.7)
			(stroke
				(width 0.15)
				(type solid)
			)
			(layer "F.SilkS")
		)
		(fp_rect
			(start 1.95 -0.9)
			(end -1.95 0.9)
			(stroke
				(width 0.05)
				(type default)
			)
			(fill no)
			(layer "F.CrtYd")
		)
		(fp_rect
			(start -0.95 -0.675)
			(end 0.95 0.675)
			(stroke
				(width 0.15)
				(type solid)
			)
			(fill no)
			(layer "F.Fab")
		)
		(fp_text user "License: Apache-2.0"
			(at -1.9 4.947 90)
			(layer "F.Fab")
			(effects
				(font
					(size 0.7 0.7)
					(thickness 0.15)
				)
				(justify left bottom)
			)
		)
		(fp_text user "${REFERENCE}"
			(at -1.9 3.947 90)
			(layer "F.Fab")
			(effects
				(font
					(size 0.7 0.7)
					(thickness 0.15)
				)
				(justify left bottom)
			)
		)
		(fp_text user "Author: Antmicro"
			(at -1.9 5.947 90)
			(layer "F.Fab")
			(effects
				(font
					(size 0.7 0.7)
					(thickness 0.15)
				)
				(justify left bottom)
			)
		)
		(pad "1" smd roundrect
			(at -1.1 0 90)
			(size 1.2 1.3)
			(layers "F.Cu" "F.Mask" "F.Paste")
			(roundrect_rratio 0.25)
			(net 1 "GND")
			(pintype "passive")
		)
		(pad "2" smd roundrect
			(at 1.1 0 90)
			(size 1.2 1.3)
			(layers "F.Cu" "F.Mask" "F.Paste")
			(roundrect_rratio 0.25)
			(net 1105 "/DCDC/20V_OUT")
			(pintype "passive")
		)
	)
	(footprint "antmicro-footprints:Fiducial_1mm_Mask3mm"
		(layer "F.Cu")
		(at 224.69 134.79)
		(descr "Circular Fiducial, 1.5mm bare copper, 3mm soldermask opening")
		(tags "fiducial")
		(property "Reference" "FD3"
			(at 1.31 1.59 0)
			(layer "F.SilkS")
			(effects
				(font
					(size 0.7 0.7)
					(thickness 0.15)
				)
				(justify left bottom)
			)
		)
		(property "Value" "Fiducial_1mm_Mask3mm"
			(at 0 2.603 0)
			(layer "F.Fab")
			(effects
				(font
					(size 0.7 0.7)
					(thickness 0.15)
				)
				(justify left bottom)
			)
		)
		(property "Description" "Fiducial mask"
			(at 0 0 0)
			(layer "F.Fab")
			(hide yes)
			(effects
				(font
					(size 1.27 1.27)
					(thickness 0.15)
				)
			)
		)
		(property "Author" "Antmicro"
			(at 0 0 0)
			(unlocked yes)
			(layer "F.Fab")
			(hide yes)
			(effects
				(font
					(size 1 1)
					(thickness 0.15)
				)
			)
		)
		(property "License" "Apache-2.0"
			(at 0 0 0)
			(unlocked yes)
			(layer "F.Fab")
			(hide yes)
			(effects
				(font
					(size 1 1)
					(thickness 0.15)
				)
			)
		)
		(sheetname "/")
		(sheetfile "jetson-agx-thor-baseboard.kicad_sch")
		(attr exclude_from_pos_files exclude_from_bom)
		(fp_circle
			(center 0 0)
			(end 1.5 0)
			(stroke
				(width 0.05)
				(type solid)
			)
			(fill no)
			(layer "F.CrtYd")
		)
		(fp_circle
			(center 0 0)
			(end 1.5 0)
			(stroke
				(width 0.15)
				(type solid)
			)
			(fill no)
			(layer "F.Fab")
		)
		(fp_text user "${REFERENCE}"
			(at -1.25 4.603 0)
			(layer "F.Fab")
			(effects
				(font
					(size 0.7 0.7)
					(thickness 0.15)
				)
				(justify left bottom)
			)
		)
		(fp_text user "Author: Antmicro"
			(at -1.25 5.803 0)
			(layer "F.Fab")
			(effects
				(font
					(size 0.7 0.7)
					(thickness 0.15)
				)
				(justify left bottom)
			)
		)
		(fp_text user "License: Apache-2.0"
			(at -1.25 7.003 0)
			(layer "F.Fab")
			(effects
				(font
					(size 0.7 0.7)
					(thickness 0.15)
				)
				(justify left bottom)
			)
		)
		(pad "" smd circle
			(at 0 0)
			(size 1 1)
			(layers "F.Cu" "F.Mask")
			(solder_mask_margin 1)
			(clearance 1)
		)
	)
	(footprint "antmicro-footprints:C_0402_1005Metric"
		(layer "F.Cu")
		(at 212.8 63.68 -90)
		(descr "Capacitor SMD 0402")
		(tags "capacitor SMD 0402")
		(property "Reference" "C357"
			(at -3.63 0.24 270)
			(layer "F.SilkS")
			(effects
				(font
					(size 0.7 0.7)
					(thickness 0.15)
				)
				(justify right top)
			)
		)
		(property "Value" "C_100n_0402"
			(at -1.022927 2.155213 90)
			(layer "F.Fab")
			(effects
				(font
					(size 0.7 0.7)
					(thickness 0.15)
				)
				(justify right top)
			)
		)
		(property "Datasheet" "https://www.murata.com/products/productdetail?partno=GRM155R61H104KE14%23"
			(at 0 0 90)
			(layer "F.Fab")
			(hide yes)
			(effects
				(font
					(size 1.27 1.27)
					(thickness 0.15)
				)
			)
		)
		(property "Description" "SMD Multilayer Ceramic Capacitor, 0.1 µF, 50 V, 0402 [1005 Metric], ± 10%, X5R, GRM Series"
			(at 0 0 90)
			(layer "F.Fab")
			(hide yes)
			(effects
				(font
					(size 1.27 1.27)
					(thickness 0.15)
				)
			)
		)
		(property "MPN" "GRM155R61H104KE14D"
			(at 0 0 270)
			(unlocked yes)
			(layer "F.Fab")
			(hide yes)
			(effects
				(font
					(size 1 1)
					(thickness 0.15)
				)
			)
		)
		(property "Val" "100n"
			(at 0 0 270)
			(unlocked yes)
			(layer "F.Fab")
			(hide yes)
			(effects
				(font
					(size 1 1)
					(thickness 0.15)
				)
			)
		)
		(property "Voltage" "50V"
			(at 0 0 270)
			(unlocked yes)
			(layer "F.Fab")
			(hide yes)
			(effects
				(font
					(size 1 1)
					(thickness 0.15)
				)
			)
		)
		(property "Dielectric" "X5R"
			(at 0 0 270)
			(unlocked yes)
			(layer "F.Fab")
			(hide yes)
			(effects
				(font
					(size 1 1)
					(thickness 0.15)
				)
			)
		)
		(property "Manufacturer" "Murata"
			(at 0 0 270)
			(unlocked yes)
			(layer "F.Fab")
			(hide yes)
			(effects
				(font
					(size 1 1)
					(thickness 0.15)
				)
			)
		)
		(property "License" "Apache-2.0"
			(at 0 0 270)
			(unlocked yes)
			(layer "F.Fab")
			(hide yes)
			(effects
				(font
					(size 1 1)
					(thickness 0.15)
				)
			)
		)
		(property "Author" "Antmicro"
			(at 0 0 270)
			(unlocked yes)
			(layer "F.Fab")
			(hide yes)
			(effects
				(font
					(size 1 1)
					(thickness 0.15)
				)
			)
		)
		(sheetname "/Power/")
		(sheetfile "power.kicad_sch")
		(attr smd)
		(fp_rect
			(start -0.925 -0.47)
			(end 0.925 0.47)
			(stroke
				(width 0.05)
				(type default)
			)
			(fill no)
			(layer "F.CrtYd")
		)
		(fp_line
			(start -0.494 0.248)
			(end -0.494 -0.25)
			(stroke
				(width 0.15)
				(type solid)
			)
			(layer "F.Fab")
		)
		(fp_line
			(start 0.504 0.248)
			(end -0.494 0.248)
			(stroke
				(width 0.15)
				(type solid)
			)
			(layer "F.Fab")
		)
		(fp_line
			(start -0.494 -0.25)
			(end 0.504 -0.25)
			(stroke
				(width 0.15)
				(type solid)
			)
			(layer "F.Fab")
		)
		(fp_line
			(start 0.504 -0.25)
			(end 0.504 0.248)
			(stroke
				(width 0.15)
				(type solid)
			)
			(layer "F.Fab")
		)
		(fp_text user "Author: Antmicro"
			(at -0.939 3.399 90)
			(layer "F.Fab")
			(effects
				(font
					(size 0.7 0.7)
					(thickness 0.15)
				)
				(justify right top)
			)
		)
		(fp_text user "${REFERENCE}"
			(at -0.939 4.599 90)
			(layer "F.Fab")
			(effects
				(font
					(size 0.7 0.7)
					(thickness 0.15)
				)
				(justify right top)
			)
		)
		(fp_text user "License: Apache-2.0"
			(at -0.939 5.799 90)
			(layer "F.Fab")
			(effects
				(font
					(size 0.7 0.7)
					(thickness 0.15)
				)
				(justify right top)
			)
		)
		(pad "1" smd roundrect
			(at -0.48 0 270)
			(size 0.59 0.64)
			(layers "F.Cu" "F.Mask" "F.Paste")
			(roundrect_rratio 0.25)
			(net 1 "GND")
			(pintype "passive")
		)
		(pad "2" smd roundrect
			(at 0.48 0 270)
			(size 0.59 0.64)
			(layers "F.Cu" "F.Mask" "F.Paste")
			(roundrect_rratio 0.25)
			(net 1383 "VCC_NO_OVP")
			(pintype "passive")
		)
	)
	(footprint "antmicro-footprints:Conn_JST_SH_1x4_BM04B-SRSS-TB-LF-SN"
		(layer "F.Cu")
		(at 200.15 111.6 180)
		(property "Reference" "J21"
			(at -1.75 -3.3 0)
			(layer "F.SilkS")
			(effects
				(font
					(size 0.7 0.7)
					(thickness 0.15)
				)
				(justify right top)
			)
		)
		(property "Value" "JST_SH_1x4_BM04B-SRSS-TB-LF-SN"
			(at -3.25 5 0)
			(layer "F.Fab")
			(effects
				(font
					(size 0.7 0.7)
					(thickness 0.15)
				)
				(justify right top)
			)
		)
		(property "Datasheet" "https://www.jst-mfg.com/product/pdf/eng/eSH.pdf"
			(at 0 0 0)
			(layer "F.Fab")
			(hide yes)
			(effects
				(font
					(size 1.27 1.27)
					(thickness 0.15)
				)
			)
		)
		(property "Description" "Pin Header, Top Entry, Wire-to-Board, 1 mm, 1 Rows, 4 Contacts, Surface Mount, SR"
			(at 0 0 0)
			(layer "F.Fab")
			(hide yes)
			(effects
				(font
					(size 1.27 1.27)
					(thickness 0.15)
				)
			)
		)
		(property "MPN" "BM04B-SRSS-TB(LF)(SN) "
			(at 0 0 180)
			(unlocked yes)
			(layer "F.Fab")
			(hide yes)
			(effects
				(font
					(size 1 1)
					(thickness 0.15)
				)
			)
		)
		(property "Manufacturer" "JST Automotive Connectors"
			(at 0 0 180)
			(unlocked yes)
			(layer "F.Fab")
			(hide yes)
			(effects
				(font
					(size 1 1)
					(thickness 0.15)
				)
			)
		)
		(property "Author" "Antmicro"
			(at 0 0 180)
			(unlocked yes)
			(layer "F.Fab")
			(hide yes)
			(effects
				(font
					(size 1 1)
					(thickness 0.15)
				)
			)
		)
		(property "License" "Apache-2.0"
			(at 0 0 180)
			(unlocked yes)
			(layer "F.Fab")
			(hide yes)
			(effects
				(font
					(size 1 1)
					(thickness 0.15)
				)
			)
		)
		(sheetname "/SoM_Power/")
		(sheetfile "som_power.kicad_sch")
		(attr smd exclude_from_pos_files exclude_from_bom dnp)
		(fp_line
			(start 1.774 -1.7)
			(end 1.774 1.702)
			(stroke
				(width 0.15)
				(type solid)
			)
			(layer "F.SilkS")
		)
		(fp_line
			(start -0.251 2.999)
			(end -1.125 2.999)
			(stroke
				(width 0.15)
				(type solid)
			)
			(layer "F.SilkS")
		)
		(fp_line
			(start -0.251 -2.999)
			(end -1.125 -2.999)
			(stroke
				(width 0.15)
				(type solid)
			)
			(layer "F.SilkS")
		)
		(fp_line
			(start -1.125 2.999)
			(end -1.125 2.201)
			(stroke
				(width 0.15)
				(type solid)
			)
			(layer "F.SilkS")
		)
		(fp_line
			(start -1.125 -2.999)
			(end -1.125 -2.201)
			(stroke
				(width 0.15)
				(type solid)
			)
			(layer "F.SilkS")
		)
		(fp_circle
			(center -1.6 -2.1)
			(end -1.55 -2.1)
			(stroke
				(width 0.15)
				(type solid)
			)
			(fill yes)
			(layer "F.SilkS")
		)
		(fp_rect
			(start -2.05 -3.95)
			(end 2.05 3.95)
			(stroke
				(width 0.05)
				(type solid)
			)
			(fill no)
			(layer "F.CrtYd")
		)
		(fp_rect
			(start -1.8 -3)
			(end 1.8 3)
			(stroke
				(width 0.15)
				(type solid)
			)
			(fill no)
			(layer "F.Fab")
		)
		(fp_text user "License: Apache-2.0"
			(at -3.25 9.4 0)
			(layer "F.Fab")
			(effects
				(font
					(size 0.7 0.7)
					(thickness 0.15)
				)
				(justify right top)
			)
		)
		(fp_text user "Author: Antmicro"
			(at -3.25 7 0)
			(layer "F.Fab")
			(effects
				(font
					(size 0.7 0.7)
					(thickness 0.15)
				)
				(justify right top)
			)
		)
		(fp_text user "${REFERENCE}"
			(at -3.25 8.2 0)
			(layer "F.Fab")
			(effects
				(font
					(size 0.7 0.7)
					(thickness 0.15)
				)
				(justify right top)
			)
		)
		(pad "1" smd roundrect
			(at -1.45 -1.5 90)
			(size 0.6 1.55)
			(layers "F.Cu" "F.Mask" "F.Paste")
			(roundrect_rratio 0.25)
			(net 1 "GND")
			(pintype "passive")
		)
		(pad "2" smd roundrect
			(at -1.45 -0.5 90)
			(size 0.6 1.55)
			(layers "F.Cu" "F.Mask" "F.Paste")
			(roundrect_rratio 0.25)
			(net 495 "/SoM_Power/~{FORCE_RECOVERY}")
			(pintype "passive")
		)
		(pad "3" smd roundrect
			(at -1.45 0.5 90)
			(size 0.6 1.55)
			(layers "F.Cu" "F.Mask" "F.Paste")
			(roundrect_rratio 0.25)
			(net 702 "/SoM_Power/~{SYS_RESET}")
			(pintype "passive")
		)
		(pad "4" smd roundrect
			(at -1.45 1.5 90)
			(size 0.6 1.55)
			(layers "F.Cu" "F.Mask" "F.Paste")
			(roundrect_rratio 0.25)
			(net 610 "/SoM_Power/~{PWR_BTN}")
			(pintype "passive")
		)
		(pad "MP" smd roundrect
			(at 1.075 -2.8 90)
			(size 1.2 1.8)
			(layers "F.Cu" "F.Mask" "F.Paste")
			(roundrect_rratio 0.25)
			(net 1 "GND")
			(pintype "passive")
		)
		(pad "MP" smd roundrect
			(at 1.075 2.8 90)
			(size 1.2 1.8)
			(layers "F.Cu" "F.Mask" "F.Paste")
			(roundrect_rratio 0.25)
			(net 1 "GND")
			(pintype "passive")
		)
	)
	(footprint "antmicro-footprints:R_0402_1005Metric"
		(layer "F.Cu")
		(at 210.114132 94.642 180)
		(descr "Resistor SMD 0402")
		(tags "resistor SMD 0402")
		(property "Reference" "R121"
			(at 0.914132 -0.558 0)
			(layer "F.SilkS")
			(effects
				(font
					(size 0.7 0.7)
					(thickness 0.15)
				)
				(justify right top)
			)
		)
		(property "Value" "R_0R_0402"
			(at -1.011843 1.772047 0)
			(layer "F.Fab")
			(effects
				(font
					(size 0.7 0.7)
					(thickness 0.15)
				)
				(justify right top)
			)
		)
		(property "Datasheet" "https://industrial.panasonic.com/cdbs/www-data/pdf/RDA0000/AOA0000C301.pdf"
			(at 0 0 0)
			(layer "F.Fab")
			(hide yes)
			(effects
				(font
					(size 1.27 1.27)
					(thickness 0.15)
				)
			)
		)
		(property "Description" "SMD Chip Resistor, Jumper, 0 ohm, 100 mW, 0402 [1005 Metric], Thick Film, General Purpose"
			(at 0 0 0)
			(layer "F.Fab")
			(hide yes)
			(effects
				(font
					(size 1.27 1.27)
					(thickness 0.15)
				)
			)
		)
		(property "Manufacturer" "Panasonic"
			(at 0 0 180)
			(unlocked yes)
			(layer "F.Fab")
			(hide yes)
			(effects
				(font
					(size 1 1)
					(thickness 0.15)
				)
			)
		)
		(property "MPN" "ERJ2GE0R00X"
			(at 0 0 180)
			(unlocked yes)
			(layer "F.Fab")
			(hide yes)
			(effects
				(font
					(size 1 1)
					(thickness 0.15)
				)
			)
		)
		(property "Val" "0R"
			(at 0 0 180)
			(unlocked yes)
			(layer "F.Fab")
			(hide yes)
			(effects
				(font
					(size 1 1)
					(thickness 0.15)
				)
			)
		)
		(property "License" "Apache-2.0"
			(at 0 0 180)
			(unlocked yes)
			(layer "F.Fab")
			(hide yes)
			(effects
				(font
					(size 1 1)
					(thickness 0.15)
				)
			)
		)
		(property "Author" "Antmicro"
			(at 0 0 180)
			(unlocked yes)
			(layer "F.Fab")
			(hide yes)
			(effects
				(font
					(size 1 1)
					(thickness 0.15)
				)
			)
		)
		(property "Tolerance" "~"
			(at 0 0 180)
			(unlocked yes)
			(layer "F.Fab")
			(hide yes)
			(effects
				(font
					(size 1 1)
					(thickness 0.15)
				)
			)
		)
		(property "Current" "1A"
			(at 0 0 180)
			(unlocked yes)
			(layer "F.Fab")
			(hide yes)
			(effects
				(font
					(size 1 1)
					(thickness 0.15)
				)
			)
		)
		(sheetname "/USB DP Alt mode/")
		(sheetfile "usb_dp.kicad_sch")
		(attr smd exclude_from_pos_files exclude_from_bom dnp)
		(fp_rect
			(start -0.925 -0.47)
			(end 0.925 0.47)
			(stroke
				(width 0.05)
				(type default)
			)
			(fill no)
			(layer "F.CrtYd")
		)
		(fp_rect
			(start -0.5 -0.25)
			(end 0.5 0.25)
			(stroke
				(width 0.15)
				(type solid)
			)
			(fill no)
			(layer "F.Fab")
		)
		(fp_text user "${REFERENCE}"
			(at -0.95 3.168 0)
			(layer "F.Fab")
			(effects
				(font
					(size 0.7 0.7)
					(thickness 0.15)
				)
				(justify right top)
			)
		)
		(fp_text user "Author: Antmicro"
			(at -0.95 4.169 0)
			(layer "F.Fab")
			(effects
				(font
					(size 0.7 0.7)
					(thickness 0.15)
				)
				(justify right top)
			)
		)
		(fp_text user "License: Apache-2.0"
			(at -0.95 5.169 0)
			(layer "F.Fab")
			(effects
				(font
					(size 0.7 0.7)
					(thickness 0.15)
				)
				(justify right top)
			)
		)
		(pad "1" smd roundrect
			(at -0.48 0 180)
			(size 0.59 0.64)
			(layers "F.Cu" "F.Mask" "F.Paste")
			(roundrect_rratio 0.25)
			(net 943 "/USB DP Alt mode/USBC1_CTL0")
			(pintype "passive")
		)
		(pad "2" smd roundrect
			(at 0.48 0 180)
			(size 0.59 0.64)
			(layers "F.Cu" "F.Mask" "F.Paste")
			(roundrect_rratio 0.25)
			(net 850 "/I2C_{SYS}.SDA")
			(pintype "passive")
		)
	)
	(footprint "antmicro-footprints:C_0402_1005Metric"
		(layer "F.Cu")
		(at 213.5 123.68 180)
		(descr "Capacitor SMD 0402")
		(tags "capacitor SMD 0402")
		(property "Reference" "C99"
			(at -1.1 1.28 0)
			(layer "F.SilkS")
			(effects
				(font
					(size 0.7 0.7)
					(thickness 0.15)
				)
				(justify right top)
			)
		)
		(property "Value" "C_100n_0402"
			(at -1.022927 2.155213 0)
			(layer "F.Fab")
			(effects
				(font
					(size 0.7 0.7)
					(thickness 0.15)
				)
				(justify right top)
			)
		)
		(property "Datasheet" "https://www.murata.com/products/productdetail?partno=GRM155R61H104KE14%23"
			(at 0 0 0)
			(layer "F.Fab")
			(hide yes)
			(effects
				(font
					(size 1.27 1.27)
					(thickness 0.15)
				)
			)
		)
		(property "Description" "SMD Multilayer Ceramic Capacitor, 0.1 µF, 50 V, 0402 [1005 Metric], ± 10%, X5R, GRM Series"
			(at 0 0 0)
			(layer "F.Fab")
			(hide yes)
			(effects
				(font
					(size 1.27 1.27)
					(thickness 0.15)
				)
			)
		)
		(property "MPN" "GRM155R61H104KE14D"
			(at 0 0 180)
			(unlocked yes)
			(layer "F.Fab")
			(hide yes)
			(effects
				(font
					(size 1 1)
					(thickness 0.15)
				)
			)
		)
		(property "Val" "100n"
			(at 0 0 180)
			(unlocked yes)
			(layer "F.Fab")
			(hide yes)
			(effects
				(font
					(size 1 1)
					(thickness 0.15)
				)
			)
		)
		(property "Voltage" "50V"
			(at 0 0 180)
			(unlocked yes)
			(layer "F.Fab")
			(hide yes)
			(effects
				(font
					(size 1 1)
					(thickness 0.15)
				)
			)
		)
		(property "Dielectric" "X5R"
			(at 0 0 180)
			(unlocked yes)
			(layer "F.Fab")
			(hide yes)
			(effects
				(font
					(size 1 1)
					(thickness 0.15)
				)
			)
		)
		(property "Manufacturer" "Murata"
			(at 0 0 180)
			(unlocked yes)
			(layer "F.Fab")
			(hide yes)
			(effects
				(font
					(size 1 1)
					(thickness 0.15)
				)
			)
		)
		(property "License" "Apache-2.0"
			(at 0 0 180)
			(unlocked yes)
			(layer "F.Fab")
			(hide yes)
			(effects
				(font
					(size 1 1)
					(thickness 0.15)
				)
			)
		)
		(property "Author" "Antmicro"
			(at 0 0 180)
			(unlocked yes)
			(layer "F.Fab")
			(hide yes)
			(effects
				(font
					(size 1 1)
					(thickness 0.15)
				)
			)
		)
		(sheetname "/USB Hub/")
		(sheetfile "usb_hub.kicad_sch")
		(attr smd)
		(fp_poly
			(pts
				(xy -0.925 -0.47) (xy 0.925 -0.47) (xy 0.925 0.47) (xy -0.925 0.47)
			)
			(stroke
				(width 0.05)
				(type default)
			)
			(fill no)
			(layer "F.CrtYd")
		)
		(fp_line
			(start 0.504 0.248)
			(end -0.494 0.248)
			(stroke
				(width 0.15)
				(type solid)
			)
			(layer "F.Fab")
		)
		(fp_line
			(start 0.504 -0.25)
			(end 0.504 0.248)
			(stroke
				(width 0.15)
				(type solid)
			)
			(layer "F.Fab")
		)
		(fp_line
			(start -0.494 0.248)
			(end -0.494 -0.25)
			(stroke
				(width 0.15)
				(type solid)
			)
			(layer "F.Fab")
		)
		(fp_line
			(start -0.494 -0.25)
			(end 0.504 -0.25)
			(stroke
				(width 0.15)
				(type solid)
			)
			(layer "F.Fab")
		)
		(fp_text user "${REFERENCE}"
			(at -0.939 4.599 0)
			(layer "F.Fab")
			(effects
				(font
					(size 0.7 0.7)
					(thickness 0.15)
				)
				(justify right top)
			)
		)
		(fp_text user "Author: Antmicro"
			(at -0.939 3.399 0)
			(layer "F.Fab")
			(effects
				(font
					(size 0.7 0.7)
					(thickness 0.15)
				)
				(justify right top)
			)
		)
		(fp_text user "License: Apache-2.0"
			(at -0.939 5.799 0)
			(layer "F.Fab")
			(effects
				(font
					(size 0.7 0.7)
					(thickness 0.15)
				)
				(justify right top)
			)
		)
		(pad "1" smd roundrect
			(at -0.48 0 180)
			(size 0.59 0.64)
			(layers "F.Cu" "F.Mask" "F.Paste")
			(roundrect_rratio 0.25)
			(net 1 "GND")
			(pintype "passive")
		)
		(pad "2" smd roundrect
			(at 0.48 0 180)
			(size 0.59 0.64)
			(layers "F.Cu" "F.Mask" "F.Paste")
			(roundrect_rratio 0.25)
			(net 282 "+1V15")
			(pintype "passive")
		)
	)
	(footprint "antmicro-footprints:TP_SMD_0.75mm"
		(layer "F.Cu")
		(at 215.9 98 90)
		(property "Reference" "TP45"
			(at 1.3 2.2 180)
			(layer "F.SilkS")
			(effects
				(font
					(size 0.7 0.7)
					(thickness 0.15)
				)
				(justify right top)
			)
		)
		(property "Value" "TP_0.75mm_SMD"
			(at 0 1.2 90)
			(layer "F.Fab")
			(effects
				(font
					(size 0.7 0.7)
					(thickness 0.15)
				)
				(justify left bottom)
			)
		)
		(property "Description" "SMT test point"
			(at 0 0 90)
			(layer "F.Fab")
			(hide yes)
			(effects
				(font
					(size 1.27 1.27)
					(thickness 0.15)
				)
			)
		)
		(property "MPN" ""
			(at 0 0 90)
			(unlocked yes)
			(layer "F.Fab")
			(hide yes)
			(effects
				(font
					(size 1 1)
					(thickness 0.15)
				)
			)
		)
		(property "Manufacturer" ""
			(at 0 0 90)
			(unlocked yes)
			(layer "F.Fab")
			(hide yes)
			(effects
				(font
					(size 1 1)
					(thickness 0.15)
				)
			)
		)
		(property "Author" "Antmicro"
			(at 0 0 90)
			(unlocked yes)
			(layer "F.Fab")
			(hide yes)
			(effects
				(font
					(size 1 1)
					(thickness 0.15)
				)
			)
		)
		(property "License" "Apache-2.0"
			(at 0 0 90)
			(unlocked yes)
			(layer "F.Fab")
			(hide yes)
			(effects
				(font
					(size 1 1)
					(thickness 0.15)
				)
			)
		)
		(sheetname "/Recovery USB/")
		(sheetfile "recovery_usb.kicad_sch")
		(attr exclude_from_pos_files exclude_from_bom)
		(fp_circle
			(center 0 0)
			(end 0.475 0)
			(stroke
				(width 0.05)
				(type default)
			)
			(fill no)
			(layer "F.CrtYd")
		)
		(fp_text user "${REFERENCE}"
			(at -0.4 2.7 90)
			(layer "F.Fab")
			(effects
				(font
					(size 0.7 0.7)
					(thickness 0.15)
				)
				(justify left bottom)
			)
		)
		(fp_text user "License: Apache-2.0"
			(at -0.4 5.101 90)
			(layer "F.Fab")
			(effects
				(font
					(size 0.7 0.7)
					(thickness 0.15)
				)
				(justify left bottom)
			)
		)
		(fp_text user "Author: Antmicro"
			(at -0.4 3.901 90)
			(layer "F.Fab")
			(effects
				(font
					(size 0.7 0.7)
					(thickness 0.15)
				)
				(justify left bottom)
			)
		)
		(pad "1" smd circle
			(at 0 0 90)
			(size 0.75 0.75)
			(layers "F.Cu" "F.Mask")
			(net 889 "/Recovery USB/USBC2_ID")
			(pinfunction "1")
			(pintype "passive")
		)
	)
	(footprint "antmicro-footprints:C_0805_2012Metric"
		(layer "F.Cu")
		(at 169.53 93.32 -90)
		(descr "Capacitor SMD 0805")
		(tags "capacitor SMD 0805")
		(property "Reference" "C259"
			(at 1.745 0.425 90)
			(layer "F.SilkS")
			(effects
				(font
					(size 0.7 0.7)
					(thickness 0.15)
				)
				(justify right top)
			)
		)
		(property "Value" "C_22u_25V_0805"
			(at -2.055717 1.963152 90)
			(layer "F.Fab")
			(effects
				(font
					(size 0.7 0.7)
					(thickness 0.15)
				)
				(justify right top)
			)
		)
		(property "Datasheet" "https://product.samsungsem.com/mlcc/CL21A226MAYNNN.do"
			(at 0 0 90)
			(layer "F.Fab")
			(hide yes)
			(effects
				(font
					(size 1.27 1.27)
					(thickness 0.15)
				)
			)
		)
		(property "Description" "SMT Multilayer Ceramic Capacitor, 22uF, +/-20%, 25V, X5R, 0805 [2012 Metric]"
			(at 0 0 90)
			(layer "F.Fab")
			(hide yes)
			(effects
				(font
					(size 1.27 1.27)
					(thickness 0.15)
				)
			)
		)
		(property "MPN" "CL21A226MAYNNNE"
			(at 0 0 270)
			(unlocked yes)
			(layer "F.Fab")
			(hide yes)
			(effects
				(font
					(size 1 1)
					(thickness 0.15)
				)
			)
		)
		(property "Manufacturer" "Samsung Electro-Mechanics"
			(at 0 0 270)
			(unlocked yes)
			(layer "F.Fab")
			(hide yes)
			(effects
				(font
					(size 1 1)
					(thickness 0.15)
				)
			)
		)
		(property "License" "Apache-2.0"
			(at 0 0 270)
			(unlocked yes)
			(layer "F.Fab")
			(hide yes)
			(effects
				(font
					(size 1 1)
					(thickness 0.15)
				)
			)
		)
		(property "Author" "Antmicro"
			(at 0 0 270)
			(unlocked yes)
			(layer "F.Fab")
			(hide yes)
			(effects
				(font
					(size 1 1)
					(thickness 0.15)
				)
			)
		)
		(property "Val" "22u"
			(at 0 0 270)
			(unlocked yes)
			(layer "F.Fab")
			(hide yes)
			(effects
				(font
					(size 1 1)
					(thickness 0.15)
				)
			)
		)
		(property "Voltage" "25V"
			(at 0 0 270)
			(unlocked yes)
			(layer "F.Fab")
			(hide yes)
			(effects
				(font
					(size 1 1)
					(thickness 0.15)
				)
			)
		)
		(property "Dielectric" "X5R"
			(at 0 0 270)
			(unlocked yes)
			(layer "F.Fab")
			(hide yes)
			(effects
				(font
					(size 1 1)
					(thickness 0.15)
				)
			)
		)
		(property "Public" "False"
			(at 0 0 270)
			(unlocked yes)
			(layer "F.Fab")
			(hide yes)
			(effects
				(font
					(size 1 1)
					(thickness 0.15)
				)
			)
		)
		(component_classes
			(class "DCDC_SOM")
		)
		(sheetname "/DCDC/")
		(sheetfile "dcdc.kicad_sch")
		(attr smd)
		(fp_line
			(start -0.3 0.7)
			(end 0.3 0.7)
			(stroke
				(width 0.15)
				(type solid)
			)
			(layer "F.SilkS")
		)
		(fp_line
			(start -0.3 -0.7)
			(end 0.3 -0.7)
			(stroke
				(width 0.15)
				(type solid)
			)
			(layer "F.SilkS")
		)
		(fp_rect
			(start 1.95 -0.9)
			(end -1.95 0.9)
			(stroke
				(width 0.05)
				(type default)
			)
			(fill no)
			(layer "F.CrtYd")
		)
		(fp_rect
			(start -0.95 -0.675)
			(end 0.95 0.675)
			(stroke
				(width 0.15)
				(type solid)
			)
			(fill no)
			(layer "F.Fab")
		)
		(fp_text user "License: Apache-2.0"
			(at -1.9 4.947 90)
			(layer "F.Fab")
			(effects
				(font
					(size 0.7 0.7)
					(thickness 0.15)
				)
				(justify right top)
			)
		)
		(fp_text user "Author: Antmicro"
			(at -1.9 5.947 90)
			(layer "F.Fab")
			(effects
				(font
					(size 0.7 0.7)
					(thickness 0.15)
				)
				(justify right top)
			)
		)
		(fp_text user "${REFERENCE}"
			(at -1.9 3.947 90)
			(layer "F.Fab")
			(effects
				(font
					(size 0.7 0.7)
					(thickness 0.15)
				)
				(justify right top)
			)
		)
		(pad "1" smd roundrect
			(at -1.1 0 270)
			(size 1.2 1.3)
			(layers "F.Cu" "F.Mask" "F.Paste")
			(roundrect_rratio 0.25)
			(net 1 "GND")
			(pintype "passive")
		)
		(pad "2" smd roundrect
			(at 1.1 0 270)
			(size 1.2 1.3)
			(layers "F.Cu" "F.Mask" "F.Paste")
			(roundrect_rratio 0.25)
			(net 903 "/DCDC/16V_OUT")
			(pintype "passive")
		)
	)
	(footprint "antmicro-footprints:C_0402_1005Metric"
		(layer "F.Cu")
		(at 89.1 98.8)
		(descr "Capacitor SMD 0402")
		(tags "capacitor SMD 0402")
		(property "Reference" "C341"
			(at -3.82 0.449999 0)
			(layer "F.SilkS")
			(effects
				(font
					(size 0.7 0.7)
					(thickness 0.15)
				)
				(justify left bottom)
			)
		)
		(property "Value" "C_100n_0402"
			(at -1.022927 2.155213 0)
			(layer "F.Fab")
			(effects
				(font
					(size 0.7 0.7)
					(thickness 0.15)
				)
				(justify left bottom)
			)
		)
		(property "Datasheet" "https://www.murata.com/products/productdetail?partno=GRM155R61H104KE14%23"
			(at 0 0 0)
			(layer "F.Fab")
			(hide yes)
			(effects
				(font
					(size 1.27 1.27)
					(thickness 0.15)
				)
			)
		)
		(property "Description" "SMD Multilayer Ceramic Capacitor, 0.1 µF, 50 V, 0402 [1005 Metric], ± 10%, X5R, GRM Series"
			(at 0 0 0)
			(layer "F.Fab")
			(hide yes)
			(effects
				(font
					(size 1.27 1.27)
					(thickness 0.15)
				)
			)
		)
		(property "Manufacturer" "Murata"
			(at 0 0 0)
			(unlocked yes)
			(layer "F.Fab")
			(hide yes)
			(effects
				(font
					(size 1 1)
					(thickness 0.15)
				)
			)
		)
		(property "MPN" "GRM155R61H104KE14D"
			(at 0 0 0)
			(unlocked yes)
			(layer "F.Fab")
			(hide yes)
			(effects
				(font
					(size 1 1)
					(thickness 0.15)
				)
			)
		)
		(property "Val" "100n"
			(at 0 0 0)
			(unlocked yes)
			(layer "F.Fab")
			(hide yes)
			(effects
				(font
					(size 1 1)
					(thickness 0.15)
				)
			)
		)
		(property "License" "Apache-2.0"
			(at 0 0 0)
			(unlocked yes)
			(layer "F.Fab")
			(hide yes)
			(effects
				(font
					(size 1 1)
					(thickness 0.15)
				)
			)
		)
		(property "Author" "Antmicro"
			(at 0 0 0)
			(unlocked yes)
			(layer "F.Fab")
			(hide yes)
			(effects
				(font
					(size 1 1)
					(thickness 0.15)
				)
			)
		)
		(property "Voltage" "50V"
			(at 0 0 0)
			(unlocked yes)
			(layer "F.Fab")
			(hide yes)
			(effects
				(font
					(size 1 1)
					(thickness 0.15)
				)
			)
		)
		(property "Dielectric" "X5R"
			(at 0 0 0)
			(unlocked yes)
			(layer "F.Fab")
			(hide yes)
			(effects
				(font
					(size 1 1)
					(thickness 0.15)
				)
			)
		)
		(sheetname "/SoM_IO2/")
		(sheetfile "som_io2.kicad_sch")
		(attr smd)
		(fp_poly
			(pts
				(xy -0.925 -0.47) (xy 0.925 -0.47) (xy 0.925 0.47) (xy -0.925 0.47)
			)
			(stroke
				(width 0.05)
				(type default)
			)
			(fill no)
			(layer "F.CrtYd")
		)
		(fp_line
			(start -0.494 -0.25)
			(end 0.504 -0.25)
			(stroke
				(width 0.15)
				(type solid)
			)
			(layer "F.Fab")
		)
		(fp_line
			(start -0.494 0.248)
			(end -0.494 -0.25)
			(stroke
				(width 0.15)
				(type solid)
			)
			(layer "F.Fab")
		)
		(fp_line
			(start 0.504 -0.25)
			(end 0.504 0.248)
			(stroke
				(width 0.15)
				(type solid)
			)
			(layer "F.Fab")
		)
		(fp_line
			(start 0.504 0.248)
			(end -0.494 0.248)
			(stroke
				(width 0.15)
				(type solid)
			)
			(layer "F.Fab")
		)
		(fp_text user "License: Apache-2.0"
			(at -0.939 5.799 0)
			(layer "F.Fab")
			(effects
				(font
					(size 0.7 0.7)
					(thickness 0.15)
				)
				(justify left bottom)
			)
		)
		(fp_text user "Author: Antmicro"
			(at -0.939 3.399 0)
			(layer "F.Fab")
			(effects
				(font
					(size 0.7 0.7)
					(thickness 0.15)
				)
				(justify left bottom)
			)
		)
		(fp_text user "${REFERENCE}"
			(at -0.939 4.599 0)
			(layer "F.Fab")
			(effects
				(font
					(size 0.7 0.7)
					(thickness 0.15)
				)
				(justify left bottom)
			)
		)
		(pad "1" smd roundrect
			(at -0.48 0)
			(size 0.59 0.64)
			(layers "F.Cu" "F.Mask" "F.Paste")
			(roundrect_rratio 0.25)
			(net 631 "/Expansion connector/DP2.TX3-")
			(pintype "passive")
		)
		(pad "2" smd roundrect
			(at 0.48 0)
			(size 0.59 0.64)
			(layers "F.Cu" "F.Mask" "F.Paste")
			(roundrect_rratio 0.25)
			(net 1261 "/SoM_IO2/DP2.TX3_C-")
			(pintype "passive")
		)
	)
	(footprint "antmicro-footprints:R_0402_1005Metric"
		(layer "F.Cu")
		(at 187.25 57.25 -90)
		(descr "Resistor SMD 0402")
		(tags "resistor SMD 0402")
		(property "Reference" "R237"
			(at -1.45 1.35 90)
			(layer "F.SilkS")
			(effects
				(font
					(size 0.7 0.7)
					(thickness 0.15)
				)
				(justify right top)
			)
		)
		(property "Value" "R_10k_0402"
			(at -1.011843 1.772047 90)
			(layer "F.Fab")
			(effects
				(font
					(size 0.7 0.7)
					(thickness 0.15)
				)
				(justify right top)
			)
		)
		(property "Datasheet" "https://www.bourns.com/docs/product-datasheets/cr.pdf"
			(at 0 0 90)
			(layer "F.Fab")
			(hide yes)
			(effects
				(font
					(size 1.27 1.27)
					(thickness 0.15)
				)
			)
		)
		(property "Description" "SMD Chip Resistor, 10 kohm, ± 1%, 62.5 mW, 0402 [1005 Metric], Thick Film, General Purpose"
			(at 0 0 90)
			(layer "F.Fab")
			(hide yes)
			(effects
				(font
					(size 1.27 1.27)
					(thickness 0.15)
				)
			)
		)
		(property "Manufacturer" "Bourns"
			(at 0 0 270)
			(unlocked yes)
			(layer "F.Fab")
			(hide yes)
			(effects
				(font
					(size 1 1)
					(thickness 0.15)
				)
			)
		)
		(property "MPN" "CR0402-FX-1002GLF"
			(at 0 0 270)
			(unlocked yes)
			(layer "F.Fab")
			(hide yes)
			(effects
				(font
					(size 1 1)
					(thickness 0.15)
				)
			)
		)
		(property "Val" "10k"
			(at 0 0 270)
			(unlocked yes)
			(layer "F.Fab")
			(hide yes)
			(effects
				(font
					(size 1 1)
					(thickness 0.15)
				)
			)
		)
		(property "License" "Apache-2.0"
			(at 0 0 270)
			(unlocked yes)
			(layer "F.Fab")
			(hide yes)
			(effects
				(font
					(size 1 1)
					(thickness 0.15)
				)
			)
		)
		(property "Author" "Antmicro"
			(at 0 0 270)
			(unlocked yes)
			(layer "F.Fab")
			(hide yes)
			(effects
				(font
					(size 1 1)
					(thickness 0.15)
				)
			)
		)
		(property "Tolerance" "1%"
			(at 0 0 270)
			(unlocked yes)
			(layer "F.Fab")
			(hide yes)
			(effects
				(font
					(size 1 1)
					(thickness 0.15)
				)
			)
		)
		(sheetname "/Peripherals/")
		(sheetfile "peripherals.kicad_sch")
		(attr smd)
		(fp_rect
			(start -0.925 -0.47)
			(end 0.925 0.47)
			(stroke
				(width 0.05)
				(type default)
			)
			(fill no)
			(layer "F.CrtYd")
		)
		(fp_rect
			(start -0.5 -0.25)
			(end 0.5 0.25)
			(stroke
				(width 0.15)
				(type solid)
			)
			(fill no)
			(layer "F.Fab")
		)
		(fp_text user "Author: Antmicro"
			(at -0.95 4.169 90)
			(layer "F.Fab")
			(effects
				(font
					(size 0.7 0.7)
					(thickness 0.15)
				)
				(justify right top)
			)
		)
		(fp_text user "License: Apache-2.0"
			(at -0.95 5.169 90)
			(layer "F.Fab")
			(effects
				(font
					(size 0.7 0.7)
					(thickness 0.15)
				)
				(justify right top)
			)
		)
		(fp_text user "${REFERENCE}"
			(at -0.95 3.168 90)
			(layer "F.Fab")
			(effects
				(font
					(size 0.7 0.7)
					(thickness 0.15)
				)
				(justify right top)
			)
		)
		(pad "1" smd roundrect
			(at -0.48 0 270)
			(size 0.59 0.64)
			(layers "F.Cu" "F.Mask" "F.Paste")
			(roundrect_rratio 0.25)
			(net 448 "/Expansion connector/GPIO.USER_BTN0")
			(pintype "passive")
		)
		(pad "2" smd roundrect
			(at 0.48 0 270)
			(size 0.59 0.64)
			(layers "F.Cu" "F.Mask" "F.Paste")
			(roundrect_rratio 0.25)
			(net 11 "+1V8")
			(pintype "passive")
		)
	)
	(footprint "antmicro-footprints:R_0402_1005Metric"
		(layer "F.Cu")
		(at 95.9 58.38 90)
		(descr "Resistor SMD 0402")
		(tags "resistor SMD 0402")
		(property "Reference" "R408"
			(at -3.67 0.35 90)
			(layer "F.SilkS")
			(effects
				(font
					(size 0.7 0.7)
					(thickness 0.15)
				)
				(justify left bottom)
			)
		)
		(property "Value" "R_124k_0402"
			(at -1.011843 1.772047 90)
			(layer "F.Fab")
			(effects
				(font
					(size 0.7 0.7)
					(thickness 0.15)
				)
				(justify left bottom)
			)
		)
		(property "Datasheet" "https://www.bourns.com/docs/product-datasheets/cr.pdf"
			(at 0 0 90)
			(layer "F.Fab")
			(hide yes)
			(effects
				(font
					(size 1.27 1.27)
					(thickness 0.15)
				)
			)
		)
		(property "Description" "SMD Chip Resistor, 124 kohm, ± 1%, 100 mW, 0402 [1005 Metric], Thick Film, Precision"
			(at 0 0 90)
			(layer "F.Fab")
			(hide yes)
			(effects
				(font
					(size 1.27 1.27)
					(thickness 0.15)
				)
			)
		)
		(property "MPN" "CR0402-FX-1243GLF"
			(at 0 0 90)
			(unlocked yes)
			(layer "F.Fab")
			(hide yes)
			(effects
				(font
					(size 1 1)
					(thickness 0.15)
				)
			)
		)
		(property "Manufacturer" "Bourns"
			(at 0 0 90)
			(unlocked yes)
			(layer "F.Fab")
			(hide yes)
			(effects
				(font
					(size 1 1)
					(thickness 0.15)
				)
			)
		)
		(property "License" "Apache-2.0"
			(at 0 0 90)
			(unlocked yes)
			(layer "F.Fab")
			(hide yes)
			(effects
				(font
					(size 1 1)
					(thickness 0.15)
				)
			)
		)
		(property "Author" "Antmicro"
			(at 0 0 90)
			(unlocked yes)
			(layer "F.Fab")
			(hide yes)
			(effects
				(font
					(size 1 1)
					(thickness 0.15)
				)
			)
		)
		(property "Val" "124k"
			(at 0 0 90)
			(unlocked yes)
			(layer "F.Fab")
			(hide yes)
			(effects
				(font
					(size 1 1)
					(thickness 0.15)
				)
			)
		)
		(property "Tolerance" "1%"
			(at 0 0 90)
			(unlocked yes)
			(layer "F.Fab")
			(hide yes)
			(effects
				(font
					(size 1 1)
					(thickness 0.15)
				)
			)
		)
		(sheetname "/SoM_Power/")
		(sheetfile "som_power.kicad_sch")
		(attr smd)
		(fp_rect
			(start -0.925 -0.47)
			(end 0.925 0.47)
			(stroke
				(width 0.05)
				(type default)
			)
			(fill no)
			(layer "F.CrtYd")
		)
		(fp_rect
			(start -0.5 -0.25)
			(end 0.5 0.25)
			(stroke
				(width 0.15)
				(type solid)
			)
			(fill no)
			(layer "F.Fab")
		)
		(fp_text user "Author: Antmicro"
			(at -0.95 4.169 90)
			(layer "F.Fab")
			(effects
				(font
					(size 0.7 0.7)
					(thickness 0.15)
				)
				(justify left bottom)
			)
		)
		(fp_text user "${REFERENCE}"
			(at -0.95 3.168 90)
			(layer "F.Fab")
			(effects
				(font
					(size 0.7 0.7)
					(thickness 0.15)
				)
				(justify left bottom)
			)
		)
		(fp_text user "License: Apache-2.0"
			(at -0.95 5.169 90)
			(layer "F.Fab")
			(effects
				(font
					(size 0.7 0.7)
					(thickness 0.15)
				)
				(justify left bottom)
			)
		)
		(pad "1" smd roundrect
			(at -0.48 0 90)
			(size 0.59 0.64)
			(layers "F.Cu" "F.Mask" "F.Paste")
			(roundrect_rratio 0.25)
			(net 1 "GND")
			(pintype "passive")
		)
		(pad "2" smd roundrect
			(at 0.48 0 90)
			(size 0.59 0.64)
			(layers "F.Cu" "F.Mask" "F.Paste")
			(roundrect_rratio 0.25)
			(net 1381 "Net-(U3-SET)")
			(pintype "passive")
		)
	)
	(footprint "antmicro-footprints:R_0402_1005Metric"
		(layer "F.Cu")
		(at 100.12 123.1 180)
		(descr "Resistor SMD 0402")
		(tags "resistor SMD 0402")
		(property "Reference" "R320"
			(at -1.8 -0.6 0)
			(layer "F.SilkS")
			(effects
				(font
					(size 0.7 0.7)
					(thickness 0.15)
				)
				(justify right top)
			)
		)
		(property "Value" "R_0R_0402"
			(at -1.011843 1.772046 0)
			(layer "F.Fab")
			(effects
				(font
					(size 0.7 0.7)
					(thickness 0.15)
				)
				(justify right top)
			)
		)
		(property "Datasheet" "https://industrial.panasonic.com/cdbs/www-data/pdf/RDA0000/AOA0000C301.pdf"
			(at 0 0 0)
			(layer "F.Fab")
			(hide yes)
			(effects
				(font
					(size 1.27 1.27)
					(thickness 0.15)
				)
			)
		)
		(property "Description" "SMD Chip Resistor, Jumper, 0 ohm, 100 mW, 0402 [1005 Metric], Thick Film, General Purpose"
			(at 0 0 0)
			(layer "F.Fab")
			(hide yes)
			(effects
				(font
					(size 1.27 1.27)
					(thickness 0.15)
				)
			)
		)
		(property "MPN" "ERJ2GE0R00X"
			(at 0 0 180)
			(unlocked yes)
			(layer "F.Fab")
			(hide yes)
			(effects
				(font
					(size 1 1)
					(thickness 0.15)
				)
			)
		)
		(property "Manufacturer" "Panasonic"
			(at 0 0 180)
			(unlocked yes)
			(layer "F.Fab")
			(hide yes)
			(effects
				(font
					(size 1 1)
					(thickness 0.15)
				)
			)
		)
		(property "License" "Apache-2.0"
			(at 0 0 180)
			(unlocked yes)
			(layer "F.Fab")
			(hide yes)
			(effects
				(font
					(size 1 1)
					(thickness 0.15)
				)
			)
		)
		(property "Author" "Antmicro"
			(at 0 0 180)
			(unlocked yes)
			(layer "F.Fab")
			(hide yes)
			(effects
				(font
					(size 1 1)
					(thickness 0.15)
				)
			)
		)
		(property "Val" "0R"
			(at 0 0 180)
			(unlocked yes)
			(layer "F.Fab")
			(hide yes)
			(effects
				(font
					(size 1 1)
					(thickness 0.15)
				)
			)
		)
		(property "Tolerance" "~"
			(at 0 0 180)
			(unlocked yes)
			(layer "F.Fab")
			(hide yes)
			(effects
				(font
					(size 1 1)
					(thickness 0.15)
				)
			)
		)
		(property "Current" "1A"
			(at 0 0 180)
			(unlocked yes)
			(layer "F.Fab")
			(hide yes)
			(effects
				(font
					(size 1 1)
					(thickness 0.15)
				)
			)
		)
		(sheetname "/Expansion connector/")
		(sheetfile "expansion_connector.kicad_sch")
		(attr smd exclude_from_pos_files exclude_from_bom dnp)
		(fp_poly
			(pts
				(xy -0.925 -0.47) (xy 0.925 -0.47) (xy 0.925 0.47) (xy -0.925 0.47)
			)
			(stroke
				(width 0.05)
				(type default)
			)
			(fill no)
			(layer "F.CrtYd")
		)
		(fp_poly
			(pts
				(xy -0.5 -0.25) (xy 0.5 -0.25) (xy 0.5 0.25) (xy -0.5 0.25)
			)
			(stroke
				(width 0.15)
				(type solid)
			)
			(fill no)
			(layer "F.Fab")
		)
		(fp_text user "License: Apache-2.0"
			(at -0.949999 5.169 0)
			(layer "F.Fab")
			(effects
				(font
					(size 0.7 0.7)
					(thickness 0.15)
				)
				(justify right top)
			)
		)
		(fp_text user "${REFERENCE}"
			(at -0.95 3.168 0)
			(layer "F.Fab")
			(effects
				(font
					(size 0.7 0.7)
					(thickness 0.15)
				)
				(justify right top)
			)
		)
		(fp_text user "Author: Antmicro"
			(at -0.95 4.169 0)
			(layer "F.Fab")
			(effects
				(font
					(size 0.7 0.7)
					(thickness 0.15)
				)
				(justify right top)
			)
		)
		(pad "1" smd roundrect
			(at -0.48 0 180)
			(size 0.59 0.64)
			(layers "F.Cu" "F.Mask" "F.Paste")
			(roundrect_rratio 0.25)
			(net 2 "+3V3")
			(pintype "passive")
		)
		(pad "2" smd roundrect
			(at 0.48 0 180)
			(size 0.59 0.64)
			(layers "F.Cu" "F.Mask" "F.Paste")
			(roundrect_rratio 0.25)
			(net 148 "/Expansion connector/+3V3_AUX")
			(pintype "passive")
		)
	)
	(footprint "antmicro-footprints:R_0402_1005Metric"
		(layer "F.Cu")
		(at 97.1 61.9 180)
		(descr "Resistor SMD 0402")
		(tags "resistor SMD 0402")
		(property "Reference" "R44"
			(at -3 0.4 0)
			(layer "F.SilkS")
			(effects
				(font
					(size 0.7 0.7)
					(thickness 0.15)
				)
				(justify right top)
			)
		)
		(property "Value" "R_0R_0402"
			(at -1.011843 1.772047 0)
			(layer "F.Fab")
			(effects
				(font
					(size 0.7 0.7)
					(thickness 0.15)
				)
				(justify right top)
			)
		)
		(property "Datasheet" "https://industrial.panasonic.com/cdbs/www-data/pdf/RDA0000/AOA0000C301.pdf"
			(at 0 0 0)
			(layer "F.Fab")
			(hide yes)
			(effects
				(font
					(size 1.27 1.27)
					(thickness 0.15)
				)
			)
		)
		(property "Description" "SMD Chip Resistor, Jumper, 0 ohm, 100 mW, 0402 [1005 Metric], Thick Film, General Purpose"
			(at 0 0 0)
			(layer "F.Fab")
			(hide yes)
			(effects
				(font
					(size 1.27 1.27)
					(thickness 0.15)
				)
			)
		)
		(property "MPN" "ERJ2GE0R00X"
			(at 0 0 180)
			(unlocked yes)
			(layer "F.Fab")
			(hide yes)
			(effects
				(font
					(size 1 1)
					(thickness 0.15)
				)
			)
		)
		(property "Manufacturer" "Panasonic"
			(at 0 0 180)
			(unlocked yes)
			(layer "F.Fab")
			(hide yes)
			(effects
				(font
					(size 1 1)
					(thickness 0.15)
				)
			)
		)
		(property "License" "Apache-2.0"
			(at 0 0 180)
			(unlocked yes)
			(layer "F.Fab")
			(hide yes)
			(effects
				(font
					(size 1 1)
					(thickness 0.15)
				)
			)
		)
		(property "Author" "Antmicro"
			(at 0 0 180)
			(unlocked yes)
			(layer "F.Fab")
			(hide yes)
			(effects
				(font
					(size 1 1)
					(thickness 0.15)
				)
			)
		)
		(property "Val" "0R"
			(at 0 0 180)
			(unlocked yes)
			(layer "F.Fab")
			(hide yes)
			(effects
				(font
					(size 1 1)
					(thickness 0.15)
				)
			)
		)
		(property "Tolerance" "~"
			(at 0 0 180)
			(unlocked yes)
			(layer "F.Fab")
			(hide yes)
			(effects
				(font
					(size 1 1)
					(thickness 0.15)
				)
			)
		)
		(property "Current" "1A"
			(at 0 0 180)
			(unlocked yes)
			(layer "F.Fab")
			(hide yes)
			(effects
				(font
					(size 1 1)
					(thickness 0.15)
				)
			)
		)
		(sheetname "/SoM_Power/")
		(sheetfile "som_power.kicad_sch")
		(attr smd)
		(fp_rect
			(start -0.925 -0.47)
			(end 0.925 0.47)
			(stroke
				(width 0.05)
				(type default)
			)
			(fill no)
			(layer "F.CrtYd")
		)
		(fp_rect
			(start -0.5 -0.25)
			(end 0.5 0.25)
			(stroke
				(width 0.15)
				(type solid)
			)
			(fill no)
			(layer "F.Fab")
		)
		(fp_text user "${REFERENCE}"
			(at -0.95 3.168 0)
			(layer "F.Fab")
			(effects
				(font
					(size 0.7 0.7)
					(thickness 0.15)
				)
				(justify right top)
			)
		)
		(fp_text user "Author: Antmicro"
			(at -0.95 4.169 0)
			(layer "F.Fab")
			(effects
				(font
					(size 0.7 0.7)
					(thickness 0.15)
				)
				(justify right top)
			)
		)
		(fp_text user "License: Apache-2.0"
			(at -0.95 5.169 0)
			(layer "F.Fab")
			(effects
				(font
					(size 0.7 0.7)
					(thickness 0.15)
				)
				(justify right top)
			)
		)
		(pad "1" smd roundrect
			(at -0.48 0 180)
			(size 0.59 0.64)
			(layers "F.Cu" "F.Mask" "F.Paste")
			(roundrect_rratio 0.25)
			(net 1379 "Net-(Q30-D)")
			(pintype "passive")
		)
		(pad "2" smd roundrect
			(at 0.48 0 180)
			(size 0.59 0.64)
			(layers "F.Cu" "F.Mask" "F.Paste")
			(roundrect_rratio 0.25)
			(net 1032 "/SoM_Power/~{FORCE_SHDN}")
			(pintype "passive")
		)
	)
	(footprint "antmicro-footprints:C_0402_1005Metric"
		(layer "F.Cu")
		(at 210.25 133.1 180)
		(descr "Capacitor SMD 0402")
		(tags "capacitor SMD 0402")
		(property "Reference" "C87"
			(at 3.05 0.4 0)
			(layer "F.SilkS")
			(effects
				(font
					(size 0.7 0.7)
					(thickness 0.15)
				)
				(justify right top)
			)
		)
		(property "Value" "C_100n_0402"
			(at -1.022927 2.155213 0)
			(layer "F.Fab")
			(effects
				(font
					(size 0.7 0.7)
					(thickness 0.15)
				)
				(justify right top)
			)
		)
		(property "Datasheet" "https://www.murata.com/products/productdetail?partno=GRM155R61H104KE14%23"
			(at 0 0 0)
			(layer "F.Fab")
			(hide yes)
			(effects
				(font
					(size 1.27 1.27)
					(thickness 0.15)
				)
			)
		)
		(property "Description" "SMD Multilayer Ceramic Capacitor, 0.1 µF, 50 V, 0402 [1005 Metric], ± 10%, X5R, GRM Series"
			(at 0 0 0)
			(layer "F.Fab")
			(hide yes)
			(effects
				(font
					(size 1.27 1.27)
					(thickness 0.15)
				)
			)
		)
		(property "MPN" "GRM155R61H104KE14D"
			(at 0 0 180)
			(unlocked yes)
			(layer "F.Fab")
			(hide yes)
			(effects
				(font
					(size 1 1)
					(thickness 0.15)
				)
			)
		)
		(property "Val" "100n"
			(at 0 0 180)
			(unlocked yes)
			(layer "F.Fab")
			(hide yes)
			(effects
				(font
					(size 1 1)
					(thickness 0.15)
				)
			)
		)
		(property "Voltage" "50V"
			(at 0 0 180)
			(unlocked yes)
			(layer "F.Fab")
			(hide yes)
			(effects
				(font
					(size 1 1)
					(thickness 0.15)
				)
			)
		)
		(property "Dielectric" "X5R"
			(at 0 0 180)
			(unlocked yes)
			(layer "F.Fab")
			(hide yes)
			(effects
				(font
					(size 1 1)
					(thickness 0.15)
				)
			)
		)
		(property "Manufacturer" "Murata"
			(at 0 0 180)
			(unlocked yes)
			(layer "F.Fab")
			(hide yes)
			(effects
				(font
					(size 1 1)
					(thickness 0.15)
				)
			)
		)
		(property "License" "Apache-2.0"
			(at 0 0 180)
			(unlocked yes)
			(layer "F.Fab")
			(hide yes)
			(effects
				(font
					(size 1 1)
					(thickness 0.15)
				)
			)
		)
		(property "Author" "Antmicro"
			(at 0 0 180)
			(unlocked yes)
			(layer "F.Fab")
			(hide yes)
			(effects
				(font
					(size 1 1)
					(thickness 0.15)
				)
			)
		)
		(sheetname "/USB Hub/")
		(sheetfile "usb_hub.kicad_sch")
		(attr smd)
		(fp_poly
			(pts
				(xy -0.925 -0.47) (xy 0.925 -0.47) (xy 0.925 0.47) (xy -0.925 0.47)
			)
			(stroke
				(width 0.05)
				(type default)
			)
			(fill no)
			(layer "F.CrtYd")
		)
		(fp_line
			(start 0.504 0.248)
			(end -0.494 0.248)
			(stroke
				(width 0.15)
				(type solid)
			)
			(layer "F.Fab")
		)
		(fp_line
			(start 0.504 -0.25)
			(end 0.504 0.248)
			(stroke
				(width 0.15)
				(type solid)
			)
			(layer "F.Fab")
		)
		(fp_line
			(start -0.494 0.248)
			(end -0.494 -0.25)
			(stroke
				(width 0.15)
				(type solid)
			)
			(layer "F.Fab")
		)
		(fp_line
			(start -0.494 -0.25)
			(end 0.504 -0.25)
			(stroke
				(width 0.15)
				(type solid)
			)
			(layer "F.Fab")
		)
		(fp_text user "${REFERENCE}"
			(at -0.939 4.599 0)
			(layer "F.Fab")
			(effects
				(font
					(size 0.7 0.7)
					(thickness 0.15)
				)
				(justify right top)
			)
		)
		(fp_text user "Author: Antmicro"
			(at -0.939 3.399 0)
			(layer "F.Fab")
			(effects
				(font
					(size 0.7 0.7)
					(thickness 0.15)
				)
				(justify right top)
			)
		)
		(fp_text user "License: Apache-2.0"
			(at -0.939 5.799 0)
			(layer "F.Fab")
			(effects
				(font
					(size 0.7 0.7)
					(thickness 0.15)
				)
				(justify right top)
			)
		)
		(pad "1" smd roundrect
			(at -0.48 0 180)
			(size 0.59 0.64)
			(layers "F.Cu" "F.Mask" "F.Paste")
			(roundrect_rratio 0.25)
			(net 1 "GND")
			(pintype "passive")
		)
		(pad "2" smd roundrect
			(at 0.48 0 180)
			(size 0.59 0.64)
			(layers "F.Cu" "F.Mask" "F.Paste")
			(roundrect_rratio 0.25)
			(net 2 "+3V3")
			(pintype "passive")
		)
	)
	(footprint "antmicro-footprints:R_0402_1005Metric"
		(layer "F.Cu")
		(at 195.1 130.3)
		(descr "Resistor SMD 0402")
		(tags "resistor SMD 0402")
		(property "Reference" "R40"
			(at -1.050001 5.3 0)
			(layer "F.SilkS")
			(effects
				(font
					(size 0.7 0.7)
					(thickness 0.15)
				)
				(justify left bottom)
			)
		)
		(property "Value" "R_0R_0402"
			(at -1.011843 1.772046 0)
			(layer "F.Fab")
			(effects
				(font
					(size 0.7 0.7)
					(thickness 0.15)
				)
				(justify left bottom)
			)
		)
		(property "Datasheet" "https://industrial.panasonic.com/cdbs/www-data/pdf/RDA0000/AOA0000C301.pdf"
			(at 0 0 0)
			(layer "F.Fab")
			(hide yes)
			(effects
				(font
					(size 1.27 1.27)
					(thickness 0.15)
				)
			)
		)
		(property "Description" "SMD Chip Resistor, Jumper, 0 ohm, 100 mW, 0402 [1005 Metric], Thick Film, General Purpose"
			(at 0 0 0)
			(layer "F.Fab")
			(hide yes)
			(effects
				(font
					(size 1.27 1.27)
					(thickness 0.15)
				)
			)
		)
		(property "Manufacturer" "Panasonic"
			(at 0 0 0)
			(unlocked yes)
			(layer "F.Fab")
			(hide yes)
			(effects
				(font
					(size 1 1)
					(thickness 0.15)
				)
			)
		)
		(property "MPN" "ERJ2GE0R00X"
			(at 0 0 0)
			(unlocked yes)
			(layer "F.Fab")
			(hide yes)
			(effects
				(font
					(size 1 1)
					(thickness 0.15)
				)
			)
		)
		(property "Val" "0R"
			(at 0 0 0)
			(unlocked yes)
			(layer "F.Fab")
			(hide yes)
			(effects
				(font
					(size 1 1)
					(thickness 0.15)
				)
			)
		)
		(property "License" "Apache-2.0"
			(at 0 0 0)
			(unlocked yes)
			(layer "F.Fab")
			(hide yes)
			(effects
				(font
					(size 1 1)
					(thickness 0.15)
				)
			)
		)
		(property "Author" "Antmicro"
			(at 0 0 0)
			(unlocked yes)
			(layer "F.Fab")
			(hide yes)
			(effects
				(font
					(size 1 1)
					(thickness 0.15)
				)
			)
		)
		(property "Tolerance" "~"
			(at 0 0 0)
			(unlocked yes)
			(layer "F.Fab")
			(hide yes)
			(effects
				(font
					(size 1 1)
					(thickness 0.15)
				)
			)
		)
		(property "Current" "1A"
			(at 0 0 0)
			(unlocked yes)
			(layer "F.Fab")
			(hide yes)
			(effects
				(font
					(size 1 1)
					(thickness 0.15)
				)
			)
		)
		(sheetname "/USB Hub/")
		(sheetfile "usb_hub.kicad_sch")
		(attr smd exclude_from_pos_files exclude_from_bom dnp)
		(fp_poly
			(pts
				(xy -0.925 -0.47) (xy -0.925 0.47) (xy 0.925 0.47) (xy 0.925 -0.47)
			)
			(stroke
				(width 0.05)
				(type default)
			)
			(fill no)
			(layer "F.CrtYd")
		)
		(fp_poly
			(pts
				(xy -0.5 -0.25) (xy -0.5 0.25) (xy 0.5 0.25) (xy 0.5 -0.25)
			)
			(stroke
				(width 0.15)
				(type solid)
			)
			(fill no)
			(layer "F.Fab")
		)
		(fp_text user "Author: Antmicro"
			(at -0.95 4.169 0)
			(layer "F.Fab")
			(effects
				(font
					(size 0.7 0.7)
					(thickness 0.15)
				)
				(justify left bottom)
			)
		)
		(fp_text user "License: Apache-2.0"
			(at -0.949999 5.169 0)
			(layer "F.Fab")
			(effects
				(font
					(size 0.7 0.7)
					(thickness 0.15)
				)
				(justify left bottom)
			)
		)
		(fp_text user "${REFERENCE}"
			(at -0.95 3.168 0)
			(layer "F.Fab")
			(effects
				(font
					(size 0.7 0.7)
					(thickness 0.15)
				)
				(justify left bottom)
			)
		)
		(pad "1" smd roundrect
			(at -0.48 0)
			(size 0.59 0.64)
			(layers "F.Cu" "F.Mask" "F.Paste")
			(roundrect_rratio 0.25)
			(net 850 "/I2C_{SYS}.SDA")
			(pintype "passive")
		)
		(pad "2" smd roundrect
			(at 0.48 0)
			(size 0.59 0.64)
			(layers "F.Cu" "F.Mask" "F.Paste")
			(roundrect_rratio 0.25)
			(net 1233 "Net-(U21-PF19)")
			(pintype "passive")
		)
	)
	(footprint "antmicro-footprints:C_0805_2012Metric"
		(layer "F.Cu")
		(at 111.380001 56.74 -90)
		(descr "Capacitor SMD 0805")
		(tags "capacitor SMD 0805")
		(property "Reference" "C380"
			(at -1.87 1.910001 180)
			(layer "F.SilkS")
			(effects
				(font
					(size 0.7 0.7)
					(thickness 0.15)
				)
				(justify left bottom)
			)
		)
		(property "Value" "C_22u_25V_0805"
			(at -2.055717 1.963153 90)
			(layer "F.Fab")
			(effects
				(font
					(size 0.7 0.7)
					(thickness 0.15)
				)
				(justify right top)
			)
		)
		(property "Datasheet" "https://product.samsungsem.com/mlcc/CL21A226MAYNNN.do"
			(at 0 0 90)
			(layer "F.Fab")
			(hide yes)
			(effects
				(font
					(size 1.27 1.27)
					(thickness 0.15)
				)
			)
		)
		(property "Description" "SMT Multilayer Ceramic Capacitor, 22uF, +/-20%, 25V, X5R, 0805 [2012 Metric]"
			(at 0 0 90)
			(layer "F.Fab")
			(hide yes)
			(effects
				(font
					(size 1.27 1.27)
					(thickness 0.15)
				)
			)
		)
		(property "MPN" "CL21A226MAYNNNE"
			(at 0 0 270)
			(unlocked yes)
			(layer "F.Fab")
			(hide yes)
			(effects
				(font
					(size 1 1)
					(thickness 0.15)
				)
			)
		)
		(property "Manufacturer" "Samsung Electro-Mechanics"
			(at 0 0 270)
			(unlocked yes)
			(layer "F.Fab")
			(hide yes)
			(effects
				(font
					(size 1 1)
					(thickness 0.15)
				)
			)
		)
		(property "License" "Apache-2.0"
			(at 0 0 270)
			(unlocked yes)
			(layer "F.Fab")
			(hide yes)
			(effects
				(font
					(size 1 1)
					(thickness 0.15)
				)
			)
		)
		(property "Author" "Antmicro"
			(at 0 0 270)
			(unlocked yes)
			(layer "F.Fab")
			(hide yes)
			(effects
				(font
					(size 1 1)
					(thickness 0.15)
				)
			)
		)
		(property "Val" "22u"
			(at 0 0 270)
			(unlocked yes)
			(layer "F.Fab")
			(hide yes)
			(effects
				(font
					(size 1 1)
					(thickness 0.15)
				)
			)
		)
		(property "Voltage" "25V"
			(at 0 0 270)
			(unlocked yes)
			(layer "F.Fab")
			(hide yes)
			(effects
				(font
					(size 1 1)
					(thickness 0.15)
				)
			)
		)
		(property "Dielectric" "X5R"
			(at 0 0 270)
			(unlocked yes)
			(layer "F.Fab")
			(hide yes)
			(effects
				(font
					(size 1 1)
					(thickness 0.15)
				)
			)
		)
		(property "Public" "False"
			(at 0 0 270)
			(unlocked yes)
			(layer "F.Fab")
			(hide yes)
			(effects
				(font
					(size 1 1)
					(thickness 0.15)
				)
			)
		)
		(sheetname "/DCDC/")
		(sheetfile "dcdc.kicad_sch")
		(attr smd)
		(fp_line
			(start -0.3 0.7)
			(end 0.3 0.7)
			(stroke
				(width 0.15)
				(type solid)
			)
			(layer "F.SilkS")
		)
		(fp_line
			(start -0.3 -0.7)
			(end 0.3 -0.7)
			(stroke
				(width 0.15)
				(type solid)
			)
			(layer "F.SilkS")
		)
		(fp_poly
			(pts
				(xy 1.95 -0.9) (xy 1.95 0.9) (xy -1.95 0.9) (xy -1.95 -0.9)
			)
			(stroke
				(width 0.05)
				(type default)
			)
			(fill no)
			(layer "F.CrtYd")
		)
		(fp_poly
			(pts
				(xy -0.95 -0.675001) (xy -0.95 0.675001) (xy 0.95 0.675001) (xy 0.95 -0.675001)
			)
			(stroke
				(width 0.15)
				(type solid)
			)
			(fill no)
			(layer "F.Fab")
		)
		(fp_text user "${REFERENCE}"
			(at -1.899999 3.947 90)
			(layer "F.Fab")
			(effects
				(font
					(size 0.7 0.7)
					(thickness 0.15)
				)
				(justify right top)
			)
		)
		(fp_text user "License: Apache-2.0"
			(at -1.9 4.947 90)
			(layer "F.Fab")
			(effects
				(font
					(size 0.7 0.7)
					(thickness 0.15)
				)
				(justify right top)
			)
		)
		(fp_text user "Author: Antmicro"
			(at -1.9 5.947 90)
			(layer "F.Fab")
			(effects
				(font
					(size 0.7 0.7)
					(thickness 0.15)
				)
				(justify right top)
			)
		)
		(pad "1" smd roundrect
			(at -1.099999 0 270)
			(size 1.2 1.3)
			(layers "F.Cu" "F.Mask" "F.Paste")
			(roundrect_rratio 0.25)
			(net 1 "GND")
			(pintype "passive")
		)
		(pad "2" smd roundrect
			(at 1.099999 0 270)
			(size 1.2 1.3)
			(layers "F.Cu" "F.Mask" "F.Paste")
			(roundrect_rratio 0.25)
			(net 1278 "/DCDC/5V_{AON}_OUT")
			(pintype "passive")
		)
	)
	(footprint "antmicro-footprints:USB-C_Receptacle_Kycon_KUSBX-SL2-CS1N24-B-TR"
		(locked yes)
		(layer "F.Cu")
		(at 236.455532 128.21 90)
		(descr "USB-C (USB TYPE-C) USB 3.2 Gen 2 (USB 3.1 Gen 2, Superspeed + (USB 3.1)) Receptacle Connector 24 Position Through Hole, Right Angle")
		(tags "CONNECTOR, USB")
		(property "Reference" "J5"
			(at 3.11 -10.885532 180)
			(layer "F.SilkS")
			(effects
				(font
					(size 0.7 0.7)
					(thickness 0.15)
				)
				(justify left bottom)
			)
		)
		(property "Value" "USB-C_Kycon_KUSBX-SL2-CS1N24-B-TR"
			(at 0 7.5 90)
			(layer "F.Fab")
			(effects
				(font
					(size 0.7 0.7)
					(thickness 0.15)
				)
				(justify right top)
			)
		)
		(property "Datasheet" "https://www.kycon.com/Pub_Eng_Draw/KUSBX-SL2-CS1N24-B-TR.pdf"
			(at 0 0 90)
			(layer "F.Fab")
			(hide yes)
			(effects
				(font
					(size 1.27 1.27)
					(thickness 0.15)
				)
			)
		)
		(property "Description" "USB-C (USB TYPE-C) USB 3.2 Gen 2 (USB 3.1 Gen 2, Superspeed + (USB 3.1)) USB PD Receptacle Connector 24 Position Surface Mount"
			(at 0 0 90)
			(layer "F.Fab")
			(hide yes)
			(effects
				(font
					(size 1.27 1.27)
					(thickness 0.15)
				)
			)
		)
		(property "MPN" "KUSBX-SL2-CS1N24-B-TR"
			(at 0 0 90)
			(unlocked yes)
			(layer "F.Fab")
			(hide yes)
			(effects
				(font
					(size 1 1)
					(thickness 0.15)
				)
			)
		)
		(property "Manufacturer" "Kycon"
			(at 0 0 90)
			(unlocked yes)
			(layer "F.Fab")
			(hide yes)
			(effects
				(font
					(size 1 1)
					(thickness 0.15)
				)
			)
		)
		(property "License" "Apache-2.0"
			(at 0 0 90)
			(unlocked yes)
			(layer "F.Fab")
			(hide yes)
			(effects
				(font
					(size 1 1)
					(thickness 0.15)
				)
			)
		)
		(property "Author" "Antmicro"
			(at 0 0 90)
			(unlocked yes)
			(layer "F.Fab")
			(hide yes)
			(effects
				(font
					(size 1 1)
					(thickness 0.15)
				)
			)
		)
		(sheetname "/USB Hub/")
		(sheetfile "usb_hub.kicad_sch")
		(attr smd)
		(fp_line
			(start 1 -8.8)
			(end 1 -8.8)
			(stroke
				(width 0.15)
				(type solid)
			)
			(layer "F.SilkS")
		)
		(fp_line
			(start 1 -8.8)
			(end -1 -8.8)
			(stroke
				(width 0.15)
				(type solid)
			)
			(layer "F.SilkS")
		)
		(fp_line
			(start -1 -8.8)
			(end 1 -8.8)
			(stroke
				(width 0.15)
				(type solid)
			)
			(layer "F.SilkS")
		)
		(fp_line
			(start -1 -8.8)
			(end -1 -8.8)
			(stroke
				(width 0.15)
				(type solid)
			)
			(layer "F.SilkS")
		)
		(fp_rect
			(start -4 -9.4)
			(end 4 5.65)
			(stroke
				(width 0.05)
				(type solid)
			)
			(fill no)
			(layer "F.CrtYd")
		)
		(fp_line
			(start 2.25 -8.8)
			(end -2.25 -8.8)
			(stroke
				(width 0.15)
				(type solid)
			)
			(layer "F.Fab")
		)
		(fp_line
			(start -2.25 -8.8)
			(end -2.25 5.5)
			(stroke
				(width 0.15)
				(type solid)
			)
			(layer "F.Fab")
		)
		(fp_line
			(start 2.25 5.5)
			(end 2.25 -8.8)
			(stroke
				(width 0.15)
				(type solid)
			)
			(layer "F.Fab")
		)
		(fp_line
			(start -2.25 5.5)
			(end 2.25 5.5)
			(stroke
				(width 0.15)
				(type solid)
			)
			(layer "F.Fab")
		)
		(fp_text user "License: Apache-2.0"
			(at -5.47 10.9 90)
			(layer "F.Fab")
			(effects
				(font
					(size 0.7 0.7)
					(thickness 0.15)
				)
				(justify left bottom)
			)
		)
		(fp_text user "Author: Antmicro"
			(at -5.47 9.7 90)
			(layer "F.Fab")
			(effects
				(font
					(size 0.7 0.7)
					(thickness 0.15)
				)
				(justify left bottom)
			)
		)
		(fp_text user "${REFERENCE}"
			(at -5.47 8.5 90)
			(layer "F.Fab")
			(effects
				(font
					(size 0.7 0.7)
					(thickness 0.15)
				)
				(justify left bottom)
			)
		)
		(pad "" np_thru_hole circle
			(at 0 -7.6 90)
			(size 1.1 1.1)
			(drill 1.1)
			(layers "*.Cu" "*.Mask")
		)
		(pad "" np_thru_hole circle
			(at 0 0 90)
			(size 1 1)
			(drill 1)
			(layers "*.Cu" "*.Mask")
		)
		(pad "A1" smd rect
			(at 1.1375 -6.525 180)
			(size 0.25 1.625)
			(layers "F.Cu" "F.Mask" "F.Paste")
			(net 1 "GND")
			(pinfunction "GND")
			(pintype "power_in")
		)
		(pad "A2" smd rect
			(at 1.1375 -6.025 180)
			(size 0.25 1.625)
			(layers "F.Cu" "F.Mask" "F.Paste")
			(net 78 "/USB Hub/USBC4_CONN_TX1_P")
			(pinfunction "TX_{1}+")
			(pintype "bidirectional")
		)
		(pad "A3" smd rect
			(at 1.1375 -5.525 180)
			(size 0.25 1.625)
			(layers "F.Cu" "F.Mask" "F.Paste")
			(net 91 "/USB Hub/USBC4_CONN_TX1_N")
			(pinfunction "TX_{1}-")
			(pintype "bidirectional")
		)
		(pad "A4" smd rect
			(at 1.1375 -5.025 180)
			(size 0.25 1.625)
			(layers "F.Cu" "F.Mask" "F.Paste")
			(net 115 "/USB Hub/USBC4_VBUS")
			(pinfunction "VBUS")
			(pintype "power_in")
		)
		(pad "A5" smd rect
			(at 1.1375 -4.525 180)
			(size 0.25 1.625)
			(layers "F.Cu" "F.Mask" "F.Paste")
			(net 503 "/USB Hub/USBC4_CC_{1}")
			(pinfunction "CC_{1}")
			(pintype "bidirectional")
		)
		(pad "A6" smd rect
			(at 1.1375 -4.025 180)
			(size 0.25 1.625)
			(layers "F.Cu" "F.Mask" "F.Paste")
			(net 505 "/USB Hub/USBC4_D+")
			(pinfunction "D_{A}+")
			(pintype "bidirectional")
		)
		(pad "A7" smd rect
			(at 1.1375 -3.525 180)
			(size 0.25 1.625)
			(layers "F.Cu" "F.Mask" "F.Paste")
			(net 499 "/USB Hub/USBC4_D-")
			(pinfunction "D_{A}-")
			(pintype "bidirectional")
		)
		(pad "A8" smd rect
			(at 1.1375 -3.025 180)
			(size 0.25 1.625)
			(layers "F.Cu" "F.Mask" "F.Paste")
			(net 175 "unconnected-(J5-SBU_{1}-PadA8)")
			(pinfunction "SBU_{1}")
			(pintype "bidirectional+no_connect")
		)
		(pad "A9" smd rect
			(at 1.1375 -2.525 180)
			(size 0.25 1.625)
			(layers "F.Cu" "F.Mask" "F.Paste")
			(net 115 "/USB Hub/USBC4_VBUS")
			(pinfunction "VBUS")
			(pintype "passive")
		)
		(pad "A10" smd rect
			(at 1.1375 -2.025 180)
			(size 0.25 1.625)
			(layers "F.Cu" "F.Mask" "F.Paste")
			(net 498 "/USB Hub/USBC4_RX_{2}+")
			(pinfunction "RX_{2}-")
			(pintype "bidirectional")
		)
		(pad "A11" smd rect
			(at 1.1375 -1.525 180)
			(size 0.25 1.625)
			(layers "F.Cu" "F.Mask" "F.Paste")
			(net 500 "/USB Hub/USBC4_RX_{2}-")
			(pinfunction "RX_{2}+")
			(pintype "bidirectional")
		)
		(pad "A12" smd rect
			(at 1.1375 -1.025 180)
			(size 0.25 1.625)
			(layers "F.Cu" "F.Mask" "F.Paste")
			(net 1 "GND")
			(pinfunction "GND")
			(pintype "passive")
		)
		(pad "B1" smd rect
			(at -1.1375 -1.025 180)
			(size 0.25 1.625)
			(layers "F.Cu" "F.Mask" "F.Paste")
			(net 1 "GND")
			(pinfunction "GND")
			(pintype "passive")
		)
		(pad "B2" smd rect
			(at -1.1375 -1.525 180)
			(size 0.25 1.625)
			(layers "F.Cu" "F.Mask" "F.Paste")
			(net 80 "/USB Hub/USBC4_CONN_TX2_P")
			(pinfunction "TX_{2}+")
			(pintype "bidirectional")
		)
		(pad "B3" smd rect
			(at -1.1375 -2.025 180)
			(size 0.25 1.625)
			(layers "F.Cu" "F.Mask" "F.Paste")
			(net 110 "/USB Hub/USBC4_CONN_TX2_N")
			(pinfunction "TX_{2}-")
			(pintype "bidirectional")
		)
		(pad "B4" smd rect
			(at -1.1375 -2.525 180)
			(size 0.25 1.625)
			(layers "F.Cu" "F.Mask" "F.Paste")
			(net 115 "/USB Hub/USBC4_VBUS")
			(pinfunction "VBUS")
			(pintype "passive")
		)
		(pad "B5" smd rect
			(at -1.1375 -3.025 180)
			(size 0.25 1.625)
			(layers "F.Cu" "F.Mask" "F.Paste")
			(net 502 "/USB Hub/USBC4_CC_{2}")
			(pinfunction "CC_{2}")
			(pintype "bidirectional")
		)
		(pad "B6" smd rect
			(at -1.1375 -3.525 180)
			(size 0.25 1.625)
			(layers "F.Cu" "F.Mask" "F.Paste")
			(net 505 "/USB Hub/USBC4_D+")
			(pinfunction "D_{B}+")
			(pintype "bidirectional")
		)
		(pad "B7" smd rect
			(at -1.1375 -4.025 180)
			(size 0.25 1.625)
			(layers "F.Cu" "F.Mask" "F.Paste")
			(net 499 "/USB Hub/USBC4_D-")
			(pinfunction "D_{B}-")
			(pintype "bidirectional")
		)
		(pad "B8" smd rect
			(at -1.1375 -4.525 180)
			(size 0.25 1.625)
			(layers "F.Cu" "F.Mask" "F.Paste")
			(net 177 "unconnected-(J5-SBU_{2}-PadB8)")
			(pinfunction "SBU_{2}")
			(pintype "bidirectional+no_connect")
		)
		(pad "B9" smd rect
			(at -1.1375 -5.025 180)
			(size 0.25 1.625)
			(layers "F.Cu" "F.Mask" "F.Paste")
			(net 115 "/USB Hub/USBC4_VBUS")
			(pinfunction "VBUS")
			(pintype "passive")
		)
		(pad "B10" smd rect
			(at -1.1375 -5.525 180)
			(size 0.25 1.625)
			(layers "F.Cu" "F.Mask" "F.Paste")
			(net 504 "/USB Hub/USBC4_RX_{1}+")
			(pinfunction "RX_{1}-")
			(pintype "bidirectional")
		)
		(pad "B11" smd rect
			(at -1.1375 -6.025 180)
			(size 0.25 1.625)
			(layers "F.Cu" "F.Mask" "F.Paste")
			(net 501 "/USB Hub/USBC4_RX_{1}-")
			(pinfunction "RX_{1}+")
			(pintype "bidirectional")
		)
		(pad "B12" smd rect
			(at -1.1375 -6.525 180)
			(size 0.25 1.625)
			(layers "F.Cu" "F.Mask" "F.Paste")
			(net 1 "GND")
			(pinfunction "GND")
			(pintype "passive")
		)
		(pad "SH" thru_hole oval
			(at -3 -7.849 90)
			(size 1 2.05)
			(drill oval 0.6 1.65)
			(layers "*.Cu" "*.Mask")
			(remove_unused_layers no)
			(net 1 "GND")
			(pinfunction "SH")
			(pintype "passive")
		)
		(pad "SH" thru_hole oval
			(at -3 0.25 90)
			(size 1 2.05)
			(drill oval 0.6 1.65)
			(layers "*.Cu" "*.Mask")
			(remove_unused_layers no)
			(net 1 "GND")
			(pinfunction "SH")
			(pintype "passive")
		)
		(pad "SH" thru_hole oval
			(at 3 -7.849 90)
			(size 1 2.05)
			(drill oval 0.6 1.65)
			(layers "*.Cu" "*.Mask")
			(remove_unused_layers no)
			(net 1 "GND")
			(pinfunction "SH")
			(pintype "passive")
		)
		(pad "SH" thru_hole oval
			(at 3 0.25 90)
			(size 1 2.05)
			(drill oval 0.6 1.65)
			(layers "*.Cu" "*.Mask")
			(remove_unused_layers no)
			(net 1 "GND")
			(pinfunction "SH")
			(pintype "passive")
		)
	)
	(footprint "antmicro-footprints:C_0402_1005Metric"
		(layer "F.Cu")
		(at 91.1 98.3)
		(descr "Capacitor SMD 0402")
		(tags "capacitor SMD 0402")
		(property "Reference" "C345"
			(at 1.1 0.500001 0)
			(layer "F.SilkS")
			(effects
				(font
					(size 0.7 0.7)
					(thickness 0.15)
				)
				(justify left bottom)
			)
		)
		(property "Value" "C_100n_0402"
			(at -1.022927 2.155213 0)
			(layer "F.Fab")
			(effects
				(font
					(size 0.7 0.7)
					(thickness 0.15)
				)
				(justify left bottom)
			)
		)
		(property "Datasheet" "https://www.murata.com/products/productdetail?partno=GRM155R61H104KE14%23"
			(at 0 0 0)
			(layer "F.Fab")
			(hide yes)
			(effects
				(font
					(size 1.27 1.27)
					(thickness 0.15)
				)
			)
		)
		(property "Description" "SMD Multilayer Ceramic Capacitor, 0.1 µF, 50 V, 0402 [1005 Metric], ± 10%, X5R, GRM Series"
			(at 0 0 0)
			(layer "F.Fab")
			(hide yes)
			(effects
				(font
					(size 1.27 1.27)
					(thickness 0.15)
				)
			)
		)
		(property "Manufacturer" "Murata"
			(at 0 0 0)
			(unlocked yes)
			(layer "F.Fab")
			(hide yes)
			(effects
				(font
					(size 1 1)
					(thickness 0.15)
				)
			)
		)
		(property "MPN" "GRM155R61H104KE14D"
			(at 0 0 0)
			(unlocked yes)
			(layer "F.Fab")
			(hide yes)
			(effects
				(font
					(size 1 1)
					(thickness 0.15)
				)
			)
		)
		(property "Val" "100n"
			(at 0 0 0)
			(unlocked yes)
			(layer "F.Fab")
			(hide yes)
			(effects
				(font
					(size 1 1)
					(thickness 0.15)
				)
			)
		)
		(property "License" "Apache-2.0"
			(at 0 0 0)
			(unlocked yes)
			(layer "F.Fab")
			(hide yes)
			(effects
				(font
					(size 1 1)
					(thickness 0.15)
				)
			)
		)
		(property "Author" "Antmicro"
			(at 0 0 0)
			(unlocked yes)
			(layer "F.Fab")
			(hide yes)
			(effects
				(font
					(size 1 1)
					(thickness 0.15)
				)
			)
		)
		(property "Voltage" "50V"
			(at 0 0 0)
			(unlocked yes)
			(layer "F.Fab")
			(hide yes)
			(effects
				(font
					(size 1 1)
					(thickness 0.15)
				)
			)
		)
		(property "Dielectric" "X5R"
			(at 0 0 0)
			(unlocked yes)
			(layer "F.Fab")
			(hide yes)
			(effects
				(font
					(size 1 1)
					(thickness 0.15)
				)
			)
		)
		(sheetname "/SoM_IO2/")
		(sheetfile "som_io2.kicad_sch")
		(attr smd)
		(fp_rect
			(start -0.925 -0.47)
			(end 0.925 0.47)
			(stroke
				(width 0.05)
				(type default)
			)
			(fill no)
			(layer "F.CrtYd")
		)
		(fp_line
			(start -0.494 -0.25)
			(end 0.504 -0.25)
			(stroke
				(width 0.15)
				(type solid)
			)
			(layer "F.Fab")
		)
		(fp_line
			(start -0.494 0.248)
			(end -0.494 -0.25)
			(stroke
				(width 0.15)
				(type solid)
			)
			(layer "F.Fab")
		)
		(fp_line
			(start 0.504 -0.25)
			(end 0.504 0.248)
			(stroke
				(width 0.15)
				(type solid)
			)
			(layer "F.Fab")
		)
		(fp_line
			(start 0.504 0.248)
			(end -0.494 0.248)
			(stroke
				(width 0.15)
				(type solid)
			)
			(layer "F.Fab")
		)
		(fp_text user "Author: Antmicro"
			(at -0.939 3.399 0)
			(layer "F.Fab")
			(effects
				(font
					(size 0.7 0.7)
					(thickness 0.15)
				)
				(justify left bottom)
			)
		)
		(fp_text user "${REFERENCE}"
			(at -0.939 4.599 0)
			(layer "F.Fab")
			(effects
				(font
					(size 0.7 0.7)
					(thickness 0.15)
				)
				(justify left bottom)
			)
		)
		(fp_text user "License: Apache-2.0"
			(at -0.939 5.799 0)
			(layer "F.Fab")
			(effects
				(font
					(size 0.7 0.7)
					(thickness 0.15)
				)
				(justify left bottom)
			)
		)
		(pad "1" smd roundrect
			(at -0.48 0)
			(size 0.59 0.64)
			(layers "F.Cu" "F.Mask" "F.Paste")
			(roundrect_rratio 0.25)
			(net 736 "/Expansion connector/DP3.TX1+")
			(pintype "passive")
		)
		(pad "2" smd roundrect
			(at 0.48 0)
			(size 0.59 0.64)
			(layers "F.Cu" "F.Mask" "F.Paste")
			(roundrect_rratio 0.25)
			(net 1265 "/SoM_IO2/DP3.TX1_C+")
			(pintype "passive")
		)
	)
	(footprint "antmicro-footprints:R_0402_1005Metric"
		(layer "F.Cu")
		(at 142.226999 108.15 -90)
		(descr "Resistor SMD 0402")
		(tags "resistor SMD 0402")
		(property "Reference" "R343"
			(at -1.45 -0.673001 90)
			(layer "F.SilkS")
			(effects
				(font
					(size 0.7 0.7)
					(thickness 0.15)
				)
				(justify right top)
			)
		)
		(property "Value" "R_10k_0402"
			(at -1.011843 1.772047 90)
			(layer "F.Fab")
			(effects
				(font
					(size 0.7 0.7)
					(thickness 0.15)
				)
				(justify right top)
			)
		)
		(property "Datasheet" "https://www.bourns.com/docs/product-datasheets/cr.pdf"
			(at 0 0 90)
			(layer "F.Fab")
			(hide yes)
			(effects
				(font
					(size 1.27 1.27)
					(thickness 0.15)
				)
			)
		)
		(property "Description" "SMD Chip Resistor, 10 kohm, ± 1%, 62.5 mW, 0402 [1005 Metric], Thick Film, General Purpose"
			(at 0 0 90)
			(layer "F.Fab")
			(hide yes)
			(effects
				(font
					(size 1.27 1.27)
					(thickness 0.15)
				)
			)
		)
		(property "Manufacturer" "Bourns"
			(at 0 0 270)
			(unlocked yes)
			(layer "F.Fab")
			(hide yes)
			(effects
				(font
					(size 1 1)
					(thickness 0.15)
				)
			)
		)
		(property "MPN" "CR0402-FX-1002GLF"
			(at 0 0 270)
			(unlocked yes)
			(layer "F.Fab")
			(hide yes)
			(effects
				(font
					(size 1 1)
					(thickness 0.15)
				)
			)
		)
		(property "Val" "10k"
			(at 0 0 270)
			(unlocked yes)
			(layer "F.Fab")
			(hide yes)
			(effects
				(font
					(size 1 1)
					(thickness 0.15)
				)
			)
		)
		(property "License" "Apache-2.0"
			(at 0 0 270)
			(unlocked yes)
			(layer "F.Fab")
			(hide yes)
			(effects
				(font
					(size 1 1)
					(thickness 0.15)
				)
			)
		)
		(property "Author" "Antmicro"
			(at 0 0 270)
			(unlocked yes)
			(layer "F.Fab")
			(hide yes)
			(effects
				(font
					(size 1 1)
					(thickness 0.15)
				)
			)
		)
		(property "Tolerance" "1%"
			(at 0 0 270)
			(unlocked yes)
			(layer "F.Fab")
			(hide yes)
			(effects
				(font
					(size 1 1)
					(thickness 0.15)
				)
			)
		)
		(sheetname "/Peripherals/")
		(sheetfile "peripherals.kicad_sch")
		(attr smd)
		(fp_rect
			(start -0.925 -0.47)
			(end 0.925 0.47)
			(stroke
				(width 0.05)
				(type default)
			)
			(fill no)
			(layer "F.CrtYd")
		)
		(fp_rect
			(start -0.5 -0.25)
			(end 0.5 0.25)
			(stroke
				(width 0.15)
				(type solid)
			)
			(fill no)
			(layer "F.Fab")
		)
		(fp_text user "${REFERENCE}"
			(at -0.95 3.168 90)
			(layer "F.Fab")
			(effects
				(font
					(size 0.7 0.7)
					(thickness 0.15)
				)
				(justify right top)
			)
		)
		(fp_text user "Author: Antmicro"
			(at -0.95 4.169 90)
			(layer "F.Fab")
			(effects
				(font
					(size 0.7 0.7)
					(thickness 0.15)
				)
				(justify right top)
			)
		)
		(fp_text user "License: Apache-2.0"
			(at -0.95 5.169 90)
			(layer "F.Fab")
			(effects
				(font
					(size 0.7 0.7)
					(thickness 0.15)
				)
				(justify right top)
			)
		)
		(pad "1" smd roundrect
			(at -0.48 0 270)
			(size 0.59 0.64)
			(layers "F.Cu" "F.Mask" "F.Paste")
			(roundrect_rratio 0.25)
			(net 1309 "/Peripherals/GPIO_EXP_IRQ")
			(pintype "passive")
		)
		(pad "2" smd roundrect
			(at 0.48 0 270)
			(size 0.59 0.64)
			(layers "F.Cu" "F.Mask" "F.Paste")
			(roundrect_rratio 0.25)
			(net 11 "+1V8")
			(pintype "passive")
		)
	)
	(footprint "antmicro-footprints:TP_SMD_0.75mm"
		(layer "F.Cu")
		(at 203.8 83.2)
		(property "Reference" "TP76"
			(at -2.4 1.6 0)
			(layer "F.SilkS")
			(effects
				(font
					(size 0.7 0.7)
					(thickness 0.15)
				)
				(justify left bottom)
			)
		)
		(property "Value" "TP_0.75mm_SMD"
			(at 0 1.2 0)
			(layer "F.Fab")
			(effects
				(font
					(size 0.7 0.7)
					(thickness 0.15)
				)
				(justify left bottom)
			)
		)
		(property "Description" "SMT test point"
			(at 0 0 0)
			(layer "F.Fab")
			(hide yes)
			(effects
				(font
					(size 1.27 1.27)
					(thickness 0.15)
				)
			)
		)
		(property "MPN" ""
			(at 0 0 0)
			(unlocked yes)
			(layer "F.Fab")
			(hide yes)
			(effects
				(font
					(size 1 1)
					(thickness 0.15)
				)
			)
		)
		(property "Manufacturer" ""
			(at 0 0 0)
			(unlocked yes)
			(layer "F.Fab")
			(hide yes)
			(effects
				(font
					(size 1 1)
					(thickness 0.15)
				)
			)
		)
		(property "Author" "Antmicro"
			(at 0 0 0)
			(unlocked yes)
			(layer "F.Fab")
			(hide yes)
			(effects
				(font
					(size 1 1)
					(thickness 0.15)
				)
			)
		)
		(property "License" "Apache-2.0"
			(at 0 0 0)
			(unlocked yes)
			(layer "F.Fab")
			(hide yes)
			(effects
				(font
					(size 1 1)
					(thickness 0.15)
				)
			)
		)
		(sheetname "/Power/")
		(sheetfile "power.kicad_sch")
		(attr exclude_from_pos_files exclude_from_bom)
		(fp_circle
			(center 0 0)
			(end 0.475 0)
			(stroke
				(width 0.05)
				(type default)
			)
			(fill no)
			(layer "F.CrtYd")
		)
		(fp_text user "Author: Antmicro"
			(at -0.4 3.901 0)
			(layer "F.Fab")
			(effects
				(font
					(size 0.7 0.7)
					(thickness 0.15)
				)
				(justify left bottom)
			)
		)
		(fp_text user "License: Apache-2.0"
			(at -0.4 5.101 0)
			(layer "F.Fab")
			(effects
				(font
					(size 0.7 0.7)
					(thickness 0.15)
				)
				(justify left bottom)
			)
		)
		(fp_text user "${REFERENCE}"
			(at -0.4 2.7 0)
			(layer "F.Fab")
			(effects
				(font
					(size 0.7 0.7)
					(thickness 0.15)
				)
				(justify left bottom)
			)
		)
		(pad "1" smd circle
			(at 0 0)
			(size 0.75 0.75)
			(layers "F.Cu" "F.Mask")
			(net 522 "/Power/USBPD1_HV")
			(pinfunction "1")
			(pintype "passive")
		)
	)
	(footprint "antmicro-footprints:R_0402_1005Metric"
		(layer "F.Cu")
		(at 141.06 58.79 -90)
		(descr "Resistor SMD 0402")
		(tags "resistor SMD 0402")
		(property "Reference" "R416"
			(at 0.97 0.41 90)
			(layer "F.SilkS")
			(effects
				(font
					(size 0.7 0.7)
					(thickness 0.15)
				)
				(justify right top)
			)
		)
		(property "Value" "R_31k6_0402"
			(at -1.011843 1.772046 90)
			(layer "F.Fab")
			(effects
				(font
					(size 0.7 0.7)
					(thickness 0.15)
				)
				(justify right top)
			)
		)
		(property "Datasheet" "https://www.bourns.com/docs/product-datasheets/cr.pdf"
			(at 0 0 90)
			(layer "F.Fab")
			(hide yes)
			(effects
				(font
					(size 1.27 1.27)
					(thickness 0.15)
				)
			)
		)
		(property "Description" "SMD Chip Resistor"
			(at 0 0 90)
			(layer "F.Fab")
			(hide yes)
			(effects
				(font
					(size 1.27 1.27)
					(thickness 0.15)
				)
			)
		)
		(property "MPN" "CR0402-FX-3162GLF"
			(at 0 0 270)
			(unlocked yes)
			(layer "F.Fab")
			(hide yes)
			(effects
				(font
					(size 1 1)
					(thickness 0.15)
				)
			)
		)
		(property "Manufacturer" "Bourns"
			(at 0 0 270)
			(unlocked yes)
			(layer "F.Fab")
			(hide yes)
			(effects
				(font
					(size 1 1)
					(thickness 0.15)
				)
			)
		)
		(property "License" "Apache-2.0"
			(at 0 0 270)
			(unlocked yes)
			(layer "F.Fab")
			(hide yes)
			(effects
				(font
					(size 1 1)
					(thickness 0.15)
				)
			)
		)
		(property "Author" "Antmicro"
			(at 0 0 270)
			(unlocked yes)
			(layer "F.Fab")
			(hide yes)
			(effects
				(font
					(size 1 1)
					(thickness 0.15)
				)
			)
		)
		(property "Val" "31k6"
			(at 0 0 270)
			(unlocked yes)
			(layer "F.Fab")
			(hide yes)
			(effects
				(font
					(size 1 1)
					(thickness 0.15)
				)
			)
		)
		(property "Tolerance" "1%"
			(at 0 0 270)
			(unlocked yes)
			(layer "F.Fab")
			(hide yes)
			(effects
				(font
					(size 1 1)
					(thickness 0.15)
				)
			)
		)
		(sheetname "/Power/")
		(sheetfile "power.kicad_sch")
		(attr smd)
		(fp_poly
			(pts
				(xy -0.925 -0.47) (xy 0.925 -0.47) (xy 0.925 0.47) (xy -0.925 0.47)
			)
			(stroke
				(width 0.05)
				(type default)
			)
			(fill no)
			(layer "F.CrtYd")
		)
		(fp_poly
			(pts
				(xy -0.5 -0.25) (xy 0.5 -0.25) (xy 0.5 0.25) (xy -0.5 0.25)
			)
			(stroke
				(width 0.15)
				(type solid)
			)
			(fill no)
			(layer "F.Fab")
		)
		(fp_text user "${REFERENCE}"
			(at -0.95 3.168 90)
			(layer "F.Fab")
			(effects
				(font
					(size 0.7 0.7)
					(thickness 0.15)
				)
				(justify right top)
			)
		)
		(fp_text user "License: Apache-2.0"
			(at -0.949999 5.169 90)
			(layer "F.Fab")
			(effects
				(font
					(size 0.7 0.7)
					(thickness 0.15)
				)
				(justify right top)
			)
		)
		(fp_text user "Author: Antmicro"
			(at -0.95 4.169 90)
			(layer "F.Fab")
			(effects
				(font
					(size 0.7 0.7)
					(thickness 0.15)
				)
				(justify right top)
			)
		)
		(pad "1" smd roundrect
			(at -0.48 0 270)
			(size 0.59 0.64)
			(layers "F.Cu" "F.Mask" "F.Paste")
			(roundrect_rratio 0.25)
			(net 1396 "Net-(U79-ADJ)")
			(pintype "passive")
		)
		(pad "2" smd roundrect
			(at 0.48 0 270)
			(size 0.59 0.64)
			(layers "F.Cu" "F.Mask" "F.Paste")
			(roundrect_rratio 0.25)
			(net 31 "/Power/3V3_LDO")
			(pintype "passive")
		)
	)
	(footprint "antmicro-footprints:R_0402_1005Metric"
		(layer "F.Cu")
		(at 180.551652 124.197356 -90)
		(descr "Resistor SMD 0402")
		(tags "resistor SMD 0402")
		(property "Reference" "R39"
			(at -6.297356 -3.086529 90)
			(layer "F.SilkS")
			(effects
				(font
					(size 0.7 0.7)
					(thickness 0.15)
				)
				(justify right top)
			)
		)
		(property "Value" "R_499k_0402"
			(at -1.011843 1.772047 90)
			(layer "F.Fab")
			(effects
				(font
					(size 0.7 0.7)
					(thickness 0.15)
				)
				(justify right top)
			)
		)
		(property "Datasheet" "https://www.mouser.com/datasheet/2/54/cr-1858361.pdf"
			(at 0 0 90)
			(layer "F.Fab")
			(hide yes)
			(effects
				(font
					(size 1.27 1.27)
					(thickness 0.15)
				)
			)
		)
		(property "Description" "SMD Chip Resistor, 499 kohm, ± 1%, 63 mW, 0402 [1005 Metric], Thick Film, General Purpose"
			(at 0 0 90)
			(layer "F.Fab")
			(hide yes)
			(effects
				(font
					(size 1.27 1.27)
					(thickness 0.15)
				)
			)
		)
		(property "MPN" "CR0402-FX-4993GLF"
			(at 0 0 270)
			(unlocked yes)
			(layer "F.Fab")
			(hide yes)
			(effects
				(font
					(size 1 1)
					(thickness 0.15)
				)
			)
		)
		(property "Manufacturer" "Bourns"
			(at 0 0 270)
			(unlocked yes)
			(layer "F.Fab")
			(hide yes)
			(effects
				(font
					(size 1 1)
					(thickness 0.15)
				)
			)
		)
		(property "License" "Apache-2.0"
			(at 0 0 270)
			(unlocked yes)
			(layer "F.Fab")
			(hide yes)
			(effects
				(font
					(size 1 1)
					(thickness 0.15)
				)
			)
		)
		(property "Author" "Antmicro"
			(at 0 0 270)
			(unlocked yes)
			(layer "F.Fab")
			(hide yes)
			(effects
				(font
					(size 1 1)
					(thickness 0.15)
				)
			)
		)
		(property "Val" "499k"
			(at 0 0 270)
			(unlocked yes)
			(layer "F.Fab")
			(hide yes)
			(effects
				(font
					(size 1 1)
					(thickness 0.15)
				)
			)
		)
		(property "Tolerance" "1%"
			(at 0 0 270)
			(unlocked yes)
			(layer "F.Fab")
			(hide yes)
			(effects
				(font
					(size 1 1)
					(thickness 0.15)
				)
			)
		)
		(sheetname "/DCDC/")
		(sheetfile "dcdc.kicad_sch")
		(attr smd)
		(fp_rect
			(start -0.925 -0.47)
			(end 0.925 0.47)
			(stroke
				(width 0.05)
				(type default)
			)
			(fill no)
			(layer "F.CrtYd")
		)
		(fp_rect
			(start -0.5 -0.25)
			(end 0.5 0.25)
			(stroke
				(width 0.15)
				(type solid)
			)
			(fill no)
			(layer "F.Fab")
		)
		(fp_text user "${REFERENCE}"
			(at -0.95 3.168 90)
			(layer "F.Fab")
			(effects
				(font
					(size 0.7 0.7)
					(thickness 0.15)
				)
				(justify right top)
			)
		)
		(fp_text user "License: Apache-2.0"
			(at -0.95 5.169 90)
			(layer "F.Fab")
			(effects
				(font
					(size 0.7 0.7)
					(thickness 0.15)
				)
				(justify right top)
			)
		)
		(fp_text user "Author: Antmicro"
			(at -0.95 4.169 90)
			(layer "F.Fab")
			(effects
				(font
					(size 0.7 0.7)
					(thickness 0.15)
				)
				(justify right top)
			)
		)
		(pad "1" smd roundrect
			(at -0.48 0 270)
			(size 0.59 0.64)
			(layers "F.Cu" "F.Mask" "F.Paste")
			(roundrect_rratio 0.25)
			(net 1 "GND")
			(pintype "passive")
		)
		(pad "2" smd roundrect
			(at 0.48 0 270)
			(size 0.59 0.64)
			(layers "F.Cu" "F.Mask" "F.Paste")
			(roundrect_rratio 0.25)
			(net 1213 "/DCDC/3V3_MODE1")
			(pintype "passive")
		)
	)
	(footprint "antmicro-footprints:C_0805_2012Metric"
		(layer "F.Cu")
		(at 169.55 79.81 90)
		(descr "Capacitor SMD 0805")
		(tags "capacitor SMD 0805")
		(property "Reference" "C288"
			(at -4.67 0.23 90)
			(layer "F.SilkS")
			(effects
				(font
					(size 0.7 0.7)
					(thickness 0.15)
				)
				(justify left bottom)
			)
		)
		(property "Value" "C_22u_25V_0805"
			(at -2.055717 1.963152 90)
			(layer "F.Fab")
			(effects
				(font
					(size 0.7 0.7)
					(thickness 0.15)
				)
				(justify left bottom)
			)
		)
		(property "Datasheet" "https://product.samsungsem.com/mlcc/CL21A226MAYNNN.do"
			(at 0 0 90)
			(layer "F.Fab")
			(hide yes)
			(effects
				(font
					(size 1.27 1.27)
					(thickness 0.15)
				)
			)
		)
		(property "Description" "SMT Multilayer Ceramic Capacitor, 22uF, +/-20%, 25V, X5R, 0805 [2012 Metric]"
			(at 0 0 90)
			(layer "F.Fab")
			(hide yes)
			(effects
				(font
					(size 1.27 1.27)
					(thickness 0.15)
				)
			)
		)
		(property "MPN" "CL21A226MAYNNNE"
			(at 0 0 90)
			(unlocked yes)
			(layer "F.Fab")
			(hide yes)
			(effects
				(font
					(size 1 1)
					(thickness 0.15)
				)
			)
		)
		(property "Manufacturer" "Samsung Electro-Mechanics"
			(at 0 0 90)
			(unlocked yes)
			(layer "F.Fab")
			(hide yes)
			(effects
				(font
					(size 1 1)
					(thickness 0.15)
				)
			)
		)
		(property "License" "Apache-2.0"
			(at 0 0 90)
			(unlocked yes)
			(layer "F.Fab")
			(hide yes)
			(effects
				(font
					(size 1 1)
					(thickness 0.15)
				)
			)
		)
		(property "Author" "Antmicro"
			(at 0 0 90)
			(unlocked yes)
			(layer "F.Fab")
			(hide yes)
			(effects
				(font
					(size 1 1)
					(thickness 0.15)
				)
			)
		)
		(property "Val" "22u"
			(at 0 0 90)
			(unlocked yes)
			(layer "F.Fab")
			(hide yes)
			(effects
				(font
					(size 1 1)
					(thickness 0.15)
				)
			)
		)
		(property "Voltage" "25V"
			(at 0 0 90)
			(unlocked yes)
			(layer "F.Fab")
			(hide yes)
			(effects
				(font
					(size 1 1)
					(thickness 0.15)
				)
			)
		)
		(property "Dielectric" "X5R"
			(at 0 0 90)
			(unlocked yes)
			(layer "F.Fab")
			(hide yes)
			(effects
				(font
					(size 1 1)
					(thickness 0.15)
				)
			)
		)
		(property "Public" "False"
			(at 0 0 90)
			(unlocked yes)
			(layer "F.Fab")
			(hide yes)
			(effects
				(font
					(size 1 1)
					(thickness 0.15)
				)
			)
		)
		(component_classes
			(class "DCDC_20V")
		)
		(sheetname "/DCDC/")
		(sheetfile "dcdc.kicad_sch")
		(attr smd)
		(fp_line
			(start -0.3 -0.7)
			(end 0.3 -0.7)
			(stroke
				(width 0.15)
				(type solid)
			)
			(layer "F.SilkS")
		)
		(fp_line
			(start -0.3 0.7)
			(end 0.3 0.7)
			(stroke
				(width 0.15)
				(type solid)
			)
			(layer "F.SilkS")
		)
		(fp_rect
			(start 1.95 -0.9)
			(end -1.95 0.9)
			(stroke
				(width 0.05)
				(type default)
			)
			(fill no)
			(layer "F.CrtYd")
		)
		(fp_rect
			(start -0.95 -0.675)
			(end 0.95 0.675)
			(stroke
				(width 0.15)
				(type solid)
			)
			(fill no)
			(layer "F.Fab")
		)
		(fp_text user "Author: Antmicro"
			(at -1.9 5.947 90)
			(layer "F.Fab")
			(effects
				(font
					(size 0.7 0.7)
					(thickness 0.15)
				)
				(justify left bottom)
			)
		)
		(fp_text user "License: Apache-2.0"
			(at -1.9 4.947 90)
			(layer "F.Fab")
			(effects
				(font
					(size 0.7 0.7)
					(thickness 0.15)
				)
				(justify left bottom)
			)
		)
		(fp_text user "${REFERENCE}"
			(at -1.9 3.947 90)
			(layer "F.Fab")
			(effects
				(font
					(size 0.7 0.7)
					(thickness 0.15)
				)
				(justify left bottom)
			)
		)
		(pad "1" smd roundrect
			(at -1.1 0 90)
			(size 1.2 1.3)
			(layers "F.Cu" "F.Mask" "F.Paste")
			(roundrect_rratio 0.25)
			(net 1 "GND")
			(pintype "passive")
		)
		(pad "2" smd roundrect
			(at 1.1 0 90)
			(size 1.2 1.3)
			(layers "F.Cu" "F.Mask" "F.Paste")
			(roundrect_rratio 0.25)
			(net 1105 "/DCDC/20V_OUT")
			(pintype "passive")
		)
	)
	(footprint "antmicro-footprints:USON-10_2.5x1mm_P0.5mm"
		(layer "F.Cu")
		(at 228 82)
		(descr "USON-10 2.5x1mm_ Pitch 0.5mm")
		(tags "USON-10 2.5x1mm Pitch 0.5mm")
		(property "Reference" "U42"
			(at -1 1.123 90)
			(layer "F.SilkS")
			(effects
				(font
					(size 0.7 0.7)
					(thickness 0.15)
				)
				(justify left bottom)
			)
		)
		(property "Value" "TPD4E05U06QDQARQ1"
			(at 0.018 2.499 0)
			(layer "F.Fab")
			(effects
				(font
					(size 0.7 0.7)
					(thickness 0.15)
				)
				(justify left bottom)
			)
		)
		(property "Datasheet" "https://www.ti.com/lit/ds/symlink/tpd4e05u06-q1.pdf?HQS=dis-mous-null-mousermode-dsf-pf-null-wwe&ts=1663591265741&ref_url=https%253A%252F%252Fwww.mouser.com%252F"
			(at 0 0 0)
			(layer "F.Fab")
			(hide yes)
			(effects
				(font
					(size 1.27 1.27)
					(thickness 0.15)
				)
			)
		)
		(property "Description" "TVS diode array, 12 kV, USON-10, 5.5 V, 0.5 pF"
			(at 0 0 0)
			(layer "F.Fab")
			(hide yes)
			(effects
				(font
					(size 1.27 1.27)
					(thickness 0.15)
				)
			)
		)
		(property "Manufacturer" "Texas Instruments"
			(at 0 0 0)
			(unlocked yes)
			(layer "F.Fab")
			(hide yes)
			(effects
				(font
					(size 1 1)
					(thickness 0.15)
				)
			)
		)
		(property "MPN" "TPD4E05U06QDQARQ1"
			(at 0 0 0)
			(unlocked yes)
			(layer "F.Fab")
			(hide yes)
			(effects
				(font
					(size 1 1)
					(thickness 0.15)
				)
			)
		)
		(property "Author" "Antmicro"
			(at 0 0 0)
			(unlocked yes)
			(layer "F.Fab")
			(hide yes)
			(effects
				(font
					(size 1 1)
					(thickness 0.15)
				)
			)
		)
		(property "License" "Apache-2.0"
			(at 0 0 0)
			(unlocked yes)
			(layer "F.Fab")
			(hide yes)
			(effects
				(font
					(size 1 1)
					(thickness 0.15)
				)
			)
		)
		(sheetname "/USB Debug, PD/")
		(sheetfile "usb_debug_pd.kicad_sch")
		(attr smd)
		(fp_line
			(start 0.498 -1.401)
			(end -0.5 -1.401)
			(stroke
				(width 0.15)
				(type solid)
			)
			(layer "F.SilkS")
		)
		(fp_line
			(start 0.498 1.398)
			(end -0.5 1.398)
			(stroke
				(width 0.15)
				(type solid)
			)
			(layer "F.SilkS")
		)
		(fp_circle
			(center -0.68 -1.27)
			(end -0.63 -1.27)
			(stroke
				(width 0.15)
				(type solid)
			)
			(fill yes)
			(layer "F.SilkS")
		)
		(fp_poly
			(pts
				(xy -0.8 -1.5) (xy 0.8 -1.5) (xy 0.799999 1.499) (xy -0.799999 1.499)
			)
			(stroke
				(width 0.05)
				(type solid)
			)
			(fill no)
			(layer "F.CrtYd")
		)
		(fp_line
			(start -0.5 -1)
			(end -0.5 1.249)
			(stroke
				(width 0.15)
				(type solid)
			)
			(layer "F.Fab")
		)
		(fp_line
			(start -0.5 1.249)
			(end 0.498 1.249)
			(stroke
				(width 0.15)
				(type solid)
			)
			(layer "F.Fab")
		)
		(fp_line
			(start -0.25 -1.25)
			(end -0.5 -1)
			(stroke
				(width 0.15)
				(type solid)
			)
			(layer "F.Fab")
		)
		(fp_line
			(start 0.498 -1.25)
			(end -0.25 -1.25)
			(stroke
				(width 0.15)
				(type solid)
			)
			(layer "F.Fab")
		)
		(fp_line
			(start 0.498 -1.25)
			(end 0.498 1.249)
			(stroke
				(width 0.15)
				(type solid)
			)
			(layer "F.Fab")
		)
		(fp_text user "${REFERENCE}"
			(at -0.802 4.498 0)
			(layer "F.Fab")
			(effects
				(font
					(size 0.7 0.7)
					(thickness 0.15)
				)
				(justify left bottom)
			)
		)
		(fp_text user "Author: Antmicro"
			(at -0.802 5.7 0)
			(layer "F.Fab")
			(effects
				(font
					(size 0.7 0.7)
					(thickness 0.15)
				)
				(justify left bottom)
			)
		)
		(fp_text user "License: Apache-2.0"
			(at -0.802 6.9 0)
			(layer "F.Fab")
			(effects
				(font
					(size 0.7 0.7)
					(thickness 0.15)
				)
				(justify left bottom)
			)
		)
		(pad "1" smd roundrect
			(at -0.387 -1 270)
			(size 0.25 0.55)
			(layers "F.Cu" "F.Mask" "F.Paste")
			(roundrect_rratio 0.25)
			(net 514 "/USB Debug, PD/USBC0_CC1")
			(pintype "passive")
		)
		(pad "2" smd roundrect
			(at -0.387 -0.5 270)
			(size 0.25 0.55)
			(layers "F.Cu" "F.Mask" "F.Paste")
			(roundrect_rratio 0.25)
			(net 488 "/USB Debug, PD/USBC0_D_N")
			(pintype "passive")
		)
		(pad "3" smd roundrect
			(at -0.387 0 270)
			(size 0.4 0.55)
			(layers "F.Cu" "F.Mask" "F.Paste")
			(roundrect_rratio 0.25)
			(net 1 "GND")
			(pintype "power_in")
		)
		(pad "4" smd roundrect
			(at -0.387 0.498 270)
			(size 0.25 0.55)
			(layers "F.Cu" "F.Mask" "F.Paste")
			(roundrect_rratio 0.25)
			(net 489 "/USB Debug, PD/USBC0_D_P")
			(pintype "passive")
		)
		(pad "5" smd roundrect
			(at -0.387 0.998 270)
			(size 0.25 0.55)
			(layers "F.Cu" "F.Mask" "F.Paste")
			(roundrect_rratio 0.25)
			(net 515 "/USB Debug, PD/USBC0_CC2")
			(pintype "passive")
		)
		(pad "6" smd roundrect
			(at 0.385001 0.998 270)
			(size 0.25 0.55)
			(layers "F.Cu" "F.Mask" "F.Paste")
			(roundrect_rratio 0.25)
			(net 515 "/USB Debug, PD/USBC0_CC2")
			(pintype "passive")
		)
		(pad "7" smd roundrect
			(at 0.385 0.498 270)
			(size 0.25 0.55)
			(layers "F.Cu" "F.Mask" "F.Paste")
			(roundrect_rratio 0.25)
			(net 489 "/USB Debug, PD/USBC0_D_P")
			(pintype "passive")
		)
		(pad "8" smd roundrect
			(at 0.385 0 270)
			(size 0.4 0.55)
			(layers "F.Cu" "F.Mask" "F.Paste")
			(roundrect_rratio 0.25)
			(net 1 "GND")
			(pintype "passive")
		)
		(pad "9" smd roundrect
			(at 0.385001 -0.5 270)
			(size 0.25 0.55)
			(layers "F.Cu" "F.Mask" "F.Paste")
			(roundrect_rratio 0.25)
			(net 488 "/USB Debug, PD/USBC0_D_N")
			(pintype "passive")
		)
		(pad "10" smd roundrect
			(at 0.385 -1 270)
			(size 0.25 0.55)
			(layers "F.Cu" "F.Mask" "F.Paste")
			(roundrect_rratio 0.25)
			(net 514 "/USB Debug, PD/USBC0_CC1")
			(pintype "passive")
		)
	)
	(footprint "antmicro-footprints:C_0603_1608Metric_EIA"
		(layer "F.Cu")
		(at 143.774391 128.15 -90)
		(descr "Capacitor SMD 0603, IPC-7351 Density Level A")
		(tags "Capacitor 0603")
		(property "Reference" "C32"
			(at -3.4 0.574391 90)
			(layer "F.SilkS")
			(effects
				(font
					(size 0.7 0.7)
					(thickness 0.15)
				)
				(justify right top)
			)
		)
		(property "Value" "C_22u_16V_0603"
			(at -1.42757 1.770288 90)
			(layer "F.Fab")
			(effects
				(font
					(size 0.7 0.7)
					(thickness 0.15)
				)
				(justify right top)
			)
		)
		(property "Datasheet" "https://product.samsungsem.com/mlcc/CL10A226MO7JZN.do"
			(at 0 0 90)
			(layer "F.Fab")
			(hide yes)
			(effects
				(font
					(size 1.27 1.27)
					(thickness 0.15)
				)
			)
		)
		(property "Description" "SMD Multilayer Ceramic Capacitor"
			(at 0 0 90)
			(layer "F.Fab")
			(hide yes)
			(effects
				(font
					(size 1.27 1.27)
					(thickness 0.15)
				)
			)
		)
		(property "MPN" "CL10A226MO7JZNC"
			(at 0 0 270)
			(unlocked yes)
			(layer "F.Fab")
			(hide yes)
			(effects
				(font
					(size 1 1)
					(thickness 0.15)
				)
			)
		)
		(property "Manufacturer" "Samsung Electro-Mechanics"
			(at 0 0 270)
			(unlocked yes)
			(layer "F.Fab")
			(hide yes)
			(effects
				(font
					(size 1 1)
					(thickness 0.15)
				)
			)
		)
		(property "License" "Apache-2.0"
			(at 0 0 270)
			(unlocked yes)
			(layer "F.Fab")
			(hide yes)
			(effects
				(font
					(size 1 1)
					(thickness 0.15)
				)
			)
		)
		(property "Author" "Antmicro"
			(at 0 0 270)
			(unlocked yes)
			(layer "F.Fab")
			(hide yes)
			(effects
				(font
					(size 1 1)
					(thickness 0.15)
				)
			)
		)
		(property "Val" "22u"
			(at 0 0 270)
			(unlocked yes)
			(layer "F.Fab")
			(hide yes)
			(effects
				(font
					(size 1 1)
					(thickness 0.15)
				)
			)
		)
		(property "Voltage" "16V"
			(at 0 0 270)
			(unlocked yes)
			(layer "F.Fab")
			(hide yes)
			(effects
				(font
					(size 1 1)
					(thickness 0.15)
				)
			)
		)
		(property "Dielectric" ""
			(at 0 0 270)
			(unlocked yes)
			(layer "F.Fab")
			(hide yes)
			(effects
				(font
					(size 1 1)
					(thickness 0.15)
				)
			)
		)
		(property "Public" "False"
			(at 0 0 270)
			(unlocked yes)
			(layer "F.Fab")
			(hide yes)
			(effects
				(font
					(size 1 1)
					(thickness 0.15)
				)
			)
		)
		(component_classes
			(class "DCDC_1V8")
		)
		(sheetname "/DCDC/")
		(sheetfile "dcdc.kicad_sch")
		(attr smd)
		(fp_line
			(start -0.15 0.55)
			(end 0.15 0.55)
			(stroke
				(width 0.15)
				(type solid)
			)
			(layer "F.SilkS")
		)
		(fp_line
			(start -0.15 -0.55)
			(end 0.15 -0.55)
			(stroke
				(width 0.15)
				(type solid)
			)
			(layer "F.SilkS")
		)
		(fp_rect
			(start -1.25 -0.65)
			(end 1.25 0.65)
			(stroke
				(width 0.05)
				(type solid)
			)
			(fill no)
			(layer "F.CrtYd")
		)
		(fp_rect
			(start -0.8 -0.45)
			(end 0.8 0.45)
			(stroke
				(width 0.15)
				(type solid)
			)
			(fill no)
			(layer "F.Fab")
		)
		(fp_text user "${REFERENCE}"
			(at -1.682 3.895 90)
			(layer "F.Fab")
			(effects
				(font
					(size 0.7 0.7)
					(thickness 0.15)
				)
				(justify right top)
			)
		)
		(fp_text user "Author: Antmicro"
			(at -1.682 4.894 90)
			(layer "F.Fab")
			(effects
				(font
					(size 0.7 0.7)
					(thickness 0.15)
				)
				(justify right top)
			)
		)
		(fp_text user "License: Apache-2.0"
			(at -1.682 5.895 90)
			(layer "F.Fab")
			(effects
				(font
					(size 0.7 0.7)
					(thickness 0.15)
				)
				(justify right top)
			)
		)
		(pad "1" smd roundrect
			(at -0.7 0 270)
			(size 0.8 1.1)
			(layers "F.Cu" "F.Mask" "F.Paste")
			(roundrect_rratio 0.2)
			(net 1 "GND")
			(pintype "passive")
		)
		(pad "2" smd roundrect
			(at 0.7 0 270)
			(size 0.8 1.1)
			(layers "F.Cu" "F.Mask" "F.Paste")
			(roundrect_rratio 0.2)
			(net 5 "+5V")
			(pintype "passive")
		)
	)
	(footprint "antmicro-footprints:MLP44-24L_4x4x0.75mm"
		(layer "F.Cu")
		(at 126.769212 61.55 -90)
		(property "Reference" "U75"
			(at -3.17 -2.480788 0)
			(layer "F.SilkS")
			(effects
				(font
					(size 0.7 0.7)
					(thickness 0.15)
				)
				(justify right top)
			)
		)
		(property "Value" "SIC437AED-T1-GE3"
			(at -2.7 3.6 90)
			(layer "F.Fab")
			(effects
				(font
					(size 0.7 0.7)
					(thickness 0.15)
				)
				(justify right top)
			)
		)
		(property "Datasheet" "https://www.vishay.com/docs/75921/sic437.pdf"
			(at 0 0 90)
			(layer "F.Fab")
			(hide yes)
			(effects
				(font
					(size 1.27 1.27)
					(thickness 0.15)
				)
			)
		)
		(property "Description" "DC/DC Buck Step Down Regulator Adjustable, 4.5-28V In, 0.6V to 20V/12A Out, 1MHz, PowerPAK MLP44-24"
			(at 0 0 90)
			(layer "F.Fab")
			(hide yes)
			(effects
				(font
					(size 1.27 1.27)
					(thickness 0.15)
				)
			)
		)
		(property "Manufacturer" "Vishay"
			(at 0 0 270)
			(unlocked yes)
			(layer "F.Fab")
			(hide yes)
			(effects
				(font
					(size 1 1)
					(thickness 0.15)
				)
			)
		)
		(property "MPN" "SIC437AED-T1-GE3"
			(at 0 0 270)
			(unlocked yes)
			(layer "F.Fab")
			(hide yes)
			(effects
				(font
					(size 1 1)
					(thickness 0.15)
				)
			)
		)
		(property "Author" "Antmicro"
			(at 0 0 270)
			(unlocked yes)
			(layer "F.Fab")
			(hide yes)
			(effects
				(font
					(size 1 1)
					(thickness 0.15)
				)
			)
		)
		(property "License" "Apache-2.0"
			(at 0 0 270)
			(unlocked yes)
			(layer "F.Fab")
			(hide yes)
			(effects
				(font
					(size 1 1)
					(thickness 0.15)
				)
			)
		)
		(sheetname "/DCDC/")
		(sheetfile "dcdc.kicad_sch")
		(attr smd)
		(net_tie_pad_groups "1,2,26" "3,4,27" "5,6,7,8,9")
		(fp_line
			(start -2.11 2.11)
			(end -2.11 1.39)
			(stroke
				(width 0.15)
				(type solid)
			)
			(layer "F.SilkS")
		)
		(fp_line
			(start -1.89 2.11)
			(end -2.11 2.11)
			(stroke
				(width 0.15)
				(type solid)
			)
			(layer "F.SilkS")
		)
		(fp_line
			(start 1.44 2.11)
			(end 2.11 2.11)
			(stroke
				(width 0.15)
				(type solid)
			)
			(layer "F.SilkS")
		)
		(fp_line
			(start 2.11 2.11)
			(end 2.11 1.84)
			(stroke
				(width 0.15)
				(type solid)
			)
			(layer "F.SilkS")
		)
		(fp_line
			(start -2.11 -1.38)
			(end -2.11 -2.1)
			(stroke
				(width 0.15)
				(type solid)
			)
			(layer "F.SilkS")
		)
		(fp_line
			(start -1.89 -2.1)
			(end -2.11 -2.1)
			(stroke
				(width 0.15)
				(type solid)
			)
			(layer "F.SilkS")
		)
		(fp_line
			(start 1.89 -2.11)
			(end 2.11 -2.11)
			(stroke
				(width 0.15)
				(type solid)
			)
			(layer "F.SilkS")
		)
		(fp_line
			(start 2.11 -2.11)
			(end 2.11 -1.69)
			(stroke
				(width 0.15)
				(type solid)
			)
			(layer "F.SilkS")
		)
		(fp_circle
			(center -2.25 -1.15)
			(end -2.2 -1.15)
			(stroke
				(width 0.15)
				(type solid)
			)
			(fill yes)
			(layer "F.SilkS")
		)
		(fp_line
			(start -2.55 2.55)
			(end -2.55 -2.55)
			(stroke
				(width 0.05)
				(type solid)
			)
			(layer "F.CrtYd")
		)
		(fp_line
			(start 2.55 2.55)
			(end -2.55 2.55)
			(stroke
				(width 0.05)
				(type solid)
			)
			(layer "F.CrtYd")
		)
		(fp_line
			(start -2.55 -2.55)
			(end 2.55 -2.55)
			(stroke
				(width 0.05)
				(type solid)
			)
			(layer "F.CrtYd")
		)
		(fp_line
			(start 2.55 -2.55)
			(end 2.55 2.55)
			(stroke
				(width 0.05)
				(type solid)
			)
			(layer "F.CrtYd")
		)
		(fp_line
			(start -2 2)
			(end 2 2)
			(stroke
				(width 0.15)
				(type solid)
			)
			(layer "F.Fab")
		)
		(fp_line
			(start 2 2)
			(end 2 -2)
			(stroke
				(width 0.15)
				(type solid)
			)
			(layer "F.Fab")
		)
		(fp_line
			(start -2 -1)
			(end -2 2)
			(stroke
				(width 0.15)
				(type solid)
			)
			(layer "F.Fab")
		)
		(fp_line
			(start -1 -2)
			(end -2 -1)
			(stroke
				(width 0.15)
				(type solid)
			)
			(layer "F.Fab")
		)
		(fp_line
			(start 2 -2)
			(end -1 -2)
			(stroke
				(width 0.15)
				(type solid)
			)
			(layer "F.Fab")
		)
		(fp_text user "License: Apache-2.0"
			(at -2.7 5.6 90)
			(layer "F.Fab")
			(effects
				(font
					(size 0.7 0.7)
					(thickness 0.15)
				)
				(justify right top)
			)
		)
		(fp_text user "${REFERENCE}"
			(at -2.7 6.8 90)
			(layer "F.Fab")
			(effects
				(font
					(size 0.7 0.7)
					(thickness 0.15)
				)
				(justify right top)
			)
		)
		(fp_text user "Author: Antmicro"
			(at -2.7 8 90)
			(layer "F.Fab")
			(effects
				(font
					(size 0.7 0.7)
					(thickness 0.15)
				)
				(justify right top)
			)
		)
		(pad "1" smd roundrect
			(at -1.94 -0.825)
			(size 0.3 0.725)
			(layers "F.Cu" "F.Mask" "F.Paste")
			(roundrect_rratio 0.25)
			(net 13 "VCC")
			(pinfunction "V_{IN}")
			(pintype "power_in")
		)
		(pad "2" smd roundrect
			(at -1.94 -0.375)
			(size 0.3 0.725)
			(layers "F.Cu" "F.Mask" "F.Paste")
			(roundrect_rratio 0.25)
			(net 13 "VCC")
			(pinfunction "V_{IN}")
			(pintype "passive")
		)
		(pad "3" smd roundrect
			(at -1.94 0.525)
			(size 0.3 0.725)
			(layers "F.Cu" "F.Mask" "F.Paste")
			(roundrect_rratio 0.25)
			(net 1 "GND")
			(pinfunction "P_{GND}")
			(pintype "passive")
		)
		(pad "4" smd roundrect
			(at -1.94 0.975)
			(size 0.3 0.725)
			(layers "F.Cu" "F.Mask" "F.Paste")
			(roundrect_rratio 0.25)
			(net 1 "GND")
			(pinfunction "P_{GND}")
			(pintype "passive")
		)
		(pad "5" smd custom
			(at -1.475 1.94 270)
			(size 0.3 0.3)
			(layers "F.Cu" "F.Mask" "F.Paste")
			(net 1297 "/DCDC/5V_{AON}_SW")
			(pinfunction "SW")
			(pintype "passive")
			(options
				(clearance outline)
				(anchor circle)
			)
			(primitives
				(gr_poly
					(pts
						(xy -0.15 -0.2875) (xy -0.144291 -0.316201) (xy -0.128033 -0.340533) (xy -0.103701 -0.356791)
						(xy -0.075 -0.3625) (xy 0.075 -0.3625) (xy 0.103701 -0.356791) (xy 0.128033 -0.340533) (xy 0.144291 -0.316201)
						(xy 0.15 -0.2875) (xy 0.15 0.2875) (xy 0.144291 0.316201) (xy 0.128033 0.340533) (xy 0.103701 0.356791)
						(xy 0.075 0.3625) (xy -0.075 0.3625) (xy -0.103701 0.356791) (xy -0.128033 0.340533) (xy -0.144291 0.316201)
						(xy -0.15 0.2875)
					)
					(width 0)
					(fill yes)
				)
				(gr_poly
					(pts
						(xy -0.15 -0.3625) (xy 2.2 -0.3625) (xy 2.2 -0.0875) (xy -0.15 -0.0875)
					)
					(width 0)
					(fill yes)
				)
			)
		)
		(pad "6" smd roundrect
			(at -1.025 1.94 270)
			(size 0.3 0.725)
			(layers "F.Cu" "F.Mask" "F.Paste")
			(roundrect_rratio 0.25)
			(net 1297 "/DCDC/5V_{AON}_SW")
			(pinfunction "SW")
			(pintype "passive")
		)
		(pad "7" smd roundrect
			(at -0.575 1.94 270)
			(size 0.3 0.725)
			(layers "F.Cu" "F.Mask" "F.Paste")
			(roundrect_rratio 0.25)
			(net 1297 "/DCDC/5V_{AON}_SW")
			(pinfunction "SW")
			(pintype "passive")
		)
		(pad "8" smd roundrect
			(at 0.125 1.94 270)
			(size 0.3 0.725)
			(layers "F.Cu" "F.Mask" "F.Paste")
			(roundrect_rratio 0.25)
			(net 1297 "/DCDC/5V_{AON}_SW")
			(pinfunction "SW")
			(pintype "passive")
		)
		(pad "9" smd roundrect
			(at 0.575 1.94 270)
			(size 0.3 0.725)
			(layers "F.Cu" "F.Mask" "F.Paste")
			(roundrect_rratio 0.25)
			(net 1297 "/DCDC/5V_{AON}_SW")
			(pinfunction "SW")
			(pintype "passive")
		)
		(pad "10" smd roundrect
			(at 1.025 1.935 270)
			(size 0.3 0.725)
			(layers "F.Cu" "F.Mask" "F.Paste")
			(roundrect_rratio 0.25)
			(net 1326 "unconnected-(U75-GL-Pad10)_1")
			(pinfunction "GL")
			(pintype "passive+no_connect")
		)
		(pad "11" smd roundrect
			(at 1.94 1.425)
			(size 0.3 0.725)
			(layers "F.Cu" "F.Mask" "F.Paste")
			(roundrect_rratio 0.25)
			(net 1327 "unconnected-(U75-GL-Pad10)_2")
			(pinfunction "GL")
			(pintype "passive+no_connect")
		)
		(pad "12" smd roundrect
			(at 1.94 0.975)
			(size 0.3 0.725)
			(layers "F.Cu" "F.Mask" "F.Paste")
			(roundrect_rratio 0.25)
			(net 1275 "/DCDC/5V_{AON}_VDRV")
			(pinfunction "V_{DRV}")
			(pintype "passive")
		)
		(pad "13" smd roundrect
			(at 1.94 0.525)
			(size 0.3 0.725)
			(layers "F.Cu" "F.Mask" "F.Paste")
			(roundrect_rratio 0.25)
			(net 1 "GND")
			(pinfunction "P_{GND}")
			(pintype "power_in")
		)
		(pad "14" smd roundrect
			(at 1.94 0.075)
			(size 0.3 0.725)
			(layers "F.Cu" "F.Mask" "F.Paste")
			(roundrect_rratio 0.25)
			(net 246 "/SoM_Power/~{VDDIN_PWR_BAD}")
			(pinfunction "P_{GOOD}")
			(pintype "output")
		)
		(pad "15" smd roundrect
			(at 1.94 -0.375)
			(size 0.3 0.725)
			(layers "F.Cu" "F.Mask" "F.Paste")
			(roundrect_rratio 0.25)
			(net 1274 "/DCDC/5V_{AON}_VDD")
			(pinfunction "V_{DD}")
			(pintype "passive")
		)
		(pad "16" smd roundrect
			(at 1.94 -0.825)
			(size 0.3 0.725)
			(layers "F.Cu" "F.Mask" "F.Paste")
			(roundrect_rratio 0.25)
			(net 1 "GND")
			(pinfunction "A_{GND}")
			(pintype "power_in")
		)
		(pad "17" smd roundrect
			(at 1.94 -1.275)
			(size 0.3 0.725)
			(layers "F.Cu" "F.Mask" "F.Paste")
			(roundrect_rratio 0.25)
			(net 1308 "/DCDC/5V_{AON}_FB")
			(pinfunction "FB")
			(pintype "passive")
		)
		(pad "18" smd roundrect
			(at 1.475 -1.94 270)
			(size 0.3 0.725)
			(layers "F.Cu" "F.Mask" "F.Paste")
			(roundrect_rratio 0.25)
			(net 1278 "/DCDC/5V_{AON}_OUT")
			(pinfunction "V_{OUT}")
			(pintype "passive")
		)
		(pad "19" smd roundrect
			(at 1.025 -1.94 270)
			(size 0.3 0.725)
			(layers "F.Cu" "F.Mask" "F.Paste")
			(roundrect_rratio 0.25)
			(net 1305 "/DCDC/5V_{AON}_EN")
			(pinfunction "EN")
			(pintype "input")
		)
		(pad "20" smd roundrect
			(at 0.575 -1.94 270)
			(size 0.3 0.725)
			(layers "F.Cu" "F.Mask" "F.Paste")
			(roundrect_rratio 0.25)
			(net 1307 "/DCDC/5V_{AON}_MODE2")
			(pinfunction "MODE2")
			(pintype "input")
		)
		(pad "21" smd roundrect
			(at 0.125 -1.94 270)
			(size 0.3 0.725)
			(layers "F.Cu" "F.Mask" "F.Paste")
			(roundrect_rratio 0.25)
			(net 1306 "/DCDC/5V_{AON}_MODE1")
			(pinfunction "MODE1")
			(pintype "input")
		)
		(pad "22" smd roundrect
			(at -0.575 -1.94 270)
			(size 0.3 0.725)
			(layers "F.Cu" "F.Mask" "F.Paste")
			(roundrect_rratio 0.25)
			(net 13 "VCC")
			(pinfunction "V_{IN}")
			(pintype "passive")
		)
		(pad "23" smd roundrect
			(at -1.025 -1.94 270)
			(size 0.3 0.725)
			(layers "F.Cu" "F.Mask" "F.Paste")
			(roundrect_rratio 0.25)
			(net 1276 "/DCDC/5V_{AON}_BOOT")
			(pinfunction "BOOT")
			(pintype "passive")
		)
		(pad "24" smd roundrect
			(at -1.475 -1.94 270)
			(size 0.3 0.725)
			(layers "F.Cu" "F.Mask" "F.Paste")
			(roundrect_rratio 0.25)
			(net 1277 "/DCDC/5V_{AON}_PHASE")
			(pinfunction "PHASE")
			(pintype "passive")
		)
		(pad "25" smd rect
			(at 0.49 -0.75 90)
			(size 1.575 1.05)
			(layers "F.Cu" "F.Mask" "F.Paste")
			(net 1 "GND")
			(pinfunction "A_{GND}")
			(pintype "passive")
		)
		(pad "26" smd rect
			(at -1.175 -0.750001 90)
			(size 1.15 1.05)
			(layers "F.Cu" "F.Mask" "F.Paste")
			(net 13 "VCC")
			(pinfunction "V_{IN}")
			(pintype "passive")
		)
		(pad "27" smd custom
			(at -0.75 0.775 270)
			(size 1 1)
			(layers "F.Cu" "F.Mask" "F.Paste")
			(net 1 "GND")
			(pinfunction "P_{GND}")
			(pintype "passive")
			(options
				(clearance outline)
				(anchor rect)
			)
			(primitives
				(gr_poly
					(pts
						(xy -1 0.5) (xy -1 -0.7) (xy 1.825 -0.7) (xy 1.825 -0.245) (xy 1.175 -0.245) (xy 1.175 0.5)
					)
					(width 0)
					(fill yes)
				)
			)
		)
		(pad "28" smd rect
			(at 0.985 0.99 90)
			(size 0.58 0.38)
			(layers "F.Cu" "F.Mask" "F.Paste")
			(net 1325 "unconnected-(U75-GL-Pad10)")
			(pinfunction "GL")
			(pintype "passive+no_connect")
		)
	)
	(footprint "antmicro-footprints:R_0402_1005Metric"
		(layer "F.Cu")
		(at 94 59.5 180)
		(descr "Resistor SMD 0402")
		(tags "resistor SMD 0402")
		(property "Reference" "R308"
			(at -9.7 -0.8 0)
			(layer "F.SilkS")
			(effects
				(font
					(size 0.7 0.7)
					(thickness 0.15)
				)
				(justify right top)
			)
		)
		(property "Value" "R_100k_0402"
			(at -1.011843 1.772047 0)
			(layer "F.Fab")
			(effects
				(font
					(size 0.7 0.7)
					(thickness 0.15)
				)
				(justify right top)
			)
		)
		(property "Datasheet" "https://www.bourns.com/docs/product-datasheets/cr.pdf"
			(at 0 0 0)
			(layer "F.Fab")
			(hide yes)
			(effects
				(font
					(size 1.27 1.27)
					(thickness 0.15)
				)
			)
		)
		(property "Description" "SMD Chip Resistor, 100 kohm, ± 1%, 62.5 mW, 0402 [1005 Metric], Thick Film, General Purpose"
			(at 0 0 0)
			(layer "F.Fab")
			(hide yes)
			(effects
				(font
					(size 1.27 1.27)
					(thickness 0.15)
				)
			)
		)
		(property "MPN" "CR0402-FX-1003GLF"
			(at 0 0 180)
			(unlocked yes)
			(layer "F.Fab")
			(hide yes)
			(effects
				(font
					(size 1 1)
					(thickness 0.15)
				)
			)
		)
		(property "Manufacturer" "Bourns"
			(at 0 0 180)
			(unlocked yes)
			(layer "F.Fab")
			(hide yes)
			(effects
				(font
					(size 1 1)
					(thickness 0.15)
				)
			)
		)
		(property "License" "Apache-2.0"
			(at 0 0 180)
			(unlocked yes)
			(layer "F.Fab")
			(hide yes)
			(effects
				(font
					(size 1 1)
					(thickness 0.15)
				)
			)
		)
		(property "Author" "Antmicro"
			(at 0 0 180)
			(unlocked yes)
			(layer "F.Fab")
			(hide yes)
			(effects
				(font
					(size 1 1)
					(thickness 0.15)
				)
			)
		)
		(property "Val" "100k"
			(at 0 0 180)
			(unlocked yes)
			(layer "F.Fab")
			(hide yes)
			(effects
				(font
					(size 1 1)
					(thickness 0.15)
				)
			)
		)
		(property "Tolerance" "1%"
			(at 0 0 180)
			(unlocked yes)
			(layer "F.Fab")
			(hide yes)
			(effects
				(font
					(size 1 1)
					(thickness 0.15)
				)
			)
		)
		(property "Public" "False"
			(at 0 0 180)
			(unlocked yes)
			(layer "F.Fab")
			(hide yes)
			(effects
				(font
					(size 1 1)
					(thickness 0.15)
				)
			)
		)
		(sheetname "/SoM_Power/")
		(sheetfile "som_power.kicad_sch")
		(attr smd exclude_from_pos_files exclude_from_bom dnp)
		(fp_rect
			(start -0.925 -0.47)
			(end 0.925 0.47)
			(stroke
				(width 0.05)
				(type default)
			)
			(fill no)
			(layer "F.CrtYd")
		)
		(fp_rect
			(start -0.5 -0.25)
			(end 0.5 0.25)
			(stroke
				(width 0.15)
				(type solid)
			)
			(fill no)
			(layer "F.Fab")
		)
		(fp_text user "License: Apache-2.0"
			(at -0.95 5.169 0)
			(layer "F.Fab")
			(effects
				(font
					(size 0.7 0.7)
					(thickness 0.15)
				)
				(justify right top)
			)
		)
		(fp_text user "${REFERENCE}"
			(at -0.95 3.168 0)
			(layer "F.Fab")
			(effects
				(font
					(size 0.7 0.7)
					(thickness 0.15)
				)
				(justify right top)
			)
		)
		(fp_text user "Author: Antmicro"
			(at -0.95 4.169 0)
			(layer "F.Fab")
			(effects
				(font
					(size 0.7 0.7)
					(thickness 0.15)
				)
				(justify right top)
			)
		)
		(pad "1" smd roundrect
			(at -0.48 0 180)
			(size 0.59 0.64)
			(layers "F.Cu" "F.Mask" "F.Paste")
			(roundrect_rratio 0.25)
			(net 524 "Net-(Q22-D)")
			(pintype "passive")
		)
		(pad "2" smd roundrect
			(at 0.48 0 180)
			(size 0.59 0.64)
			(layers "F.Cu" "F.Mask" "F.Paste")
			(roundrect_rratio 0.25)
			(net 610 "/SoM_Power/~{PWR_BTN}")
			(pintype "passive")
		)
	)
	(footprint "antmicro-footprints:Fiducial_1mm_Mask3mm"
		(layer "F.Cu")
		(at 82.5 151.47)
		(descr "Circular Fiducial, 1.5mm bare copper, 3mm soldermask opening")
		(tags "fiducial")
		(property "Reference" "FD2"
			(at 1.09 1.74 0)
			(layer "F.SilkS")
			(effects
				(font
					(size 0.7 0.7)
					(thickness 0.15)
				)
				(justify left bottom)
			)
		)
		(property "Value" "Fiducial_1mm_Mask3mm"
			(at 0 2.603 0)
			(layer "F.Fab")
			(effects
				(font
					(size 0.7 0.7)
					(thickness 0.15)
				)
				(justify left bottom)
			)
		)
		(property "Description" "Fiducial mask"
			(at 0 0 0)
			(layer "F.Fab")
			(hide yes)
			(effects
				(font
					(size 1.27 1.27)
					(thickness 0.15)
				)
			)
		)
		(property "Author" "Antmicro"
			(at 0 0 0)
			(unlocked yes)
			(layer "F.Fab")
			(hide yes)
			(effects
				(font
					(size 1 1)
					(thickness 0.15)
				)
			)
		)
		(property "License" "Apache-2.0"
			(at 0 0 0)
			(unlocked yes)
			(layer "F.Fab")
			(hide yes)
			(effects
				(font
					(size 1 1)
					(thickness 0.15)
				)
			)
		)
		(sheetname "/")
		(sheetfile "jetson-agx-thor-baseboard.kicad_sch")
		(attr exclude_from_pos_files exclude_from_bom)
		(fp_circle
			(center 0 0)
			(end 1.5 0)
			(stroke
				(width 0.05)
				(type solid)
			)
			(fill no)
			(layer "F.CrtYd")
		)
		(fp_circle
			(center 0 0)
			(end 1.5 0)
			(stroke
				(width 0.15)
				(type solid)
			)
			(fill no)
			(layer "F.Fab")
		)
		(fp_text user "Author: Antmicro"
			(at -1.25 5.803 0)
			(layer "F.Fab")
			(effects
				(font
					(size 0.7 0.7)
					(thickness 0.15)
				)
				(justify left bottom)
			)
		)
		(fp_text user "${REFERENCE}"
			(at -1.25 4.603 0)
			(layer "F.Fab")
			(effects
				(font
					(size 0.7 0.7)
					(thickness 0.15)
				)
				(justify left bottom)
			)
		)
		(fp_text user "License: Apache-2.0"
			(at -1.25 7.003 0)
			(layer "F.Fab")
			(effects
				(font
					(size 0.7 0.7)
					(thickness 0.15)
				)
				(justify left bottom)
			)
		)
		(pad "" smd circle
			(at 0 0)
			(size 1 1)
			(layers "F.Cu" "F.Mask")
			(solder_mask_margin 1)
			(clearance 1)
		)
	)
	(footprint "antmicro-footprints:R_0402_1005Metric"
		(layer "F.Cu")
		(at 106.850001 57.68)
		(descr "Resistor SMD 0402")
		(tags "resistor SMD 0402")
		(property "Reference" "R314"
			(at -2.730001 6.11 0)
			(layer "F.SilkS")
			(effects
				(font
					(size 0.7 0.7)
					(thickness 0.15)
				)
				(justify left bottom)
			)
		)
		(property "Value" "R_27R_0402"
			(at -1.011843 1.772046 0)
			(layer "F.Fab")
			(effects
				(font
					(size 0.7 0.7)
					(thickness 0.15)
				)
				(justify left bottom)
			)
		)
		(property "Datasheet" "https://www.bourns.com/docs/product-datasheets/cr.pdf"
			(at 0 0 0)
			(layer "F.Fab")
			(hide yes)
			(effects
				(font
					(size 1.27 1.27)
					(thickness 0.15)
				)
			)
		)
		(property "Description" "SMD Chip Resistor, 27 ohm, ± 1%, 63 mW, 0402 [1005 Metric], Thick Film, General Purpose"
			(at 0 0 0)
			(layer "F.Fab")
			(hide yes)
			(effects
				(font
					(size 1.27 1.27)
					(thickness 0.15)
				)
			)
		)
		(property "MPN" "CR0402-FX-27R0GLF"
			(at 0 0 0)
			(unlocked yes)
			(layer "F.Fab")
			(hide yes)
			(effects
				(font
					(size 1 1)
					(thickness 0.15)
				)
			)
		)
		(property "Manufacturer" "Bourns"
			(at 0 0 0)
			(unlocked yes)
			(layer "F.Fab")
			(hide yes)
			(effects
				(font
					(size 1 1)
					(thickness 0.15)
				)
			)
		)
		(property "License" "Apache-2.0"
			(at 0 0 0)
			(unlocked yes)
			(layer "F.Fab")
			(hide yes)
			(effects
				(font
					(size 1 1)
					(thickness 0.15)
				)
			)
		)
		(property "Author" "Antmicro"
			(at 0 0 0)
			(unlocked yes)
			(layer "F.Fab")
			(hide yes)
			(effects
				(font
					(size 1 1)
					(thickness 0.15)
				)
			)
		)
		(property "Val" "27R"
			(at 0 0 0)
			(unlocked yes)
			(layer "F.Fab")
			(hide yes)
			(effects
				(font
					(size 1 1)
					(thickness 0.15)
				)
			)
		)
		(property "Tolerance" "1%"
			(at 0 0 0)
			(unlocked yes)
			(layer "F.Fab")
			(hide yes)
			(effects
				(font
					(size 1 1)
					(thickness 0.15)
				)
			)
		)
		(sheetname "/DCDC/")
		(sheetfile "dcdc.kicad_sch")
		(attr smd)
		(fp_poly
			(pts
				(xy -0.925 -0.47) (xy -0.925 0.47) (xy 0.925 0.47) (xy 0.925 -0.47)
			)
			(stroke
				(width 0.05)
				(type default)
			)
			(fill no)
			(layer "F.CrtYd")
		)
		(fp_poly
			(pts
				(xy -0.5 -0.25) (xy -0.5 0.25) (xy 0.5 0.25) (xy 0.5 -0.25)
			)
			(stroke
				(width 0.15)
				(type solid)
			)
			(fill no)
			(layer "F.Fab")
		)
		(fp_text user "Author: Antmicro"
			(at -0.95 4.169 0)
			(layer "F.Fab")
			(effects
				(font
					(size 0.7 0.7)
					(thickness 0.15)
				)
				(justify left bottom)
			)
		)
		(fp_text user "License: Apache-2.0"
			(at -0.949999 5.169 0)
			(layer "F.Fab")
			(effects
				(font
					(size 0.7 0.7)
					(thickness 0.15)
				)
				(justify left bottom)
			)
		)
		(fp_text user "${REFERENCE}"
			(at -0.95 3.168 0)
			(layer "F.Fab")
			(effects
				(font
					(size 0.7 0.7)
					(thickness 0.15)
				)
				(justify left bottom)
			)
		)
		(pad "1" smd roundrect
			(at -0.48 0)
			(size 0.59 0.64)
			(layers "F.Cu" "F.Mask" "F.Paste")
			(roundrect_rratio 0.25)
			(net 1280 "Net-(U76-IN+)")
			(pintype "passive")
		)
		(pad "2" smd roundrect
			(at 0.48 0)
			(size 0.59 0.64)
			(layers "F.Cu" "F.Mask" "F.Paste")
			(roundrect_rratio 0.25)
			(net 1278 "/DCDC/5V_{AON}_OUT")
			(pintype "passive")
		)
	)
	(footprint "antmicro-footprints:R_0402_1005Metric"
		(layer "F.Cu")
		(at 74.5 76.85 90)
		(descr "Resistor SMD 0402")
		(tags "resistor SMD 0402")
		(property "Reference" "R349"
			(at -0.95 -0.7 90)
			(layer "F.SilkS")
			(effects
				(font
					(size 0.7 0.7)
					(thickness 0.15)
				)
				(justify left bottom)
			)
		)
		(property "Value" "R_10k_0402"
			(at -1.011843 1.772046 90)
			(layer "F.Fab")
			(effects
				(font
					(size 0.7 0.7)
					(thickness 0.15)
				)
				(justify left bottom)
			)
		)
		(property "Datasheet" "https://www.bourns.com/docs/product-datasheets/cr.pdf"
			(at 0 0 90)
			(layer "F.Fab")
			(hide yes)
			(effects
				(font
					(size 1.27 1.27)
					(thickness 0.15)
				)
			)
		)
		(property "Description" "SMD Chip Resistor, 10 kohm, ± 1%, 62.5 mW, 0402 [1005 Metric], Thick Film, General Purpose"
			(at 0 0 90)
			(layer "F.Fab")
			(hide yes)
			(effects
				(font
					(size 1.27 1.27)
					(thickness 0.15)
				)
			)
		)
		(property "MPN" "CR0402-FX-1002GLF"
			(at 0 0 90)
			(unlocked yes)
			(layer "F.Fab")
			(hide yes)
			(effects
				(font
					(size 1 1)
					(thickness 0.15)
				)
			)
		)
		(property "Manufacturer" "Bourns"
			(at 0 0 90)
			(unlocked yes)
			(layer "F.Fab")
			(hide yes)
			(effects
				(font
					(size 1 1)
					(thickness 0.15)
				)
			)
		)
		(property "License" "Apache-2.0"
			(at 0 0 90)
			(unlocked yes)
			(layer "F.Fab")
			(hide yes)
			(effects
				(font
					(size 1 1)
					(thickness 0.15)
				)
			)
		)
		(property "Author" "Antmicro"
			(at 0 0 90)
			(unlocked yes)
			(layer "F.Fab")
			(hide yes)
			(effects
				(font
					(size 1 1)
					(thickness 0.15)
				)
			)
		)
		(property "Val" "10k"
			(at 0 0 90)
			(unlocked yes)
			(layer "F.Fab")
			(hide yes)
			(effects
				(font
					(size 1 1)
					(thickness 0.15)
				)
			)
		)
		(property "Tolerance" "1%"
			(at 0 0 90)
			(unlocked yes)
			(layer "F.Fab")
			(hide yes)
			(effects
				(font
					(size 1 1)
					(thickness 0.15)
				)
			)
		)
		(sheetname "/Expansion connector/")
		(sheetfile "expansion_connector.kicad_sch")
		(attr smd)
		(fp_poly
			(pts
				(xy -0.925 -0.47) (xy 0.925 -0.47) (xy 0.925 0.47) (xy -0.925 0.47)
			)
			(stroke
				(width 0.05)
				(type default)
			)
			(fill no)
			(layer "F.CrtYd")
		)
		(fp_poly
			(pts
				(xy -0.5 -0.25) (xy 0.5 -0.25) (xy 0.5 0.25) (xy -0.5 0.25)
			)
			(stroke
				(width 0.15)
				(type solid)
			)
			(fill no)
			(layer "F.Fab")
		)
		(fp_text user "License: Apache-2.0"
			(at -0.949999 5.169 90)
			(layer "F.Fab")
			(effects
				(font
					(size 0.7 0.7)
					(thickness 0.15)
				)
				(justify left bottom)
			)
		)
		(fp_text user "Author: Antmicro"
			(at -0.95 4.169 90)
			(layer "F.Fab")
			(effects
				(font
					(size 0.7 0.7)
					(thickness 0.15)
				)
				(justify left bottom)
			)
		)
		(fp_text user "${REFERENCE}"
			(at -0.95 3.168 90)
			(layer "F.Fab")
			(effects
				(font
					(size 0.7 0.7)
					(thickness 0.15)
				)
				(justify left bottom)
			)
		)
		(pad "1" smd roundrect
			(at -0.48 0 90)
			(size 0.59 0.64)
			(layers "F.Cu" "F.Mask" "F.Paste")
			(roundrect_rratio 0.25)
			(net 319 "/Expansion connector/FMC_PRSNT_M2C_L")
			(pintype "passive")
		)
		(pad "2" smd roundrect
			(at 0.48 0 90)
			(size 0.59 0.64)
			(layers "F.Cu" "F.Mask" "F.Paste")
			(roundrect_rratio 0.25)
			(net 11 "+1V8")
			(pintype "passive")
		)
	)
	(footprint "antmicro-footprints:Conn_Amphenol_SFP28_Cage_U773GC16382071"
		(locked yes)
		(layer "F.Cu")
		(at 201.826 144.9 90)
		(property "Reference" "J19"
			(at 7.4 -14.826 180)
			(layer "F.SilkS")
			(effects
				(font
					(size 0.7 0.7)
					(thickness 0.15)
				)
				(justify left bottom)
			)
		)
		(property "Value" "Amphenol_SFP28_Cage_U773GC16382071"
			(at -2.012 44.2 90)
			(layer "F.Fab")
			(effects
				(font
					(size 0.7 0.7)
					(thickness 0.15)
				)
				(justify left bottom)
			)
		)
		(property "Datasheet" "https://cdn.amphenol-cs.com/media/wysiwyg/files/documentation/datasheet/inputoutput/hsio_cn_ultraport_sfp.pdf"
			(at -2 49 90)
			(layer "F.Fab")
			(effects
				(font
					(size 0.7 0.7)
					(thickness 0.15)
				)
				(justify left bottom)
			)
		)
		(property "Description" "SFP28 Receptacle Cage"
			(at 7.123 30.001 90)
			(layer "F.Fab")
			(effects
				(font
					(size 0.7 0.7)
					(thickness 0.15)
				)
				(justify left bottom)
			)
		)
		(property "MPN" "U773GC16382071"
			(at 0 0 90)
			(unlocked yes)
			(layer "F.Fab")
			(hide yes)
			(effects
				(font
					(size 1 1)
					(thickness 0.15)
				)
			)
		)
		(property "Manufacturer" "Amphenol"
			(at 0 0 90)
			(unlocked yes)
			(layer "F.Fab")
			(hide yes)
			(effects
				(font
					(size 1 1)
					(thickness 0.15)
				)
			)
		)
		(property "Author" "Antmicro"
			(at 0 0 90)
			(unlocked yes)
			(layer "F.Fab")
			(hide yes)
			(effects
				(font
					(size 1 1)
					(thickness 0.15)
				)
			)
		)
		(property "License" "Apache-2.0"
			(at 0 0 90)
			(unlocked yes)
			(layer "F.Fab")
			(hide yes)
			(effects
				(font
					(size 1 1)
					(thickness 0.15)
				)
			)
		)
		(sheetname "/SFP/")
		(sheetfile "sfp.kicad_sch")
		(attr through_hole)
		(fp_poly
			(pts
				(xy -6.027 11.901) (xy 6.023 11.901) (xy 6.023 13.901) (xy -6.027 13.901)
			)
			(stroke
				(width 0.01)
				(type solid)
			)
			(fill yes)
			(layer "F.Mask")
		)
		(fp_line
			(start 8.128 -12.749)
			(end 6.98 -12.749)
			(stroke
				(width 0.15)
				(type solid)
			)
			(layer "F.SilkS")
		)
		(fp_line
			(start 8.128 -12.749)
			(end 8.128 -11.695)
			(stroke
				(width 0.15)
				(type solid)
			)
			(layer "F.SilkS")
		)
		(fp_line
			(start -8.132 -12.749)
			(end -7.02 -12.749)
			(stroke
				(width 0.15)
				(type solid)
			)
			(layer "F.SilkS")
		)
		(fp_line
			(start -8.132 -12.749)
			(end -8.132 -11.695)
			(stroke
				(width 0.15)
				(type solid)
			)
			(layer "F.SilkS")
		)
		(fp_line
			(start 8.128 35.401)
			(end 8.128 34.305)
			(stroke
				(width 0.15)
				(type solid)
			)
			(layer "F.SilkS")
		)
		(fp_line
			(start 8.128 35.401)
			(end 6.98 35.401)
			(stroke
				(width 0.15)
				(type solid)
			)
			(layer "F.SilkS")
		)
		(fp_line
			(start -8.132 35.401)
			(end -8.132 34.305)
			(stroke
				(width 0.15)
				(type solid)
			)
			(layer "F.SilkS")
		)
		(fp_line
			(start -8.132 35.401)
			(end -7.02 35.401)
			(stroke
				(width 0.15)
				(type solid)
			)
			(layer "F.SilkS")
		)
		(fp_rect
			(start -8.445 -7.2)
			(end 8.425 43.4)
			(stroke
				(width 0.05)
				(type solid)
			)
			(fill no)
			(layer "F.CrtYd")
		)
		(fp_text user "Author: Antmicro"
			(at -2.012 47.8 90)
			(layer "F.Fab")
			(effects
				(font
					(size 0.7 0.7)
					(thickness 0.15)
				)
				(justify left bottom)
			)
		)
		(fp_text user "${REFERENCE}"
			(at -2.012 46.6 90)
			(layer "F.Fab")
			(effects
				(font
					(size 0.7 0.7)
					(thickness 0.15)
				)
				(justify left bottom)
			)
		)
		(fp_text user "License: Apache-2.0"
			(at -2.012 45.4 90)
			(layer "F.Fab")
			(effects
				(font
					(size 0.7 0.7)
					(thickness 0.15)
				)
				(justify left bottom)
			)
		)
		(pad "" np_thru_hole circle
			(at -7.125 -1.6 90)
			(size 0.95 0.95)
			(drill 0.95)
			(layers "*.Cu" "*.Mask")
		)
		(pad "" np_thru_hole circle
			(at -7.125 3.4 90)
			(size 0.95 0.95)
			(drill 0.95)
			(layers "*.Cu" "*.Mask")
		)
		(pad "" np_thru_hole circle
			(at -7.125 8.1 90)
			(size 0.95 0.95)
			(drill 0.95)
			(layers "*.Cu" "*.Mask")
		)
		(pad "" np_thru_hole circle
			(at -4.8 -6.2 90)
			(size 0.95 0.95)
			(drill 0.95)
			(layers "*.Cu" "*.Mask")
		)
		(pad "" np_thru_hole circle
			(at 0 -6.2 90)
			(size 0.95 0.95)
			(drill 0.95)
			(layers "*.Cu" "*.Mask")
		)
		(pad "" np_thru_hole circle
			(at 4.8 -6.2 90)
			(size 0.95 0.95)
			(drill 0.95)
			(layers "*.Cu" "*.Mask")
		)
		(pad "" np_thru_hole circle
			(at 7.125 -1.6 90)
			(size 0.95 0.95)
			(drill 0.95)
			(layers "*.Cu" "*.Mask")
		)
		(pad "" np_thru_hole circle
			(at 7.125 3.4 90)
			(size 0.95 0.95)
			(drill 0.95)
			(layers "*.Cu" "*.Mask")
		)
		(pad "" np_thru_hole circle
			(at 7.125 8.1 90)
			(size 0.95 0.95)
			(drill 0.95)
			(layers "*.Cu" "*.Mask")
		)
		(pad "SH" thru_hole rect
			(at -7.125 0.9 90)
			(size 2 2)
			(drill 0.85)
			(layers "*.Cu" "*.Mask")
			(remove_unused_layers no)
			(net 379 "/SFP/SH")
			(pinfunction "SH")
			(pintype "passive")
			(solder_mask_margin 0.102)
		)
		(pad "SH" thru_hole rect
			(at -7.125 10.9 90)
			(size 2 2)
			(drill 1.1)
			(layers "*.Cu" "*.Mask")
			(remove_unused_layers no)
			(net 379 "/SFP/SH")
			(pinfunction "SH")
			(pintype "passive")
			(solder_mask_margin 0.102)
		)
		(pad "SH" thru_hole rect
			(at -7.125 20.9 90)
			(size 2 2)
			(drill 1.1)
			(layers "*.Cu" "*.Mask")
			(remove_unused_layers no)
			(net 379 "/SFP/SH")
			(pinfunction "SH")
			(pintype "passive")
			(solder_mask_margin 0.102)
		)
		(pad "SH" thru_hole rect
			(at -7.125 30.9 90)
			(size 2 2)
			(drill 1.1)
			(layers "*.Cu" "*.Mask")
			(remove_unused_layers no)
			(net 379 "/SFP/SH")
			(pinfunction "SH")
			(pintype "passive")
			(solder_mask_margin 0.102)
		)
		(pad "SH" smd rect
			(at 0 12.9 90)
			(size 12.05 2)
			(layers "F.Cu" "F.Paste")
			(net 379 "/SFP/SH")
			(pinfunction "SH")
			(pintype "passive")
		)
		(pad "SH" thru_hole rect
			(at 7.125 -4.1 90)
			(size 2 2)
			(drill 1.1)
			(layers "*.Cu" "*.Mask")
			(remove_unused_layers no)
			(net 379 "/SFP/SH")
			(pinfunction "SH")
			(pintype "passive")
			(solder_mask_margin 0.102)
		)
		(pad "SH" thru_hole rect
			(at 7.125 5.9 90)
			(size 2 2)
			(drill 1.1)
			(layers "*.Cu" "*.Mask")
			(remove_unused_layers no)
			(net 379 "/SFP/SH")
			(pinfunction "SH")
			(pintype "passive")
			(solder_mask_margin 0.102)
		)
		(pad "SH" thru_hole rect
			(at 7.125 15.9 90)
			(size 2 2)
			(drill 1.1)
			(layers "*.Cu" "*.Mask")
			(remove_unused_layers no)
			(net 379 "/SFP/SH")
			(pinfunction "SH")
			(pintype "passive")
			(solder_mask_margin 0.102)
		)
		(pad "SH" thru_hole rect
			(at 7.125 25.9 90)
			(size 2 2)
			(drill 1.1)
			(layers "*.Cu" "*.Mask")
			(remove_unused_layers no)
			(net 379 "/SFP/SH")
			(pinfunction "SH")
			(pintype "passive")
			(solder_mask_margin 0.102)
		)
		(zone
			(net 0)
			(net_name "")
			(layer "F.Cu")
			(hatch full 0.508)
			(connect_pads
				(clearance 0)
			)
			(min_thickness 0.01)
			(filled_areas_thickness no)
			(keepout
				(tracks allowed)
				(vias allowed)
				(pads allowed)
				(copperpour not_allowed)
				(footprints not_allowed)
			)
			(placement
				(enabled no)
				(sheetname "")
			)
			(fill
				(thermal_gap 0.508)
				(thermal_bridge_width 0.508)
			)
			(polygon
				(pts
					(xy 194.927 146.647) (xy 194.927 143.547) (xy 195.927 143.547) (xy 195.927 146.647)
				)
			)
		)
		(zone
			(net 0)
			(net_name "")
			(layer "F.Cu")
			(hatch full 0.508)
			(connect_pads
				(clearance 0)
			)
			(min_thickness 0.01)
			(filled_areas_thickness no)
			(keepout
				(tracks allowed)
				(vias allowed)
				(pads allowed)
				(copperpour not_allowed)
				(footprints not_allowed)
			)
			(placement
				(enabled no)
				(sheetname "")
			)
			(fill
				(thermal_gap 0.508)
				(thermal_bridge_width 0.508)
			)
			(polygon
				(pts
					(xy 206.727 136.777) (xy 198.727 136.777) (xy 198.727 138.777) (xy 206.727 138.777)
				)
			)
		)
		(zone
			(net 0)
			(net_name "")
			(layer "F.Cu")
			(hatch full 0.508)
			(connect_pads
				(clearance 0)
			)
			(min_thickness 0.01)
			(filled_areas_thickness no)
			(keepout
				(tracks allowed)
				(vias allowed)
				(pads allowed)
				(copperpour not_allowed)
				(footprints not_allowed)
			)
			(placement
				(enabled no)
				(sheetname "")
			)
			(fill
				(thermal_gap 0.508)
				(thermal_bridge_width 0.508)
			)
			(polygon
				(pts
					(xy 196.727 136.777) (xy 194.927 136.777) (xy 194.927 141.847) (xy 195.927 141.847) (xy 195.927 138.777)
					(xy 196.727 138.777)
				)
			)
		)
		(zone
			(net 0)
			(net_name "")
			(layer "F.Cu")
			(hatch full 0.508)
			(connect_pads
				(clearance 0)
			)
			(min_thickness 0.01)
			(filled_areas_thickness no)
			(keepout
				(tracks allowed)
				(vias allowed)
				(pads allowed)
				(copperpour not_allowed)
				(footprints not_allowed)
			)
			(placement
				(enabled no)
				(sheetname "")
			)
			(fill
				(thermal_gap 0.508)
				(thermal_bridge_width 0.508)
			)
			(polygon
				(pts
					(xy 201.727 153.027) (xy 194.927 153.027) (xy 194.927 148.347) (xy 195.927 148.347) (xy 195.927 151.027)
					(xy 201.727 151.027)
				)
			)
		)
		(zone
			(net 0)
			(net_name "")
			(layer "F.Cu")
			(hatch full 0.508)
			(connect_pads
				(clearance 0)
			)
			(min_thickness 0.01)
			(filled_areas_thickness no)
			(keepout
				(tracks allowed)
				(vias allowed)
				(pads allowed)
				(copperpour not_allowed)
				(footprints not_allowed)
			)
			(placement
				(enabled no)
				(sheetname "")
			)
			(fill
				(thermal_gap 0.508)
				(thermal_bridge_width 0.508)
			)
			(polygon
				(pts
					(xy 237.227 136.777) (xy 237.227 153.027) (xy 233.727 153.027) (xy 233.727 151.027) (xy 231.727 151.027)
					(xy 231.727 153.027) (xy 223.727 153.027) (xy 223.727 151.027) (xy 221.727 151.027) (xy 221.727 153.027)
					(xy 213.727 153.027) (xy 213.727 151.027) (xy 211.727 151.027) (xy 211.727 153.027) (xy 203.727 153.027)
					(xy 203.727 151.027) (xy 210.427 151.027) (xy 210.427 138.777) (xy 208.727 138.777) (xy 208.727 136.777)
					(xy 216.727 136.777) (xy 216.727 138.777) (xy 218.727 138.777) (xy 218.727 136.777) (xy 226.727 136.777)
					(xy 226.727 138.777) (xy 228.727 138.777) (xy 228.727 136.777)
				)
			)
		)
	)
	(footprint "antmicro-footprints:R_0402_1005Metric"
		(layer "F.Cu")
		(at 132.465349 60.98)
		(descr "Resistor SMD 0402")
		(tags "resistor SMD 0402")
		(property "Reference" "R310"
			(at 0.844651 1.38 0)
			(layer "F.SilkS")
			(effects
				(font
					(size 0.7 0.7)
					(thickness 0.15)
				)
				(justify left bottom)
			)
		)
		(property "Value" "R_200k_0402"
			(at -1.011843 1.772046 0)
			(layer "F.Fab")
			(effects
				(font
					(size 0.7 0.7)
					(thickness 0.15)
				)
				(justify left bottom)
			)
		)
		(property "Datasheet" "https://www.bourns.com/docs/product-datasheets/cr.pdf"
			(at 0 0 0)
			(layer "F.Fab")
			(hide yes)
			(effects
				(font
					(size 1.27 1.27)
					(thickness 0.15)
				)
			)
		)
		(property "Description" "SMD Chip Resistor, 200 kohm, ± 1%, 62.5 mW, 0402 [1005 Metric], Thick Film, General Purpose"
			(at 0 0 0)
			(layer "F.Fab")
			(hide yes)
			(effects
				(font
					(size 1.27 1.27)
					(thickness 0.15)
				)
			)
		)
		(property "MPN" "CR0402-FX-2003GLF"
			(at 0 0 0)
			(unlocked yes)
			(layer "F.Fab")
			(hide yes)
			(effects
				(font
					(size 1 1)
					(thickness 0.15)
				)
			)
		)
		(property "Manufacturer" "Bourns"
			(at 0 0 0)
			(unlocked yes)
			(layer "F.Fab")
			(hide yes)
			(effects
				(font
					(size 1 1)
					(thickness 0.15)
				)
			)
		)
		(property "License" "Apache-2.0"
			(at 0 0 0)
			(unlocked yes)
			(layer "F.Fab")
			(hide yes)
			(effects
				(font
					(size 1 1)
					(thickness 0.15)
				)
			)
		)
		(property "Author" "Antmicro"
			(at 0 0 0)
			(unlocked yes)
			(layer "F.Fab")
			(hide yes)
			(effects
				(font
					(size 1 1)
					(thickness 0.15)
				)
			)
		)
		(property "Val" "200k"
			(at 0 0 0)
			(unlocked yes)
			(layer "F.Fab")
			(hide yes)
			(effects
				(font
					(size 1 1)
					(thickness 0.15)
				)
			)
		)
		(property "Tolerance" "1%"
			(at 0 0 0)
			(unlocked yes)
			(layer "F.Fab")
			(hide yes)
			(effects
				(font
					(size 1 1)
					(thickness 0.15)
				)
			)
		)
		(sheetname "/DCDC/")
		(sheetfile "dcdc.kicad_sch")
		(attr smd)
		(fp_poly
			(pts
				(xy -0.925 -0.47) (xy -0.925 0.47) (xy 0.925 0.47) (xy 0.925 -0.47)
			)
			(stroke
				(width 0.05)
				(type default)
			)
			(fill no)
			(layer "F.CrtYd")
		)
		(fp_poly
			(pts
				(xy -0.5 -0.25) (xy -0.5 0.25) (xy 0.5 0.25) (xy 0.5 -0.25)
			)
			(stroke
				(width 0.15)
				(type solid)
			)
			(fill no)
			(layer "F.Fab")
		)
		(fp_text user "${REFERENCE}"
			(at -0.95 3.168 0)
			(layer "F.Fab")
			(effects
				(font
					(size 0.7 0.7)
					(thickness 0.15)
				)
				(justify left bottom)
			)
		)
		(fp_text user "Author: Antmicro"
			(at -0.95 4.169 0)
			(layer "F.Fab")
			(effects
				(font
					(size 0.7 0.7)
					(thickness 0.15)
				)
				(justify left bottom)
			)
		)
		(fp_text user "License: Apache-2.0"
			(at -0.949999 5.169 0)
			(layer "F.Fab")
			(effects
				(font
					(size 0.7 0.7)
					(thickness 0.15)
				)
				(justify left bottom)
			)
		)
		(pad "1" smd roundrect
			(at -0.48 0)
			(size 0.59 0.64)
			(layers "F.Cu" "F.Mask" "F.Paste")
			(roundrect_rratio 0.25)
			(net 1 "GND")
			(pintype "passive")
		)
		(pad "2" smd roundrect
			(at 0.48 0)
			(size 0.59 0.64)
			(layers "F.Cu" "F.Mask" "F.Paste")
			(roundrect_rratio 0.25)
			(net 1306 "/DCDC/5V_{AON}_MODE1")
			(pintype "passive")
		)
	)
	(footprint "antmicro-footprints:C_0603_1608Metric_EIA"
		(layer "F.Cu")
		(at 174.95 113.59 -90)
		(descr "Capacitor SMD 0603, IPC-7351 Density Level A")
		(tags "Capacitor 0603")
		(property "Reference" "C72"
			(at -1.18 7.369468 90)
			(layer "F.SilkS")
			(effects
				(font
					(size 0.7 0.7)
					(thickness 0.15)
				)
				(justify right top)
			)
		)
		(property "Value" "C_22u_16V_0603"
			(at -1.42757 1.770288 90)
			(layer "F.Fab")
			(effects
				(font
					(size 0.7 0.7)
					(thickness 0.15)
				)
				(justify right top)
			)
		)
		(property "Datasheet" "https://product.samsungsem.com/mlcc/CL10A226MO7JZN.do"
			(at 0 0 90)
			(layer "F.Fab")
			(hide yes)
			(effects
				(font
					(size 1.27 1.27)
					(thickness 0.15)
				)
			)
		)
		(property "Description" "SMD Multilayer Ceramic Capacitor"
			(at 0 0 90)
			(layer "F.Fab")
			(hide yes)
			(effects
				(font
					(size 1.27 1.27)
					(thickness 0.15)
				)
			)
		)
		(property "Manufacturer" "Samsung Electro-Mechanics"
			(at 0 0 270)
			(unlocked yes)
			(layer "F.Fab")
			(hide yes)
			(effects
				(font
					(size 1 1)
					(thickness 0.15)
				)
			)
		)
		(property "MPN" "CL10A226MO7JZNC"
			(at 0 0 270)
			(unlocked yes)
			(layer "F.Fab")
			(hide yes)
			(effects
				(font
					(size 1 1)
					(thickness 0.15)
				)
			)
		)
		(property "Val" "22u"
			(at 0 0 270)
			(unlocked yes)
			(layer "F.Fab")
			(hide yes)
			(effects
				(font
					(size 1 1)
					(thickness 0.15)
				)
			)
		)
		(property "License" "Apache-2.0"
			(at 0 0 270)
			(unlocked yes)
			(layer "F.Fab")
			(hide yes)
			(effects
				(font
					(size 1 1)
					(thickness 0.15)
				)
			)
		)
		(property "Author" "Antmicro"
			(at 0 0 270)
			(unlocked yes)
			(layer "F.Fab")
			(hide yes)
			(effects
				(font
					(size 1 1)
					(thickness 0.15)
				)
			)
		)
		(property "Voltage" "16V"
			(at 0 0 270)
			(unlocked yes)
			(layer "F.Fab")
			(hide yes)
			(effects
				(font
					(size 1 1)
					(thickness 0.15)
				)
			)
		)
		(property "Dielectric" ""
			(at 0 0 270)
			(unlocked yes)
			(layer "F.Fab")
			(hide yes)
			(effects
				(font
					(size 1 1)
					(thickness 0.15)
				)
			)
		)
		(sheetname "/DCDC/")
		(sheetfile "dcdc.kicad_sch")
		(attr smd)
		(fp_line
			(start -0.15 0.55)
			(end 0.15 0.55)
			(stroke
				(width 0.15)
				(type solid)
			)
			(layer "F.SilkS")
		)
		(fp_line
			(start -0.15 -0.55)
			(end 0.15 -0.55)
			(stroke
				(width 0.15)
				(type solid)
			)
			(layer "F.SilkS")
		)
		(fp_rect
			(start -1.25 -0.65)
			(end 1.25 0.65)
			(stroke
				(width 0.05)
				(type solid)
			)
			(fill no)
			(layer "F.CrtYd")
		)
		(fp_rect
			(start -0.8 -0.45)
			(end 0.8 0.45)
			(stroke
				(width 0.15)
				(type solid)
			)
			(fill no)
			(layer "F.Fab")
		)
		(fp_text user "License: Apache-2.0"
			(at -1.682 5.895 90)
			(layer "F.Fab")
			(effects
				(font
					(size 0.7 0.7)
					(thickness 0.15)
				)
				(justify right top)
			)
		)
		(fp_text user "${REFERENCE}"
			(at -1.682 3.895 90)
			(layer "F.Fab")
			(effects
				(font
					(size 0.7 0.7)
					(thickness 0.15)
				)
				(justify right top)
			)
		)
		(fp_text user "Author: Antmicro"
			(at -1.682 4.894 90)
			(layer "F.Fab")
			(effects
				(font
					(size 0.7 0.7)
					(thickness 0.15)
				)
				(justify right top)
			)
		)
		(pad "1" smd roundrect
			(at -0.7 0 270)
			(size 0.8 1.1)
			(layers "F.Cu" "F.Mask" "F.Paste")
			(roundrect_rratio 0.2)
			(net 1 "GND")
			(pintype "passive")
		)
		(pad "2" smd roundrect
			(at 0.7 0 270)
			(size 0.8 1.1)
			(layers "F.Cu" "F.Mask" "F.Paste")
			(roundrect_rratio 0.2)
			(net 253 "/DCDC/5V_OUT")
			(pintype "passive")
		)
	)
	(footprint "antmicro-footprints:R_0402_1005Metric"
		(layer "F.Cu")
		(at 106.85 56.68)
		(descr "Resistor SMD 0402")
		(tags "resistor SMD 0402")
		(property "Reference" "R367"
			(at -2.73 6.16 0)
			(layer "F.SilkS")
			(effects
				(font
					(size 0.7 0.7)
					(thickness 0.15)
				)
				(justify left bottom)
			)
		)
		(property "Value" "R_27R_0402"
			(at -1.011843 1.772046 0)
			(layer "F.Fab")
			(effects
				(font
					(size 0.7 0.7)
					(thickness 0.15)
				)
				(justify left bottom)
			)
		)
		(property "Datasheet" "https://www.bourns.com/docs/product-datasheets/cr.pdf"
			(at 0 0 0)
			(layer "F.Fab")
			(hide yes)
			(effects
				(font
					(size 1.27 1.27)
					(thickness 0.15)
				)
			)
		)
		(property "Description" "SMD Chip Resistor, 27 ohm, ± 1%, 63 mW, 0402 [1005 Metric], Thick Film, General Purpose"
			(at 0 0 0)
			(layer "F.Fab")
			(hide yes)
			(effects
				(font
					(size 1.27 1.27)
					(thickness 0.15)
				)
			)
		)
		(property "Manufacturer" "Bourns"
			(at 0 0 0)
			(unlocked yes)
			(layer "F.Fab")
			(hide yes)
			(effects
				(font
					(size 1 1)
					(thickness 0.15)
				)
			)
		)
		(property "MPN" "CR0402-FX-27R0GLF"
			(at 0 0 0)
			(unlocked yes)
			(layer "F.Fab")
			(hide yes)
			(effects
				(font
					(size 1 1)
					(thickness 0.15)
				)
			)
		)
		(property "Val" "27R"
			(at 0 0 0)
			(unlocked yes)
			(layer "F.Fab")
			(hide yes)
			(effects
				(font
					(size 1 1)
					(thickness 0.15)
				)
			)
		)
		(property "License" "Apache-2.0"
			(at 0 0 0)
			(unlocked yes)
			(layer "F.Fab")
			(hide yes)
			(effects
				(font
					(size 1 1)
					(thickness 0.15)
				)
			)
		)
		(property "Author" "Antmicro"
			(at 0 0 0)
			(unlocked yes)
			(layer "F.Fab")
			(hide yes)
			(effects
				(font
					(size 1 1)
					(thickness 0.15)
				)
			)
		)
		(property "Tolerance" "1%"
			(at 0 0 0)
			(unlocked yes)
			(layer "F.Fab")
			(hide yes)
			(effects
				(font
					(size 1 1)
					(thickness 0.15)
				)
			)
		)
		(sheetname "/DCDC/")
		(sheetfile "dcdc.kicad_sch")
		(attr smd)
		(fp_poly
			(pts
				(xy -0.925 -0.47) (xy -0.925 0.47) (xy 0.925 0.47) (xy 0.925 -0.47)
			)
			(stroke
				(width 0.05)
				(type default)
			)
			(fill no)
			(layer "F.CrtYd")
		)
		(fp_poly
			(pts
				(xy -0.5 -0.25) (xy -0.5 0.25) (xy 0.5 0.25) (xy 0.5 -0.25)
			)
			(stroke
				(width 0.15)
				(type solid)
			)
			(fill no)
			(layer "F.Fab")
		)
		(fp_text user "License: Apache-2.0"
			(at -0.949999 5.169 0)
			(layer "F.Fab")
			(effects
				(font
					(size 0.7 0.7)
					(thickness 0.15)
				)
				(justify left bottom)
			)
		)
		(fp_text user "${REFERENCE}"
			(at -0.95 3.168 0)
			(layer "F.Fab")
			(effects
				(font
					(size 0.7 0.7)
					(thickness 0.15)
				)
				(justify left bottom)
			)
		)
		(fp_text user "Author: Antmicro"
			(at -0.95 4.169 0)
			(layer "F.Fab")
			(effects
				(font
					(size 0.7 0.7)
					(thickness 0.15)
				)
				(justify left bottom)
			)
		)
		(pad "1" smd roundrect
			(at -0.48 0)
			(size 0.59 0.64)
			(layers "F.Cu" "F.Mask" "F.Paste")
			(roundrect_rratio 0.25)
			(net 1279 "Net-(U76-IN-)")
			(pintype "passive")
		)
		(pad "2" smd roundrect
			(at 0.48 0)
			(size 0.59 0.64)
			(layers "F.Cu" "F.Mask" "F.Paste")
			(roundrect_rratio 0.25)
			(net 491 "+5V_AON")
			(pintype "passive")
		)
	)
	(footprint "antmicro-footprints:R_0402_1005Metric"
		(layer "F.Cu")
		(at 61.6 64.2)
		(descr "Resistor SMD 0402")
		(tags "resistor SMD 0402")
		(property "Reference" "R167"
			(at -1.4 3.6 0)
			(layer "F.SilkS")
			(effects
				(font
					(size 0.7 0.7)
					(thickness 0.15)
				)
				(justify left bottom)
			)
		)
		(property "Value" "R_10k_0402"
			(at -1.011843 1.772046 0)
			(layer "F.Fab")
			(effects
				(font
					(size 0.7 0.7)
					(thickness 0.15)
				)
				(justify left bottom)
			)
		)
		(property "Datasheet" "https://www.bourns.com/docs/product-datasheets/cr.pdf"
			(at 0 0 0)
			(layer "F.Fab")
			(hide yes)
			(effects
				(font
					(size 1.27 1.27)
					(thickness 0.15)
				)
			)
		)
		(property "Description" "SMD Chip Resistor, 10 kohm, ± 1%, 62.5 mW, 0402 [1005 Metric], Thick Film, General Purpose"
			(at 0 0 0)
			(layer "F.Fab")
			(hide yes)
			(effects
				(font
					(size 1.27 1.27)
					(thickness 0.15)
				)
			)
		)
		(property "Manufacturer" "Bourns"
			(at 0 0 0)
			(unlocked yes)
			(layer "F.Fab")
			(hide yes)
			(effects
				(font
					(size 1 1)
					(thickness 0.15)
				)
			)
		)
		(property "MPN" "CR0402-FX-1002GLF"
			(at 0 0 0)
			(unlocked yes)
			(layer "F.Fab")
			(hide yes)
			(effects
				(font
					(size 1 1)
					(thickness 0.15)
				)
			)
		)
		(property "Val" "10k"
			(at 0 0 0)
			(unlocked yes)
			(layer "F.Fab")
			(hide yes)
			(effects
				(font
					(size 1 1)
					(thickness 0.15)
				)
			)
		)
		(property "License" "Apache-2.0"
			(at 0 0 0)
			(unlocked yes)
			(layer "F.Fab")
			(hide yes)
			(effects
				(font
					(size 1 1)
					(thickness 0.15)
				)
			)
		)
		(property "Author" "Antmicro"
			(at 0 0 0)
			(unlocked yes)
			(layer "F.Fab")
			(hide yes)
			(effects
				(font
					(size 1 1)
					(thickness 0.15)
				)
			)
		)
		(property "Tolerance" "1%"
			(at 0 0 0)
			(unlocked yes)
			(layer "F.Fab")
			(hide yes)
			(effects
				(font
					(size 1 1)
					(thickness 0.15)
				)
			)
		)
		(sheetname "/CSI/")
		(sheetfile "csi.kicad_sch")
		(attr smd)
		(fp_poly
			(pts
				(xy -0.925 -0.47) (xy -0.925 0.47) (xy 0.925 0.47) (xy 0.925 -0.47)
			)
			(stroke
				(width 0.05)
				(type default)
			)
			(fill no)
			(layer "F.CrtYd")
		)
		(fp_poly
			(pts
				(xy -0.5 -0.25) (xy -0.5 0.25) (xy 0.5 0.25) (xy 0.5 -0.25)
			)
			(stroke
				(width 0.15)
				(type solid)
			)
			(fill no)
			(layer "F.Fab")
		)
		(fp_text user "License: Apache-2.0"
			(at -0.949999 5.169 0)
			(layer "F.Fab")
			(effects
				(font
					(size 0.7 0.7)
					(thickness 0.15)
				)
				(justify left bottom)
			)
		)
		(fp_text user "Author: Antmicro"
			(at -0.95 4.169 0)
			(layer "F.Fab")
			(effects
				(font
					(size 0.7 0.7)
					(thickness 0.15)
				)
				(justify left bottom)
			)
		)
		(fp_text user "${REFERENCE}"
			(at -0.95 3.168 0)
			(layer "F.Fab")
			(effects
				(font
					(size 0.7 0.7)
					(thickness 0.15)
				)
				(justify left bottom)
			)
		)
		(pad "1" smd roundrect
			(at -0.48 0)
			(size 0.59 0.64)
			(layers "F.Cu" "F.Mask" "F.Paste")
			(roundrect_rratio 0.25)
			(net 11 "+1V8")
			(pintype "passive")
		)
		(pad "2" smd roundrect
			(at 0.48 0)
			(size 0.59 0.64)
			(layers "F.Cu" "F.Mask" "F.Paste")
			(roundrect_rratio 0.25)
			(net 989 "/CSI/I2C_MUX_RESET")
			(pintype "passive")
		)
	)
	(footprint "antmicro-footprints:C_0402_1005Metric"
		(layer "F.Cu")
		(at 200.7 133.7 90)
		(descr "Capacitor SMD 0402")
		(tags "capacitor SMD 0402")
		(property "Reference" "C97"
			(at -1.105 -1.8 90)
			(layer "F.SilkS")
			(effects
				(font
					(size 0.7 0.7)
					(thickness 0.15)
				)
				(justify left bottom)
			)
		)
		(property "Value" "C_100n_0402"
			(at -1.022927 2.155213 90)
			(layer "F.Fab")
			(effects
				(font
					(size 0.7 0.7)
					(thickness 0.15)
				)
				(justify left bottom)
			)
		)
		(property "Datasheet" "https://www.murata.com/products/productdetail?partno=GRM155R61H104KE14%23"
			(at 0 0 90)
			(layer "F.Fab")
			(hide yes)
			(effects
				(font
					(size 1.27 1.27)
					(thickness 0.15)
				)
			)
		)
		(property "Description" "SMD Multilayer Ceramic Capacitor, 0.1 µF, 50 V, 0402 [1005 Metric], ± 10%, X5R, GRM Series"
			(at 0 0 90)
			(layer "F.Fab")
			(hide yes)
			(effects
				(font
					(size 1.27 1.27)
					(thickness 0.15)
				)
			)
		)
		(property "MPN" "GRM155R61H104KE14D"
			(at 0 0 90)
			(unlocked yes)
			(layer "F.Fab")
			(hide yes)
			(effects
				(font
					(size 1 1)
					(thickness 0.15)
				)
			)
		)
		(property "Val" "100n"
			(at 0 0 90)
			(unlocked yes)
			(layer "F.Fab")
			(hide yes)
			(effects
				(font
					(size 1 1)
					(thickness 0.15)
				)
			)
		)
		(property "Voltage" "50V"
			(at 0 0 90)
			(unlocked yes)
			(layer "F.Fab")
			(hide yes)
			(effects
				(font
					(size 1 1)
					(thickness 0.15)
				)
			)
		)
		(property "Dielectric" "X5R"
			(at 0 0 90)
			(unlocked yes)
			(layer "F.Fab")
			(hide yes)
			(effects
				(font
					(size 1 1)
					(thickness 0.15)
				)
			)
		)
		(property "Manufacturer" "Murata"
			(at 0 0 90)
			(unlocked yes)
			(layer "F.Fab")
			(hide yes)
			(effects
				(font
					(size 1 1)
					(thickness 0.15)
				)
			)
		)
		(property "License" "Apache-2.0"
			(at 0 0 90)
			(unlocked yes)
			(layer "F.Fab")
			(hide yes)
			(effects
				(font
					(size 1 1)
					(thickness 0.15)
				)
			)
		)
		(property "Author" "Antmicro"
			(at 0 0 90)
			(unlocked yes)
			(layer "F.Fab")
			(hide yes)
			(effects
				(font
					(size 1 1)
					(thickness 0.15)
				)
			)
		)
		(sheetname "/USB Hub/")
		(sheetfile "usb_hub.kicad_sch")
		(attr smd)
		(fp_poly
			(pts
				(xy -0.925 -0.47) (xy 0.925 -0.47) (xy 0.925 0.47) (xy -0.925 0.47)
			)
			(stroke
				(width 0.05)
				(type default)
			)
			(fill no)
			(layer "F.CrtYd")
		)
		(fp_line
			(start 0.504 -0.25)
			(end 0.504 0.248)
			(stroke
				(width 0.15)
				(type solid)
			)
			(layer "F.Fab")
		)
		(fp_line
			(start -0.494 -0.25)
			(end 0.504 -0.25)
			(stroke
				(width 0.15)
				(type solid)
			)
			(layer "F.Fab")
		)
		(fp_line
			(start 0.504 0.248)
			(end -0.494 0.248)
			(stroke
				(width 0.15)
				(type solid)
			)
			(layer "F.Fab")
		)
		(fp_line
			(start -0.494 0.248)
			(end -0.494 -0.25)
			(stroke
				(width 0.15)
				(type solid)
			)
			(layer "F.Fab")
		)
		(fp_text user "${REFERENCE}"
			(at -0.939 4.599 90)
			(layer "F.Fab")
			(effects
				(font
					(size 0.7 0.7)
					(thickness 0.15)
				)
				(justify left bottom)
			)
		)
		(fp_text user "License: Apache-2.0"
			(at -0.939 5.799 90)
			(layer "F.Fab")
			(effects
				(font
					(size 0.7 0.7)
					(thickness 0.15)
				)
				(justify left bottom)
			)
		)
		(fp_text user "Author: Antmicro"
			(at -0.939 3.399 90)
			(layer "F.Fab")
			(effects
				(font
					(size 0.7 0.7)
					(thickness 0.15)
				)
				(justify left bottom)
			)
		)
		(pad "1" smd roundrect
			(at -0.48 0 90)
			(size 0.59 0.64)
			(layers "F.Cu" "F.Mask" "F.Paste")
			(roundrect_rratio 0.25)
			(net 1 "GND")
			(pintype "passive")
		)
		(pad "2" smd roundrect
			(at 0.48 0 90)
			(size 0.59 0.64)
			(layers "F.Cu" "F.Mask" "F.Paste")
			(roundrect_rratio 0.25)
			(net 282 "+1V15")
			(pintype "passive")
		)
	)
	(footprint "antmicro-footprints:R_0603_1608Metric"
		(layer "F.Cu")
		(at 193.89 124.08)
		(descr "Resistor SMD 0603")
		(tags "resistor SMD 0603")
		(property "Reference" "R7"
			(at -2.59 0.72 0)
			(layer "F.SilkS")
			(effects
				(font
					(size 0.7 0.7)
					(thickness 0.15)
				)
				(justify left bottom)
			)
		)
		(property "Value" "R_0R_22.4A_0603"
			(at 0 1.6 0)
			(layer "F.Fab")
			(effects
				(font
					(size 0.7 0.7)
					(thickness 0.15)
				)
				(justify left bottom)
			)
		)
		(property "Datasheet" "https://fscdn.rohm.com/en/products/databook/datasheet/passive/resistor/chip_resistor/pmr-jpw-e.pdf"
			(at 0 0 0)
			(layer "F.Fab")
			(hide yes)
			(effects
				(font
					(size 1.27 1.27)
					(thickness 0.15)
				)
			)
		)
		(property "Description" "SMD Chip Resistor"
			(at 0 0 0)
			(layer "F.Fab")
			(hide yes)
			(effects
				(font
					(size 1.27 1.27)
					(thickness 0.15)
				)
			)
		)
		(property "Manufacturer" "ROHM Semiconductor"
			(at 0 0 0)
			(unlocked yes)
			(layer "F.Fab")
			(hide yes)
			(effects
				(font
					(size 1 1)
					(thickness 0.15)
				)
			)
		)
		(property "MPN" "PMR03EZPJ000"
			(at 0 0 0)
			(unlocked yes)
			(layer "F.Fab")
			(hide yes)
			(effects
				(font
					(size 1 1)
					(thickness 0.15)
				)
			)
		)
		(property "Val" "0R"
			(at 0 0 0)
			(unlocked yes)
			(layer "F.Fab")
			(hide yes)
			(effects
				(font
					(size 1 1)
					(thickness 0.15)
				)
			)
		)
		(property "Author" "Antmicro"
			(at 0 0 0)
			(unlocked yes)
			(layer "F.Fab")
			(hide yes)
			(effects
				(font
					(size 1 1)
					(thickness 0.15)
				)
			)
		)
		(property "License" "Apache-2.0"
			(at 0 0 0)
			(unlocked yes)
			(layer "F.Fab")
			(hide yes)
			(effects
				(font
					(size 1 1)
					(thickness 0.15)
				)
			)
		)
		(property "Max. Curr." "22.4A"
			(at 0 0 0)
			(unlocked yes)
			(layer "F.Fab")
			(hide yes)
			(effects
				(font
					(size 1 1)
					(thickness 0.15)
				)
			)
		)
		(property "Tolerance" "template_tolerance"
			(at 0 0 0)
			(unlocked yes)
			(layer "F.Fab")
			(hide yes)
			(effects
				(font
					(size 1 1)
					(thickness 0.15)
				)
			)
		)
		(component_classes
			(class "DCDC_1V15")
		)
		(sheetname "/DCDC/")
		(sheetfile "dcdc.kicad_sch")
		(attr smd)
		(fp_line
			(start -0.15 -0.4)
			(end 0.15 -0.4)
			(stroke
				(width 0.15)
				(type solid)
			)
			(layer "F.SilkS")
		)
		(fp_line
			(start -0.15 0.4)
			(end 0.15 0.4)
			(stroke
				(width 0.15)
				(type solid)
			)
			(layer "F.SilkS")
		)
		(fp_rect
			(start -1.25 -0.65)
			(end 1.25 0.65)
			(stroke
				(width 0.05)
				(type solid)
			)
			(fill no)
			(layer "F.CrtYd")
		)
		(fp_rect
			(start -0.8 -0.4)
			(end 0.8 0.4)
			(stroke
				(width 0.15)
				(type solid)
			)
			(fill no)
			(layer "F.Fab")
		)
		(fp_text user "${REFERENCE}"
			(at -1.25 3.898 0)
			(layer "F.Fab")
			(effects
				(font
					(size 0.7 0.7)
					(thickness 0.15)
				)
				(justify left bottom)
			)
		)
		(fp_text user "Author: Antmicro"
			(at -1.25 4.9 0)
			(layer "F.Fab")
			(effects
				(font
					(size 0.7 0.7)
					(thickness 0.15)
				)
				(justify left bottom)
			)
		)
		(fp_text user "License: Apache-2.0"
			(at -1.25 5.9 0)
			(layer "F.Fab")
			(effects
				(font
					(size 0.7 0.7)
					(thickness 0.15)
				)
				(justify left bottom)
			)
		)
		(pad "1" smd roundrect
			(at -0.7 0)
			(size 0.8 1)
			(layers "F.Cu" "F.Mask" "F.Paste")
			(roundrect_rratio 0.2)
			(net 280 "/DCDC/1V15_OUT")
			(pintype "passive")
		)
		(pad "2" smd roundrect
			(at 0.7 0)
			(size 0.8 1)
			(layers "F.Cu" "F.Mask" "F.Paste")
			(roundrect_rratio 0.2)
			(net 282 "+1V15")
			(pintype "passive")
		)
	)
	(footprint "antmicro-footprints:Vishay_PowerPAK_1212-8_Single"
		(layer "F.Cu")
		(at 216.743 68.8)
		(descr "PowerPAK 1212-8 Single")
		(tags "Vishay PowerPAK 1212-8 Single")
		(property "Reference" "Q32"
			(at 2.907 0.4 90)
			(layer "F.SilkS")
			(effects
				(font
					(size 0.7 0.7)
					(thickness 0.15)
				)
				(justify left bottom)
			)
		)
		(property "Value" "SISS05DN-T1-GE3"
			(at 0 2.7 0)
			(layer "F.Fab")
			(effects
				(font
					(size 0.7 0.7)
					(thickness 0.15)
				)
				(justify left bottom)
			)
		)
		(property "Datasheet" "https://www.vishay.com/docs/77029/siss05dn.pdf"
			(at 0 0 0)
			(layer "F.Fab")
			(hide yes)
			(effects
				(font
					(size 1.27 1.27)
					(thickness 0.15)
				)
			)
		)
		(property "Description" "Power MOSFET, P Channel, 30 V, 108 A, 0.0035 ohm, PowerPAK 1212, Surface Mount"
			(at 0 0 0)
			(layer "F.Fab")
			(hide yes)
			(effects
				(font
					(size 1.27 1.27)
					(thickness 0.15)
				)
			)
		)
		(property "MPN" "SISS05DN-T1-GE3"
			(at 0 0 0)
			(unlocked yes)
			(layer "F.Fab")
			(hide yes)
			(effects
				(font
					(size 1 1)
					(thickness 0.15)
				)
			)
		)
		(property "Manufacturer" "Vishay"
			(at 0 0 0)
			(unlocked yes)
			(layer "F.Fab")
			(hide yes)
			(effects
				(font
					(size 1 1)
					(thickness 0.15)
				)
			)
		)
		(property "Author" "Antmicro"
			(at 0 0 0)
			(unlocked yes)
			(layer "F.Fab")
			(hide yes)
			(effects
				(font
					(size 1 1)
					(thickness 0.15)
				)
			)
		)
		(property "License" "Apache-2.0"
			(at 0 0 0)
			(unlocked yes)
			(layer "F.Fab")
			(hide yes)
			(effects
				(font
					(size 1 1)
					(thickness 0.15)
				)
			)
		)
		(sheetname "/Power/")
		(sheetfile "power.kicad_sch")
		(attr smd)
		(fp_line
			(start -1.651 -1.651)
			(end -1.651 -1.317)
			(stroke
				(width 0.15)
				(type solid)
			)
			(layer "F.SilkS")
		)
		(fp_line
			(start -1.651 -1.651)
			(end 1.648 -1.651)
			(stroke
				(width 0.15)
				(type solid)
			)
			(layer "F.SilkS")
		)
		(fp_line
			(start -1.635 1.3)
			(end -1.635 1.634)
			(stroke
				(width 0.15)
				(type solid)
			)
			(layer "F.SilkS")
		)
		(fp_line
			(start -1.635 1.634)
			(end 1.634 1.634)
			(stroke
				(width 0.15)
				(type solid)
			)
			(layer "F.SilkS")
		)
		(fp_line
			(start 1.634 1.3)
			(end 1.634 1.634)
			(stroke
				(width 0.15)
				(type solid)
			)
			(layer "F.SilkS")
		)
		(fp_line
			(start 1.648 -1.651)
			(end 1.648 -1.317)
			(stroke
				(width 0.15)
				(type solid)
			)
			(layer "F.SilkS")
		)
		(fp_circle
			(center -1.9 -1.4)
			(end -1.85 -1.4)
			(stroke
				(width 0.15)
				(type solid)
			)
			(fill yes)
			(layer "F.SilkS")
		)
		(fp_rect
			(start -2 -1.8)
			(end 2 1.798)
			(stroke
				(width 0.05)
				(type solid)
			)
			(fill no)
			(layer "F.CrtYd")
		)
		(fp_line
			(start -1.6425 -1.4175)
			(end -1.4175 -1.6425)
			(stroke
				(width 0.15)
				(type solid)
			)
			(layer "F.Fab")
		)
		(fp_rect
			(start -1.651 -1.651)
			(end 1.648 1.648)
			(stroke
				(width 0.15)
				(type solid)
			)
			(fill no)
			(layer "F.Fab")
		)
		(fp_text user "License: Apache-2.0"
			(at -8 7.1 0)
			(layer "F.Fab")
			(effects
				(font
					(size 0.7 0.7)
					(thickness 0.15)
				)
				(justify left bottom)
			)
		)
		(fp_text user "Author: Antmicro"
			(at -8 5.9 0)
			(layer "F.Fab")
			(effects
				(font
					(size 0.7 0.7)
					(thickness 0.15)
				)
				(justify left bottom)
			)
		)
		(fp_text user "${REFERENCE}"
			(at -8 4.7 0)
			(layer "F.Fab")
			(effects
				(font
					(size 0.7 0.7)
					(thickness 0.15)
				)
				(justify left bottom)
			)
		)
		(pad "1" smd rect
			(at -1.436 -0.99)
			(size 0.99 0.405)
			(layers "F.Cu" "F.Mask" "F.Paste")
			(net 1383 "VCC_NO_OVP")
			(pinfunction "S")
			(pintype "passive")
		)
		(pad "2" smd rect
			(at -1.436 -0.332)
			(size 0.99 0.405)
			(layers "F.Cu" "F.Mask" "F.Paste")
			(net 1383 "VCC_NO_OVP")
			(pinfunction "S")
			(pintype "passive")
		)
		(pad "3" smd rect
			(at -1.436 0.33)
			(size 0.99 0.405)
			(layers "F.Cu" "F.Mask" "F.Paste")
			(net 1383 "VCC_NO_OVP")
			(pinfunction "S")
			(pintype "passive")
		)
		(pad "4" smd rect
			(at -1.436 0.988)
			(size 0.99 0.405)
			(layers "F.Cu" "F.Mask" "F.Paste")
			(net 1384 "Net-(Q32-G)")
			(pinfunction "G")
			(pintype "input")
		)
		(pad "5" smd custom
			(at 0.557 0)
			(size 1.725 2.235)
			(layers "F.Cu" "F.Mask" "F.Paste")
			(net 3 "VCC_IN")
			(pinfunction "D")
			(pintype "passive")
			(zone_connect 2)
			(options
				(clearance outline)
				(anchor rect)
			)
			(primitives
				(gr_poly
					(pts
						(xy 0.8625 0.1275) (xy 0.8625 -0.1275) (xy 1.3725 -0.1275) (xy 1.3725 -0.5325) (xy 0.8625 -0.5325)
						(xy 0.8625 -0.7875) (xy 1.3725 -0.7875) (xy 1.3725 -1.195) (xy 0.6125 -1.195) (xy 0.6125 1.195)
						(xy 1.3725 1.195) (xy 1.3725 0.7875) (xy 0.8625 0.7875) (xy 0.8625 0.5325) (xy 1.3725 0.5325)
						(xy 1.3725 0.1275)
					)
					(width 0)
					(fill yes)
				)
			)
		)
	)
	(footprint "antmicro-footprints:LED_0603_1608Metric_G"
		(layer "F.Cu")
		(at 177.5 55.32 -90)
		(descr "LED SMD 0603 Green")
		(tags "LED SMD 0603 Green")
		(property "Reference" "D63"
			(at -1.04 1.365 90)
			(layer "F.SilkS")
			(effects
				(font
					(size 0.7 0.7)
					(thickness 0.15)
				)
				(justify right top)
			)
		)
		(property "Value" "LED_G_0603_LTST-C190GKT"
			(at -0.001 1.599 90)
			(layer "F.Fab")
			(effects
				(font
					(size 0.7 0.7)
					(thickness 0.15)
				)
				(justify right top)
			)
		)
		(property "Datasheet" "https://media.digikey.com/pdf/Data%20Sheets/Lite-On%20PDFs/LTST-C190GKT.pdf"
			(at 0 0 90)
			(layer "F.Fab")
			(hide yes)
			(effects
				(font
					(size 1.27 1.27)
					(thickness 0.15)
				)
			)
		)
		(property "Description" "LED, Green, SMD, 0603, 20 mA, 2.1 V, 569 nm"
			(at 0 0 90)
			(layer "F.Fab")
			(hide yes)
			(effects
				(font
					(size 1.27 1.27)
					(thickness 0.15)
				)
			)
		)
		(property "MPN" "LTST-C190GKT"
			(at 0 0 270)
			(unlocked yes)
			(layer "F.Fab")
			(hide yes)
			(effects
				(font
					(size 1 1)
					(thickness 0.15)
				)
			)
		)
		(property "Manufacturer" "Lite-On"
			(at 0 0 270)
			(unlocked yes)
			(layer "F.Fab")
			(hide yes)
			(effects
				(font
					(size 1 1)
					(thickness 0.15)
				)
			)
		)
		(property "Author" "Antmicro"
			(at 0 0 270)
			(unlocked yes)
			(layer "F.Fab")
			(hide yes)
			(effects
				(font
					(size 1 1)
					(thickness 0.15)
				)
			)
		)
		(property "License" "Apache-2.0"
			(at 0 0 270)
			(unlocked yes)
			(layer "F.Fab")
			(hide yes)
			(effects
				(font
					(size 1 1)
					(thickness 0.15)
				)
			)
		)
		(property "Color" "Green"
			(at 0 0 270)
			(unlocked yes)
			(layer "F.Fab")
			(hide yes)
			(effects
				(font
					(size 1 1)
					(thickness 0.15)
				)
			)
		)
		(sheetname "/Power/")
		(sheetfile "power.kicad_sch")
		(attr smd)
		(fp_line
			(start 0.22 0.35)
			(end -0.22 0.35)
			(stroke
				(width 0.15)
				(type solid)
			)
			(layer "F.SilkS")
		)
		(fp_line
			(start -0.094672 0.201008)
			(end -0.094672 -0.198992)
			(stroke
				(width 0.1)
				(type solid)
			)
			(layer "F.SilkS")
		)
		(fp_line
			(start 0.105328 0.201008)
			(end -0.094672 0.001008)
			(stroke
				(width 0.1)
				(type solid)
			)
			(layer "F.SilkS")
		)
		(fp_line
			(start 0.105328 0.201008)
			(end 0.105328 -0.198992)
			(stroke
				(width 0.1)
				(type solid)
			)
			(layer "F.SilkS")
		)
		(fp_line
			(start -0.094672 0.001008)
			(end -0.24 0.001008)
			(stroke
				(width 0.1)
				(type solid)
			)
			(layer "F.SilkS")
		)
		(fp_line
			(start -0.094672 0.001008)
			(end 0.105328 -0.198992)
			(stroke
				(width 0.1)
				(type solid)
			)
			(layer "F.SilkS")
		)
		(fp_line
			(start 0.105328 0.001008)
			(end 0.24 0.001)
			(stroke
				(width 0.1)
				(type solid)
			)
			(layer "F.SilkS")
		)
		(fp_line
			(start -1.18 -0.319)
			(end -1.18 0.321)
			(stroke
				(width 0.15)
				(type solid)
			)
			(layer "F.SilkS")
		)
		(fp_line
			(start 0.22 -0.35)
			(end -0.22 -0.35)
			(stroke
				(width 0.15)
				(type solid)
			)
			(layer "F.SilkS")
		)
		(fp_rect
			(start 1.25 0.65)
			(end -1.25 -0.65)
			(stroke
				(width 0.05)
				(type solid)
			)
			(fill no)
			(layer "F.CrtYd")
		)
		(fp_line
			(start -0.199 0.2)
			(end -0.199 0.1)
			(stroke
				(width 0.15)
				(type solid)
			)
			(layer "F.Fab")
		)
		(fp_line
			(start 0.201 0.2)
			(end 0.201 0)
			(stroke
				(width 0.15)
				(type solid)
			)
			(layer "F.Fab")
		)
		(fp_line
			(start -0.199 0)
			(end -0.597 0)
			(stroke
				(width 0.15)
				(type solid)
			)
			(layer "F.Fab")
		)
		(fp_line
			(start -0.101 0)
			(end 0.201 0.2)
			(stroke
				(width 0.15)
				(type solid)
			)
			(layer "F.Fab")
		)
		(fp_line
			(start 0.201 0)
			(end 0.201 -0.202)
			(stroke
				(width 0.15)
				(type solid)
			)
			(layer "F.Fab")
		)
		(fp_line
			(start 0.599 0)
			(end 0.201 0)
			(stroke
				(width 0.15)
				(type solid)
			)
			(layer "F.Fab")
		)
		(fp_line
			(start -0.199 -0.202)
			(end -0.199 0.1)
			(stroke
				(width 0.15)
				(type solid)
			)
			(layer "F.Fab")
		)
		(fp_line
			(start 0.201 -0.202)
			(end -0.101 0)
			(stroke
				(width 0.15)
				(type solid)
			)
			(layer "F.Fab")
		)
		(fp_rect
			(start 0.848 0.4)
			(end -0.85 -0.402)
			(stroke
				(width 0.15)
				(type solid)
			)
			(fill no)
			(layer "F.Fab")
		)
		(fp_text user "License: Apache-2.0"
			(at -1.4224 3.599 90)
			(layer "F.Fab")
			(effects
				(font
					(size 0.7 0.7)
					(thickness 0.15)
				)
				(justify right top)
			)
		)
		(fp_text user "Author: Antmicro"
			(at -1.4224 4.799 90)
			(layer "F.Fab")
			(effects
				(font
					(size 0.7 0.7)
					(thickness 0.15)
				)
				(justify right top)
			)
		)
		(fp_text user "${REFERENCE}"
			(at -1.4224 5.999 90)
			(layer "F.Fab")
			(effects
				(font
					(size 0.7 0.7)
					(thickness 0.15)
				)
				(justify right top)
			)
		)
		(pad "1" smd roundrect
			(at -0.7 0 90)
			(size 0.8 1)
			(layers "F.Cu" "F.Mask" "F.Paste")
			(roundrect_rratio 0.2)
			(net 1 "GND")
			(pinfunction "C")
			(pintype "passive")
		)
		(pad "2" smd roundrect
			(at 0.7 0 90)
			(size 0.8 1)
			(layers "F.Cu" "F.Mask" "F.Paste")
			(roundrect_rratio 0.2)
			(net 46 "Net-(D63-A)")
			(pinfunction "A")
			(pintype "passive")
		)
	)
	(footprint "antmicro-footprints:LED_0603_1608Metric_G"
		(layer "F.Cu")
		(at 184.25 55.3 -90)
		(descr "LED SMD 0603 Green")
		(tags "LED SMD 0603 Green")
		(property "Reference" "D4"
			(at -0.62 1.6 90)
			(layer "F.SilkS")
			(effects
				(font
					(size 0.7 0.7)
					(thickness 0.15)
				)
				(justify right top)
			)
		)
		(property "Value" "LED_G_0603_LTST-C190GKT"
			(at -0.001 1.599 90)
			(layer "F.Fab")
			(effects
				(font
					(size 0.7 0.7)
					(thickness 0.15)
				)
				(justify right top)
			)
		)
		(property "Datasheet" "https://media.digikey.com/pdf/Data%20Sheets/Lite-On%20PDFs/LTST-C190GKT.pdf"
			(at 0 0 90)
			(layer "F.Fab")
			(hide yes)
			(effects
				(font
					(size 1.27 1.27)
					(thickness 0.15)
				)
			)
		)
		(property "Description" "LED, Green, SMD, 0603, 20 mA, 2.1 V, 569 nm"
			(at 0 0 90)
			(layer "F.Fab")
			(hide yes)
			(effects
				(font
					(size 1.27 1.27)
					(thickness 0.15)
				)
			)
		)
		(property "MPN" "LTST-C190GKT"
			(at 0 0 270)
			(unlocked yes)
			(layer "F.Fab")
			(hide yes)
			(effects
				(font
					(size 1 1)
					(thickness 0.15)
				)
			)
		)
		(property "Manufacturer" "Lite-On"
			(at 0 0 270)
			(unlocked yes)
			(layer "F.Fab")
			(hide yes)
			(effects
				(font
					(size 1 1)
					(thickness 0.15)
				)
			)
		)
		(property "Author" "Antmicro"
			(at 0 0 270)
			(unlocked yes)
			(layer "F.Fab")
			(hide yes)
			(effects
				(font
					(size 1 1)
					(thickness 0.15)
				)
			)
		)
		(property "License" "Apache-2.0"
			(at 0 0 270)
			(unlocked yes)
			(layer "F.Fab")
			(hide yes)
			(effects
				(font
					(size 1 1)
					(thickness 0.15)
				)
			)
		)
		(property "Color" "Green"
			(at 0 0 270)
			(unlocked yes)
			(layer "F.Fab")
			(hide yes)
			(effects
				(font
					(size 1 1)
					(thickness 0.15)
				)
			)
		)
		(sheetname "/Power/")
		(sheetfile "power.kicad_sch")
		(attr smd)
		(fp_line
			(start 0.22 0.35)
			(end -0.22 0.35)
			(stroke
				(width 0.15)
				(type solid)
			)
			(layer "F.SilkS")
		)
		(fp_line
			(start -0.094672 0.201008)
			(end -0.094672 -0.198992)
			(stroke
				(width 0.1)
				(type solid)
			)
			(layer "F.SilkS")
		)
		(fp_line
			(start 0.105328 0.201008)
			(end -0.094672 0.001008)
			(stroke
				(width 0.1)
				(type solid)
			)
			(layer "F.SilkS")
		)
		(fp_line
			(start 0.105328 0.201008)
			(end 0.105328 -0.198992)
			(stroke
				(width 0.1)
				(type solid)
			)
			(layer "F.SilkS")
		)
		(fp_line
			(start -0.094672 0.001008)
			(end -0.24 0.001008)
			(stroke
				(width 0.1)
				(type solid)
			)
			(layer "F.SilkS")
		)
		(fp_line
			(start -0.094672 0.001008)
			(end 0.105328 -0.198992)
			(stroke
				(width 0.1)
				(type solid)
			)
			(layer "F.SilkS")
		)
		(fp_line
			(start 0.105328 0.001008)
			(end 0.24 0.001)
			(stroke
				(width 0.1)
				(type solid)
			)
			(layer "F.SilkS")
		)
		(fp_line
			(start -1.18 -0.319)
			(end -1.18 0.321)
			(stroke
				(width 0.15)
				(type solid)
			)
			(layer "F.SilkS")
		)
		(fp_line
			(start 0.22 -0.35)
			(end -0.22 -0.35)
			(stroke
				(width 0.15)
				(type solid)
			)
			(layer "F.SilkS")
		)
		(fp_rect
			(start 1.25 0.65)
			(end -1.25 -0.65)
			(stroke
				(width 0.05)
				(type solid)
			)
			(fill no)
			(layer "F.CrtYd")
		)
		(fp_line
			(start -0.199 0.2)
			(end -0.199 0.1)
			(stroke
				(width 0.15)
				(type solid)
			)
			(layer "F.Fab")
		)
		(fp_line
			(start 0.201 0.2)
			(end 0.201 0)
			(stroke
				(width 0.15)
				(type solid)
			)
			(layer "F.Fab")
		)
		(fp_line
			(start -0.199 0)
			(end -0.597 0)
			(stroke
				(width 0.15)
				(type solid)
			)
			(layer "F.Fab")
		)
		(fp_line
			(start -0.101 0)
			(end 0.201 0.2)
			(stroke
				(width 0.15)
				(type solid)
			)
			(layer "F.Fab")
		)
		(fp_line
			(start 0.201 0)
			(end 0.201 -0.202)
			(stroke
				(width 0.15)
				(type solid)
			)
			(layer "F.Fab")
		)
		(fp_line
			(start 0.599 0)
			(end 0.201 0)
			(stroke
				(width 0.15)
				(type solid)
			)
			(layer "F.Fab")
		)
		(fp_line
			(start -0.199 -0.202)
			(end -0.199 0.1)
			(stroke
				(width 0.15)
				(type solid)
			)
			(layer "F.Fab")
		)
		(fp_line
			(start 0.201 -0.202)
			(end -0.101 0)
			(stroke
				(width 0.15)
				(type solid)
			)
			(layer "F.Fab")
		)
		(fp_rect
			(start 0.848 0.4)
			(end -0.85 -0.402)
			(stroke
				(width 0.15)
				(type solid)
			)
			(fill no)
			(layer "F.Fab")
		)
		(fp_text user "${REFERENCE}"
			(at -1.4224 5.999 90)
			(layer "F.Fab")
			(effects
				(font
					(size 0.7 0.7)
					(thickness 0.15)
				)
				(justify right top)
			)
		)
		(fp_text user "License: Apache-2.0"
			(at -1.4224 3.599 90)
			(layer "F.Fab")
			(effects
				(font
					(size 0.7 0.7)
					(thickness 0.15)
				)
				(justify right top)
			)
		)
		(fp_text user "Author: Antmicro"
			(at -1.4224 4.799 90)
			(layer "F.Fab")
			(effects
				(font
					(size 0.7 0.7)
					(thickness 0.15)
				)
				(justify right top)
			)
		)
		(pad "1" smd roundrect
			(at -0.7 0 90)
			(size 0.8 1)
			(layers "F.Cu" "F.Mask" "F.Paste")
			(roundrect_rratio 0.2)
			(net 1 "GND")
			(pinfunction "C")
			(pintype "passive")
		)
		(pad "2" smd roundrect
			(at 0.7 0 90)
			(size 0.8 1)
			(layers "F.Cu" "F.Mask" "F.Paste")
			(roundrect_rratio 0.2)
			(net 528 "Net-(D4-A)")
			(pinfunction "A")
			(pintype "passive")
		)
	)
	(footprint "antmicro-footprints:DFN-6-1EP_3x3mm_P1mm_EP1.5x2.4mm"
		(layer "F.Cu")
		(at 138.6 57.3)
		(descr "DFN, 6 Pin")
		(tags "DFN NoLead")
		(property "Reference" "U79"
			(at -1.01 -1.8 0)
			(layer "F.SilkS")
			(effects
				(font
					(size 0.7 0.7)
					(thickness 0.15)
				)
				(justify left bottom)
			)
		)
		(property "Value" "LD39100PUR"
			(at 0 2.600001 0)
			(layer "F.Fab")
			(effects
				(font
					(size 0.7 0.7)
					(thickness 0.15)
				)
				(justify left bottom)
			)
		)
		(property "Datasheet" "https://eu.mouser.com/datasheet/2/389/ld39100-1849679.pdf"
			(at 0 0 0)
			(layer "F.Fab")
			(hide yes)
			(effects
				(font
					(size 1.27 1.27)
					(thickness 0.15)
				)
			)
		)
		(property "Description" "LDO Voltage Regulator 1A Low Quiescent Reg 1.5 to 5.5 V 200mV"
			(at 0 0 0)
			(layer "F.Fab")
			(hide yes)
			(effects
				(font
					(size 1.27 1.27)
					(thickness 0.15)
				)
			)
		)
		(property "MPN" "LD39100PUR"
			(at 0 0 0)
			(unlocked yes)
			(layer "F.Fab")
			(hide yes)
			(effects
				(font
					(size 1 1)
					(thickness 0.15)
				)
			)
		)
		(property "Manufacturer" "STMicroelectronics"
			(at 0 0 0)
			(unlocked yes)
			(layer "F.Fab")
			(hide yes)
			(effects
				(font
					(size 1 1)
					(thickness 0.15)
				)
			)
		)
		(property "Author" "Antmicro"
			(at 0 0 0)
			(unlocked yes)
			(layer "F.Fab")
			(hide yes)
			(effects
				(font
					(size 1 1)
					(thickness 0.15)
				)
			)
		)
		(property "License" "Apache-2.0"
			(at 0 0 0)
			(unlocked yes)
			(layer "F.Fab")
			(hide yes)
			(effects
				(font
					(size 1 1)
					(thickness 0.15)
				)
			)
		)
		(sheetname "/Power/")
		(sheetfile "power.kicad_sch")
		(attr smd)
		(fp_line
			(start -1.5 -1.6)
			(end 1.5 -1.6)
			(stroke
				(width 0.15)
				(type solid)
			)
			(layer "F.SilkS")
		)
		(fp_line
			(start -1.5 1.61)
			(end 1.499 1.61)
			(stroke
				(width 0.15)
				(type solid)
			)
			(layer "F.SilkS")
		)
		(fp_circle
			(center -1.7 -1.4)
			(end -1.65 -1.4)
			(stroke
				(width 0.15)
				(type solid)
			)
			(fill yes)
			(layer "F.SilkS")
		)
		(fp_poly
			(pts
				(xy -1.899999 -1.7) (xy 1.899999 -1.7) (xy 1.899999 1.7) (xy -1.899999 1.7)
			)
			(stroke
				(width 0.05)
				(type solid)
			)
			(fill no)
			(layer "F.CrtYd")
		)
		(fp_line
			(start -1.5 -0.75)
			(end -0.75 -1.5)
			(stroke
				(width 0.15)
				(type solid)
			)
			(layer "F.Fab")
		)
		(fp_line
			(start -1.5 1.499)
			(end -1.5 -0.75)
			(stroke
				(width 0.15)
				(type solid)
			)
			(layer "F.Fab")
		)
		(fp_line
			(start -0.75 -1.5)
			(end 1.499 -1.5)
			(stroke
				(width 0.15)
				(type solid)
			)
			(layer "F.Fab")
		)
		(fp_line
			(start 1.499 -1.5)
			(end 1.499 1.499)
			(stroke
				(width 0.15)
				(type solid)
			)
			(layer "F.Fab")
		)
		(fp_line
			(start 1.499 1.499)
			(end -1.5 1.499)
			(stroke
				(width 0.15)
				(type solid)
			)
			(layer "F.Fab")
		)
		(fp_text user "License: Apache-2.0"
			(at -2.101 6.85 0)
			(layer "F.Fab")
			(effects
				(font
					(size 0.7 0.7)
					(thickness 0.15)
				)
				(justify left bottom)
			)
		)
		(fp_text user "${REFERENCE}"
			(at -2.101 4.45 0)
			(layer "F.Fab")
			(effects
				(font
					(size 0.7 0.7)
					(thickness 0.15)
				)
				(justify left bottom)
			)
		)
		(fp_text user "Author: Antmicro"
			(at -2.101 5.65 0)
			(layer "F.Fab")
			(effects
				(font
					(size 0.7 0.7)
					(thickness 0.15)
				)
				(justify left bottom)
			)
		)
		(pad "" smd roundrect
			(at -0.375 -0.6)
			(size 0.6 0.97)
			(layers "F.Paste")
			(roundrect_rratio 0.25)
		)
		(pad "" smd roundrect
			(at -0.375 0.598)
			(size 0.6 0.97)
			(layers "F.Paste")
			(roundrect_rratio 0.25)
		)
		(pad "" smd roundrect
			(at 0.373 -0.6)
			(size 0.6 0.97)
			(layers "F.Paste")
			(roundrect_rratio 0.25)
		)
		(pad "" smd roundrect
			(at 0.373 0.598)
			(size 0.6 0.97)
			(layers "F.Paste")
			(roundrect_rratio 0.25)
		)
		(pad "1" smd roundrect
			(at -1.45 -1)
			(size 0.8 0.4)
			(layers "F.Cu" "F.Mask" "F.Paste")
			(roundrect_rratio 0.25)
			(net 491 "+5V_AON")
			(pinfunction "EN")
			(pintype "input")
		)
		(pad "2" smd roundrect
			(at -1.45 0)
			(size 0.8 0.4)
			(layers "F.Cu" "F.Mask" "F.Paste")
			(roundrect_rratio 0.25)
			(net 1 "GND")
			(pinfunction "GND")
			(pintype "power_in")
		)
		(pad "3" smd roundrect
			(at -1.45 0.998)
			(size 0.8 0.4)
			(layers "F.Cu" "F.Mask" "F.Paste")
			(roundrect_rratio 0.25)
			(net 1397 "unconnected-(U79-PG-Pad3)")
			(pinfunction "PG")
			(pintype "open_collector+no_connect")
		)
		(pad "4" smd roundrect
			(at 1.449 0.998)
			(size 0.8 0.4)
			(layers "F.Cu" "F.Mask" "F.Paste")
			(roundrect_rratio 0.25)
			(net 31 "/Power/3V3_LDO")
			(pinfunction "V_{OUT}")
			(pintype "power_out")
		)
		(pad "5" smd roundrect
			(at 1.449 0)
			(size 0.8 0.4)
			(layers "F.Cu" "F.Mask" "F.Paste")
			(roundrect_rratio 0.25)
			(net 1396 "Net-(U79-ADJ)")
			(pinfunction "ADJ")
			(pintype "input")
		)
		(pad "6" smd roundrect
			(at 1.449 -1)
			(size 0.8 0.4)
			(layers "F.Cu" "F.Mask" "F.Paste")
			(roundrect_rratio 0.25)
			(net 491 "+5V_AON")
			(pinfunction "V_{IN}")
			(pintype "power_in")
		)
		(pad "7" smd rect
			(at 0 0)
			(size 1.5 2.4)
			(layers "F.Cu" "F.Mask")
			(net 1 "GND")
			(pinfunction "GND")
			(pintype "passive")
		)
	)
	(footprint "antmicro-footprints:R_0402_1005Metric"
		(layer "F.Cu")
		(at 232.540532 95.71 180)
		(descr "Resistor SMD 0402")
		(tags "resistor SMD 0402")
		(property "Reference" "R157"
			(at -1.122484 -0.772697 0)
			(layer "F.SilkS")
			(effects
				(font
					(size 0.7 0.7)
					(thickness 0.15)
				)
				(justify right top)
			)
		)
		(property "Value" "R_4k7_0402"
			(at -1.011843 1.772046 0)
			(layer "F.Fab")
			(effects
				(font
					(size 0.7 0.7)
					(thickness 0.15)
				)
				(justify right top)
			)
		)
		(property "Datasheet" "https://www.bourns.com/docs/product-datasheets/cr.pdf"
			(at 0 0 0)
			(layer "F.Fab")
			(hide yes)
			(effects
				(font
					(size 1.27 1.27)
					(thickness 0.15)
				)
			)
		)
		(property "Description" "SMD Chip Resistor, 4.7 kohm, ± 1%, 62.5 mW, 0402 [1005 Metric], Thick Film, General Purpose"
			(at 0 0 0)
			(layer "F.Fab")
			(hide yes)
			(effects
				(font
					(size 1.27 1.27)
					(thickness 0.15)
				)
			)
		)
		(property "Manufacturer" "Bourns"
			(at 0 0 180)
			(unlocked yes)
			(layer "F.Fab")
			(hide yes)
			(effects
				(font
					(size 1 1)
					(thickness 0.15)
				)
			)
		)
		(property "MPN" "CR0402-FX-4701GLF"
			(at 0 0 180)
			(unlocked yes)
			(layer "F.Fab")
			(hide yes)
			(effects
				(font
					(size 1 1)
					(thickness 0.15)
				)
			)
		)
		(property "Val" "4k7"
			(at 0 0 180)
			(unlocked yes)
			(layer "F.Fab")
			(hide yes)
			(effects
				(font
					(size 1 1)
					(thickness 0.15)
				)
			)
		)
		(property "License" "Apache-2.0"
			(at 0 0 180)
			(unlocked yes)
			(layer "F.Fab")
			(hide yes)
			(effects
				(font
					(size 1 1)
					(thickness 0.15)
				)
			)
		)
		(property "Author" "Antmicro"
			(at 0 0 180)
			(unlocked yes)
			(layer "F.Fab")
			(hide yes)
			(effects
				(font
					(size 1 1)
					(thickness 0.15)
				)
			)
		)
		(property "Tolerance" "1%"
			(at 0 0 180)
			(unlocked yes)
			(layer "F.Fab")
			(hide yes)
			(effects
				(font
					(size 1 1)
					(thickness 0.15)
				)
			)
		)
		(sheetname "/USB DP Alt mode/")
		(sheetfile "usb_dp.kicad_sch")
		(attr smd)
		(fp_poly
			(pts
				(xy -0.925 -0.47) (xy 0.925 -0.47) (xy 0.925 0.47) (xy -0.925 0.47)
			)
			(stroke
				(width 0.05)
				(type default)
			)
			(fill no)
			(layer "F.CrtYd")
		)
		(fp_poly
			(pts
				(xy -0.5 -0.25) (xy 0.5 -0.25) (xy 0.5 0.25) (xy -0.5 0.25)
			)
			(stroke
				(width 0.15)
				(type solid)
			)
			(fill no)
			(layer "F.Fab")
		)
		(fp_text user "${REFERENCE}"
			(at -0.95 3.168 0)
			(layer "F.Fab")
			(effects
				(font
					(size 0.7 0.7)
					(thickness 0.15)
				)
				(justify right top)
			)
		)
		(fp_text user "License: Apache-2.0"
			(at -0.949999 5.169 0)
			(layer "F.Fab")
			(effects
				(font
					(size 0.7 0.7)
					(thickness 0.15)
				)
				(justify right top)
			)
		)
		(fp_text user "Author: Antmicro"
			(at -0.95 4.169 0)
			(layer "F.Fab")
			(effects
				(font
					(size 0.7 0.7)
					(thickness 0.15)
				)
				(justify right top)
			)
		)
		(pad "1" smd roundrect
			(at -0.48 0 180)
			(size 0.59 0.64)
			(layers "F.Cu" "F.Mask" "F.Paste")
			(roundrect_rratio 0.25)
			(net 1388 "Net-(D25-A)")
			(pintype "passive")
		)
		(pad "2" smd roundrect
			(at 0.48 0 180)
			(size 0.59 0.64)
			(layers "F.Cu" "F.Mask" "F.Paste")
			(roundrect_rratio 0.25)
			(net 376 "/USB DP Alt mode/USBC1_VBUS")
			(pintype "passive")
		)
	)
	(footprint "antmicro-footprints:USON-8_2x3mm_P0.5mm"
		(layer "F.Cu")
		(at 192.95 84.45)
		(property "Reference" "U29"
			(at 1.011 1.710001 0)
			(layer "F.SilkS")
			(effects
				(font
					(size 0.7 0.7)
					(thickness 0.15)
				)
				(justify right top)
			)
		)
		(property "Value" "W25Q80DV_USON"
			(at 0 2.300001 0)
			(layer "F.Fab")
			(effects
				(font
					(size 0.7 0.7)
					(thickness 0.15)
				)
				(justify left bottom)
			)
		)
		(property "Datasheet" "https://www.mouser.com/datasheet/2/949/w25q80dv_dl_revh_10022015-1489677.pdf"
			(at 0 0 0)
			(layer "F.Fab")
			(hide yes)
			(effects
				(font
					(size 1.27 1.27)
					(thickness 0.15)
				)
			)
		)
		(property "Description" "FLASH - NOR Memory IC 8Mbit SPI - Quad I/O 104 MHz 8-USON (2x3)"
			(at 0 0 0)
			(layer "F.Fab")
			(hide yes)
			(effects
				(font
					(size 1.27 1.27)
					(thickness 0.15)
				)
			)
		)
		(property "MPN" "W25Q80DVUXIE TR"
			(at 0 0 0)
			(unlocked yes)
			(layer "F.Fab")
			(hide yes)
			(effects
				(font
					(size 1 1)
					(thickness 0.15)
				)
			)
		)
		(property "Manufacturer" "Winbond"
			(at 0 0 0)
			(unlocked yes)
			(layer "F.Fab")
			(hide yes)
			(effects
				(font
					(size 1 1)
					(thickness 0.15)
				)
			)
		)
		(property "Author" "Antmicro"
			(at 0 0 0)
			(unlocked yes)
			(layer "F.Fab")
			(hide yes)
			(effects
				(font
					(size 1 1)
					(thickness 0.15)
				)
			)
		)
		(property "License" "Apache-2.0"
			(at 0 0 0)
			(unlocked yes)
			(layer "F.Fab")
			(hide yes)
			(effects
				(font
					(size 1 1)
					(thickness 0.15)
				)
			)
		)
		(sheetname "/USB Debug, PD/")
		(sheetfile "usb_debug_pd.kicad_sch")
		(attr smd)
		(fp_line
			(start -1.710001 -0.89)
			(end -1.3 -1.301)
			(stroke
				(width 0.15)
				(type solid)
			)
			(layer "F.SilkS")
		)
		(fp_line
			(start -1.71 1.3)
			(end -1.710001 -0.89)
			(stroke
				(width 0.15)
				(type solid)
			)
			(layer "F.SilkS")
		)
		(fp_line
			(start -1.3 -1.301)
			(end 1.71 -1.3005)
			(stroke
				(width 0.15)
				(type solid)
			)
			(layer "F.SilkS")
		)
		(fp_line
			(start 1.71 -1.3005)
			(end 1.71 1.3005)
			(stroke
				(width 0.15)
				(type solid)
			)
			(layer "F.SilkS")
		)
		(fp_line
			(start 1.71 1.3005)
			(end -1.71 1.3)
			(stroke
				(width 0.15)
				(type solid)
			)
			(layer "F.SilkS")
		)
		(fp_circle
			(center -1.749999 -1.25)
			(end -1.7 -1.25)
			(stroke
				(width 0.15)
				(type solid)
			)
			(fill yes)
			(layer "F.SilkS")
		)
		(fp_poly
			(pts
				(xy 1.899999 -1.4) (xy -1.899999 -1.4) (xy -1.899999 1.4) (xy 1.899999 1.4)
			)
			(stroke
				(width 0.05)
				(type solid)
			)
			(fill no)
			(layer "F.CrtYd")
		)
		(fp_line
			(start -1.499 -0.499999)
			(end -0.998 -1)
			(stroke
				(width 0.15)
				(type solid)
			)
			(layer "F.Fab")
		)
		(fp_poly
			(pts
				(xy 1.5 1) (xy -1.5 1) (xy -1.5 -1) (xy 1.5 -1)
			)
			(stroke
				(width 0.15)
				(type solid)
			)
			(fill no)
			(layer "F.Fab")
		)
		(fp_text user "Author: Antmicro"
			(at -1.9 6.099 0)
			(layer "F.Fab")
			(effects
				(font
					(size 0.7 0.7)
					(thickness 0.15)
				)
				(justify left bottom)
			)
		)
		(fp_text user "${REFERENCE}"
			(at -1.899999 5.099 0)
			(layer "F.Fab")
			(effects
				(font
					(size 0.7 0.7)
					(thickness 0.15)
				)
				(justify left bottom)
			)
		)
		(fp_text user "License: Apache-2.0"
			(at -1.9 7.099 0)
			(layer "F.Fab")
			(effects
				(font
					(size 0.7 0.7)
					(thickness 0.15)
				)
				(justify left bottom)
			)
		)
		(pad "1" smd roundrect
			(at -1.273 -0.75 270)
			(size 0.3 0.7)
			(layers "F.Cu" "F.Mask" "F.Paste")
			(roundrect_rratio 0.25)
			(net 939 "/USB Debug, PD/~{PDC_CS}")
			(pinfunction "~{CS}")
			(pintype "input")
		)
		(pad "2" smd roundrect
			(at -1.273 -0.25 270)
			(size 0.3 0.7)
			(layers "F.Cu" "F.Mask" "F.Paste")
			(roundrect_rratio 0.25)
			(net 936 "/USB Debug, PD/PDC_MISO")
			(pinfunction "SO/IO1")
			(pintype "input")
		)
		(pad "3" smd roundrect
			(at -1.272999 0.248 270)
			(size 0.3 0.7)
			(layers "F.Cu" "F.Mask" "F.Paste")
			(roundrect_rratio 0.25)
			(net 271 "FLASH_PWR")
			(pinfunction "~{WP}/IO2")
			(pintype "input")
		)
		(pad "4" smd roundrect
			(at -1.273 0.748 270)
			(size 0.3 0.7)
			(layers "F.Cu" "F.Mask" "F.Paste")
			(roundrect_rratio 0.25)
			(net 1 "GND")
			(pinfunction "VSS")
			(pintype "power_in")
		)
		(pad "5" smd roundrect
			(at 1.276 0.748 270)
			(size 0.3 0.7)
			(layers "F.Cu" "F.Mask" "F.Paste")
			(roundrect_rratio 0.25)
			(net 940 "/USB Debug, PD/PDC_MOSI")
			(pinfunction "SI/IO0")
			(pintype "input")
		)
		(pad "6" smd roundrect
			(at 1.276 0.248 270)
			(size 0.3 0.7)
			(layers "F.Cu" "F.Mask" "F.Paste")
			(roundrect_rratio 0.25)
			(net 941 "/USB Debug, PD/PDC_SCLK")
			(pinfunction "SCLK")
			(pintype "input")
		)
		(pad "7" smd roundrect
			(at 1.276 -0.25 270)
			(size 0.3 0.7)
			(layers "F.Cu" "F.Mask" "F.Paste")
			(roundrect_rratio 0.25)
			(net 271 "FLASH_PWR")
			(pinfunction "~{HOLD}/IO3")
			(pintype "input")
		)
		(pad "8" smd roundrect
			(at 1.276 -0.75 270)
			(size 0.3 0.7)
			(layers "F.Cu" "F.Mask" "F.Paste")
			(roundrect_rratio 0.25)
			(net 271 "FLASH_PWR")
			(pinfunction "VCC")
			(pintype "power_in")
		)
		(pad "EP" smd roundrect
			(at 0 0)
			(size 0.2 1.6)
			(layers "F.Cu" "F.Mask" "F.Paste")
			(roundrect_rratio 0.25)
			(net 1107 "unconnected-(U29-PadEP)")
			(pinfunction "EP")
			(pintype "power_in+no_connect")
		)
	)
	(footprint "antmicro-footprints:R_0402_1005Metric"
		(layer "F.Cu")
		(at 193.026 149.7 180)
		(descr "Resistor SMD 0402")
		(tags "resistor SMD 0402")
		(property "Reference" "R204"
			(at -1.574 -0.9 0)
			(layer "F.SilkS")
			(effects
				(font
					(size 0.7 0.7)
					(thickness 0.15)
				)
				(justify right top)
			)
		)
		(property "Value" "R_200R_0402"
			(at -1.011843 1.772046 0)
			(layer "F.Fab")
			(effects
				(font
					(size 0.7 0.7)
					(thickness 0.15)
				)
				(justify right top)
			)
		)
		(property "Datasheet" "https://www.bourns.com/docs/product-datasheets/cr.pdf"
			(at 0 0 0)
			(layer "F.Fab")
			(hide yes)
			(effects
				(font
					(size 1.27 1.27)
					(thickness 0.15)
				)
			)
		)
		(property "Description" "SMD Chip Resistor, 200 ohm, ± 1%, 62.5 mW, 0402 [1005 Metric], Thick Film, General Purpose"
			(at 0 0 0)
			(layer "F.Fab")
			(hide yes)
			(effects
				(font
					(size 1.27 1.27)
					(thickness 0.15)
				)
			)
		)
		(property "MPN" "CR0402-FX-2000GLF"
			(at 0 0 180)
			(unlocked yes)
			(layer "F.Fab")
			(hide yes)
			(effects
				(font
					(size 1 1)
					(thickness 0.15)
				)
			)
		)
		(property "Manufacturer" "Bourns"
			(at 0 0 180)
			(unlocked yes)
			(layer "F.Fab")
			(hide yes)
			(effects
				(font
					(size 1 1)
					(thickness 0.15)
				)
			)
		)
		(property "License" "Apache-2.0"
			(at 0 0 180)
			(unlocked yes)
			(layer "F.Fab")
			(hide yes)
			(effects
				(font
					(size 1 1)
					(thickness 0.15)
				)
			)
		)
		(property "Author" "Antmicro"
			(at 0 0 180)
			(unlocked yes)
			(layer "F.Fab")
			(hide yes)
			(effects
				(font
					(size 1 1)
					(thickness 0.15)
				)
			)
		)
		(property "Val" "200R"
			(at 0 0 180)
			(unlocked yes)
			(layer "F.Fab")
			(hide yes)
			(effects
				(font
					(size 1 1)
					(thickness 0.15)
				)
			)
		)
		(property "Tolerance" "1%"
			(at 0 0 180)
			(unlocked yes)
			(layer "F.Fab")
			(hide yes)
			(effects
				(font
					(size 1 1)
					(thickness 0.15)
				)
			)
		)
		(sheetname "/SFP/")
		(sheetfile "sfp.kicad_sch")
		(attr smd)
		(fp_poly
			(pts
				(xy -0.925 -0.47) (xy 0.925 -0.47) (xy 0.925 0.47) (xy -0.925 0.47)
			)
			(stroke
				(width 0.05)
				(type default)
			)
			(fill no)
			(layer "F.CrtYd")
		)
		(fp_poly
			(pts
				(xy -0.5 -0.25) (xy 0.5 -0.25) (xy 0.5 0.25) (xy -0.5 0.25)
			)
			(stroke
				(width 0.15)
				(type solid)
			)
			(fill no)
			(layer "F.Fab")
		)
		(fp_text user "Author: Antmicro"
			(at -0.95 4.169 0)
			(layer "F.Fab")
			(effects
				(font
					(size 0.7 0.7)
					(thickness 0.15)
				)
				(justify right top)
			)
		)
		(fp_text user "${REFERENCE}"
			(at -0.95 3.168 0)
			(layer "F.Fab")
			(effects
				(font
					(size 0.7 0.7)
					(thickness 0.15)
				)
				(justify right top)
			)
		)
		(fp_text user "License: Apache-2.0"
			(at -0.949999 5.169 0)
			(layer "F.Fab")
			(effects
				(font
					(size 0.7 0.7)
					(thickness 0.15)
				)
				(justify right top)
			)
		)
		(pad "1" smd roundrect
			(at -0.48 0 180)
			(size 0.59 0.64)
			(layers "F.Cu" "F.Mask" "F.Paste")
			(roundrect_rratio 0.25)
			(net 1003 "/SFP/SFP_LEDY")
			(pintype "passive")
		)
		(pad "2" smd roundrect
			(at 0.48 0 180)
			(size 0.59 0.64)
			(layers "F.Cu" "F.Mask" "F.Paste")
			(roundrect_rratio 0.25)
			(net 543 "Net-(D30-C)")
			(pintype "passive")
		)
	)
	(footprint "antmicro-footprints:C_0402_1005Metric"
		(layer "F.Cu")
		(at 211.4 118.3 180)
		(descr "Capacitor SMD 0402")
		(tags "capacitor SMD 0402")
		(property "Reference" "C91"
			(at -1.2 1.4 0)
			(layer "F.SilkS")
			(effects
				(font
					(size 0.7 0.7)
					(thickness 0.15)
				)
				(justify right top)
			)
		)
		(property "Value" "C_100n_0402"
			(at -1.022927 2.155213 0)
			(layer "F.Fab")
			(effects
				(font
					(size 0.7 0.7)
					(thickness 0.15)
				)
				(justify right top)
			)
		)
		(property "Datasheet" "https://www.murata.com/products/productdetail?partno=GRM155R61H104KE14%23"
			(at 0 0 0)
			(layer "F.Fab")
			(hide yes)
			(effects
				(font
					(size 1.27 1.27)
					(thickness 0.15)
				)
			)
		)
		(property "Description" "SMD Multilayer Ceramic Capacitor, 0.1 µF, 50 V, 0402 [1005 Metric], ± 10%, X5R, GRM Series"
			(at 0 0 0)
			(layer "F.Fab")
			(hide yes)
			(effects
				(font
					(size 1.27 1.27)
					(thickness 0.15)
				)
			)
		)
		(property "MPN" "GRM155R61H104KE14D"
			(at 0 0 180)
			(unlocked yes)
			(layer "F.Fab")
			(hide yes)
			(effects
				(font
					(size 1 1)
					(thickness 0.15)
				)
			)
		)
		(property "Val" "100n"
			(at 0 0 180)
			(unlocked yes)
			(layer "F.Fab")
			(hide yes)
			(effects
				(font
					(size 1 1)
					(thickness 0.15)
				)
			)
		)
		(property "Voltage" "50V"
			(at 0 0 180)
			(unlocked yes)
			(layer "F.Fab")
			(hide yes)
			(effects
				(font
					(size 1 1)
					(thickness 0.15)
				)
			)
		)
		(property "Dielectric" "X5R"
			(at 0 0 180)
			(unlocked yes)
			(layer "F.Fab")
			(hide yes)
			(effects
				(font
					(size 1 1)
					(thickness 0.15)
				)
			)
		)
		(property "Manufacturer" "Murata"
			(at 0 0 180)
			(unlocked yes)
			(layer "F.Fab")
			(hide yes)
			(effects
				(font
					(size 1 1)
					(thickness 0.15)
				)
			)
		)
		(property "License" "Apache-2.0"
			(at 0 0 180)
			(unlocked yes)
			(layer "F.Fab")
			(hide yes)
			(effects
				(font
					(size 1 1)
					(thickness 0.15)
				)
			)
		)
		(property "Author" "Antmicro"
			(at 0 0 180)
			(unlocked yes)
			(layer "F.Fab")
			(hide yes)
			(effects
				(font
					(size 1 1)
					(thickness 0.15)
				)
			)
		)
		(sheetname "/USB Hub/")
		(sheetfile "usb_hub.kicad_sch")
		(attr smd)
		(fp_poly
			(pts
				(xy -0.925 -0.47) (xy -0.925 0.47) (xy 0.925 0.47) (xy 0.925 -0.47)
			)
			(stroke
				(width 0.05)
				(type default)
			)
			(fill no)
			(layer "F.CrtYd")
		)
		(fp_line
			(start 0.504 0.248)
			(end -0.494 0.248)
			(stroke
				(width 0.15)
				(type solid)
			)
			(layer "F.Fab")
		)
		(fp_line
			(start 0.504 -0.25)
			(end 0.504 0.248)
			(stroke
				(width 0.15)
				(type solid)
			)
			(layer "F.Fab")
		)
		(fp_line
			(start -0.494 0.248)
			(end -0.494 -0.25)
			(stroke
				(width 0.15)
				(type solid)
			)
			(layer "F.Fab")
		)
		(fp_line
			(start -0.494 -0.25)
			(end 0.504 -0.25)
			(stroke
				(width 0.15)
				(type solid)
			)
			(layer "F.Fab")
		)
		(fp_text user "License: Apache-2.0"
			(at -0.939 5.799 0)
			(layer "F.Fab")
			(effects
				(font
					(size 0.7 0.7)
					(thickness 0.15)
				)
				(justify right top)
			)
		)
		(fp_text user "Author: Antmicro"
			(at -0.939 3.399 0)
			(layer "F.Fab")
			(effects
				(font
					(size 0.7 0.7)
					(thickness 0.15)
				)
				(justify right top)
			)
		)
		(fp_text user "${REFERENCE}"
			(at -0.939 4.599 0)
			(layer "F.Fab")
			(effects
				(font
					(size 0.7 0.7)
					(thickness 0.15)
				)
				(justify right top)
			)
		)
		(pad "1" smd roundrect
			(at -0.48 0 180)
			(size 0.59 0.64)
			(layers "F.Cu" "F.Mask" "F.Paste")
			(roundrect_rratio 0.25)
			(net 1 "GND")
			(pintype "passive")
		)
		(pad "2" smd roundrect
			(at 0.48 0 180)
			(size 0.59 0.64)
			(layers "F.Cu" "F.Mask" "F.Paste")
			(roundrect_rratio 0.25)
			(net 2 "+3V3")
			(pintype "passive")
		)
	)
	(footprint "antmicro-footprints:C_0402_1005Metric"
		(layer "F.Cu")
		(at 211 102.355)
		(descr "Capacitor SMD 0402")
		(tags "capacitor SMD 0402")
		(property "Reference" "C200"
			(at -3.79 0.33 0)
			(layer "F.SilkS")
			(effects
				(font
					(size 0.7 0.7)
					(thickness 0.15)
				)
				(justify left bottom)
			)
		)
		(property "Value" "C_100n_0402"
			(at -1.022927 2.155213 0)
			(layer "F.Fab")
			(effects
				(font
					(size 0.7 0.7)
					(thickness 0.15)
				)
				(justify left bottom)
			)
		)
		(property "Datasheet" "https://www.murata.com/products/productdetail?partno=GRM155R61H104KE14%23"
			(at 0 0 0)
			(layer "F.Fab")
			(hide yes)
			(effects
				(font
					(size 1.27 1.27)
					(thickness 0.15)
				)
			)
		)
		(property "Description" "SMD Multilayer Ceramic Capacitor, 0.1 µF, 50 V, 0402 [1005 Metric], ± 10%, X5R, GRM Series"
			(at 0 0 0)
			(layer "F.Fab")
			(hide yes)
			(effects
				(font
					(size 1.27 1.27)
					(thickness 0.15)
				)
			)
		)
		(property "Manufacturer" "Murata"
			(at 0 0 0)
			(unlocked yes)
			(layer "F.Fab")
			(hide yes)
			(effects
				(font
					(size 1 1)
					(thickness 0.15)
				)
			)
		)
		(property "MPN" "GRM155R61H104KE14D"
			(at 0 0 0)
			(unlocked yes)
			(layer "F.Fab")
			(hide yes)
			(effects
				(font
					(size 1 1)
					(thickness 0.15)
				)
			)
		)
		(property "Val" "100n"
			(at 0 0 0)
			(unlocked yes)
			(layer "F.Fab")
			(hide yes)
			(effects
				(font
					(size 1 1)
					(thickness 0.15)
				)
			)
		)
		(property "License" "Apache-2.0"
			(at 0 0 0)
			(unlocked yes)
			(layer "F.Fab")
			(hide yes)
			(effects
				(font
					(size 1 1)
					(thickness 0.15)
				)
			)
		)
		(property "Author" "Antmicro"
			(at 0 0 0)
			(unlocked yes)
			(layer "F.Fab")
			(hide yes)
			(effects
				(font
					(size 1 1)
					(thickness 0.15)
				)
			)
		)
		(property "Voltage" "50V"
			(at 0 0 0)
			(unlocked yes)
			(layer "F.Fab")
			(hide yes)
			(effects
				(font
					(size 1 1)
					(thickness 0.15)
				)
			)
		)
		(property "Dielectric" "X5R"
			(at 0 0 0)
			(unlocked yes)
			(layer "F.Fab")
			(hide yes)
			(effects
				(font
					(size 1 1)
					(thickness 0.15)
				)
			)
		)
		(sheetname "/Recovery USB/")
		(sheetfile "recovery_usb.kicad_sch")
		(attr smd)
		(fp_rect
			(start -0.925 -0.47)
			(end 0.925 0.47)
			(stroke
				(width 0.05)
				(type default)
			)
			(fill no)
			(layer "F.CrtYd")
		)
		(fp_line
			(start -0.494 -0.25)
			(end 0.504 -0.25)
			(stroke
				(width 0.15)
				(type solid)
			)
			(layer "F.Fab")
		)
		(fp_line
			(start -0.494 0.248)
			(end -0.494 -0.25)
			(stroke
				(width 0.15)
				(type solid)
			)
			(layer "F.Fab")
		)
		(fp_line
			(start 0.504 -0.25)
			(end 0.504 0.248)
			(stroke
				(width 0.15)
				(type solid)
			)
			(layer "F.Fab")
		)
		(fp_line
			(start 0.504 0.248)
			(end -0.494 0.248)
			(stroke
				(width 0.15)
				(type solid)
			)
			(layer "F.Fab")
		)
		(fp_text user "License: Apache-2.0"
			(at -0.939 5.799 0)
			(layer "F.Fab")
			(effects
				(font
					(size 0.7 0.7)
					(thickness 0.15)
				)
				(justify left bottom)
			)
		)
		(fp_text user "Author: Antmicro"
			(at -0.939 3.399 0)
			(layer "F.Fab")
			(effects
				(font
					(size 0.7 0.7)
					(thickness 0.15)
				)
				(justify left bottom)
			)
		)
		(fp_text user "${REFERENCE}"
			(at -0.939 4.599 0)
			(layer "F.Fab")
			(effects
				(font
					(size 0.7 0.7)
					(thickness 0.15)
				)
				(justify left bottom)
			)
		)
		(pad "1" smd roundrect
			(at -0.48 0)
			(size 0.59 0.64)
			(layers "F.Cu" "F.Mask" "F.Paste")
			(roundrect_rratio 0.25)
			(net 618 "/Recovery USB/USBSS0.TX+")
			(pintype "passive")
		)
		(pad "2" smd roundrect
			(at 0.48 0)
			(size 0.59 0.64)
			(layers "F.Cu" "F.Mask" "F.Paste")
			(roundrect_rratio 0.25)
			(net 1129 "/Recovery USB/USBSS_TX_N")
			(pintype "passive")
		)
	)
	(footprint "antmicro-footprints:C_0402_1005Metric"
		(layer "F.Cu")
		(at 211 104.3)
		(descr "Capacitor SMD 0402")
		(tags "capacitor SMD 0402")
		(property "Reference" "C201"
			(at -3.77 0.4 0)
			(layer "F.SilkS")
			(effects
				(font
					(size 0.7 0.7)
					(thickness 0.15)
				)
				(justify left bottom)
			)
		)
		(property "Value" "C_100n_0402"
			(at -1.022927 2.155213 0)
			(layer "F.Fab")
			(effects
				(font
					(size 0.7 0.7)
					(thickness 0.15)
				)
				(justify left bottom)
			)
		)
		(property "Datasheet" "https://www.murata.com/products/productdetail?partno=GRM155R61H104KE14%23"
			(at 0 0 0)
			(layer "F.Fab")
			(hide yes)
			(effects
				(font
					(size 1.27 1.27)
					(thickness 0.15)
				)
			)
		)
		(property "Description" "SMD Multilayer Ceramic Capacitor, 0.1 µF, 50 V, 0402 [1005 Metric], ± 10%, X5R, GRM Series"
			(at 0 0 0)
			(layer "F.Fab")
			(hide yes)
			(effects
				(font
					(size 1.27 1.27)
					(thickness 0.15)
				)
			)
		)
		(property "Manufacturer" "Murata"
			(at 0 0 0)
			(unlocked yes)
			(layer "F.Fab")
			(hide yes)
			(effects
				(font
					(size 1 1)
					(thickness 0.15)
				)
			)
		)
		(property "MPN" "GRM155R61H104KE14D"
			(at 0 0 0)
			(unlocked yes)
			(layer "F.Fab")
			(hide yes)
			(effects
				(font
					(size 1 1)
					(thickness 0.15)
				)
			)
		)
		(property "Val" "100n"
			(at 0 0 0)
			(unlocked yes)
			(layer "F.Fab")
			(hide yes)
			(effects
				(font
					(size 1 1)
					(thickness 0.15)
				)
			)
		)
		(property "License" "Apache-2.0"
			(at 0 0 0)
			(unlocked yes)
			(layer "F.Fab")
			(hide yes)
			(effects
				(font
					(size 1 1)
					(thickness 0.15)
				)
			)
		)
		(property "Author" "Antmicro"
			(at 0 0 0)
			(unlocked yes)
			(layer "F.Fab")
			(hide yes)
			(effects
				(font
					(size 1 1)
					(thickness 0.15)
				)
			)
		)
		(property "Voltage" "50V"
			(at 0 0 0)
			(unlocked yes)
			(layer "F.Fab")
			(hide yes)
			(effects
				(font
					(size 1 1)
					(thickness 0.15)
				)
			)
		)
		(property "Dielectric" "X5R"
			(at 0 0 0)
			(unlocked yes)
			(layer "F.Fab")
			(hide yes)
			(effects
				(font
					(size 1 1)
					(thickness 0.15)
				)
			)
		)
		(sheetname "/Recovery USB/")
		(sheetfile "recovery_usb.kicad_sch")
		(attr smd)
		(fp_rect
			(start -0.925 -0.47)
			(end 0.925 0.47)
			(stroke
				(width 0.05)
				(type default)
			)
			(fill no)
			(layer "F.CrtYd")
		)
		(fp_line
			(start -0.494 -0.25)
			(end 0.504 -0.25)
			(stroke
				(width 0.15)
				(type solid)
			)
			(layer "F.Fab")
		)
		(fp_line
			(start -0.494 0.248)
			(end -0.494 -0.25)
			(stroke
				(width 0.15)
				(type solid)
			)
			(layer "F.Fab")
		)
		(fp_line
			(start 0.504 -0.25)
			(end 0.504 0.248)
			(stroke
				(width 0.15)
				(type solid)
			)
			(layer "F.Fab")
		)
		(fp_line
			(start 0.504 0.248)
			(end -0.494 0.248)
			(stroke
				(width 0.15)
				(type solid)
			)
			(layer "F.Fab")
		)
		(fp_text user "License: Apache-2.0"
			(at -0.939 5.799 0)
			(layer "F.Fab")
			(effects
				(font
					(size 0.7 0.7)
					(thickness 0.15)
				)
				(justify left bottom)
			)
		)
		(fp_text user "${REFERENCE}"
			(at -0.939 4.599 0)
			(layer "F.Fab")
			(effects
				(font
					(size 0.7 0.7)
					(thickness 0.15)
				)
				(justify left bottom)
			)
		)
		(fp_text user "Author: Antmicro"
			(at -0.939 3.399 0)
			(layer "F.Fab")
			(effects
				(font
					(size 0.7 0.7)
					(thickness 0.15)
				)
				(justify left bottom)
			)
		)
		(pad "1" smd roundrect
			(at -0.48 0)
			(size 0.59 0.64)
			(layers "F.Cu" "F.Mask" "F.Paste")
			(roundrect_rratio 0.25)
			(net 622 "/Recovery USB/USBSS0.RX-")
			(pintype "passive")
		)
		(pad "2" smd roundrect
			(at 0.48 0)
			(size 0.59 0.64)
			(layers "F.Cu" "F.Mask" "F.Paste")
			(roundrect_rratio 0.25)
			(net 1130 "/Recovery USB/USBSS_RX_P")
			(pintype "passive")
		)
	)
	(footprint "antmicro-footprints:C_0402_1005Metric"
		(layer "F.Cu")
		(at 198.75 73.5)
		(descr "Capacitor SMD 0402")
		(tags "capacitor SMD 0402")
		(property "Reference" "C147"
			(at -1.65 -0.74 0)
			(layer "F.SilkS")
			(effects
				(font
					(size 0.7 0.7)
					(thickness 0.15)
				)
				(justify left bottom)
			)
		)
		(property "Value" "C_10u_0402"
			(at -1.022927 2.155213 0)
			(layer "F.Fab")
			(effects
				(font
					(size 0.7 0.7)
					(thickness 0.15)
				)
				(justify left bottom)
			)
		)
		(property "Datasheet" "https://www.yageo.com/en/Chart/Download/pdf/CC0402MRX5R5BB106"
			(at 0 0 0)
			(layer "F.Fab")
			(hide yes)
			(effects
				(font
					(size 1.27 1.27)
					(thickness 0.15)
				)
			)
		)
		(property "Description" "SMD Multilayer Ceramic Capacitor, 10 µF, 6.3 V, 0402 [1005 Metric], ± 20%, X5R, CC Series"
			(at 0 0 0)
			(layer "F.Fab")
			(hide yes)
			(effects
				(font
					(size 1.27 1.27)
					(thickness 0.15)
				)
			)
		)
		(property "MPN" "CC0402MRX5R5BB106"
			(at 0 0 0)
			(unlocked yes)
			(layer "F.Fab")
			(hide yes)
			(effects
				(font
					(size 1 1)
					(thickness 0.15)
				)
			)
		)
		(property "Manufacturer" "YAGEO"
			(at 0 0 0)
			(unlocked yes)
			(layer "F.Fab")
			(hide yes)
			(effects
				(font
					(size 1 1)
					(thickness 0.15)
				)
			)
		)
		(property "License" "Apache-2.0"
			(at 0 0 0)
			(unlocked yes)
			(layer "F.Fab")
			(hide yes)
			(effects
				(font
					(size 1 1)
					(thickness 0.15)
				)
			)
		)
		(property "Author" "Antmicro"
			(at 0 0 0)
			(unlocked yes)
			(layer "F.Fab")
			(hide yes)
			(effects
				(font
					(size 1 1)
					(thickness 0.15)
				)
			)
		)
		(property "Val" "10u"
			(at 0 0 0)
			(unlocked yes)
			(layer "F.Fab")
			(hide yes)
			(effects
				(font
					(size 1 1)
					(thickness 0.15)
				)
			)
		)
		(property "Voltage" ""
			(at 0 0 0)
			(unlocked yes)
			(layer "F.Fab")
			(hide yes)
			(effects
				(font
					(size 1 1)
					(thickness 0.15)
				)
			)
		)
		(property "Dielectric" ""
			(at 0 0 0)
			(unlocked yes)
			(layer "F.Fab")
			(hide yes)
			(effects
				(font
					(size 1 1)
					(thickness 0.15)
				)
			)
		)
		(sheetname "/USB Debug, PD/")
		(sheetfile "usb_debug_pd.kicad_sch")
		(attr smd)
		(fp_poly
			(pts
				(xy -0.925 -0.47) (xy -0.925 0.47) (xy 0.925 0.47) (xy 0.925 -0.47)
			)
			(stroke
				(width 0.05)
				(type default)
			)
			(fill no)
			(layer "F.CrtYd")
		)
		(fp_line
			(start -0.494 -0.25)
			(end 0.504 -0.25)
			(stroke
				(width 0.15)
				(type solid)
			)
			(layer "F.Fab")
		)
		(fp_line
			(start -0.494 0.248)
			(end -0.494 -0.25)
			(stroke
				(width 0.15)
				(type solid)
			)
			(layer "F.Fab")
		)
		(fp_line
			(start 0.504 -0.25)
			(end 0.504 0.248)
			(stroke
				(width 0.15)
				(type solid)
			)
			(layer "F.Fab")
		)
		(fp_line
			(start 0.504 0.248)
			(end -0.494 0.248)
			(stroke
				(width 0.15)
				(type solid)
			)
			(layer "F.Fab")
		)
		(fp_text user "Author: Antmicro"
			(at -0.939 3.399 0)
			(layer "F.Fab")
			(effects
				(font
					(size 0.7 0.7)
					(thickness 0.15)
				)
				(justify left bottom)
			)
		)
		(fp_text user "${REFERENCE}"
			(at -0.939 4.599 0)
			(layer "F.Fab")
			(effects
				(font
					(size 0.7 0.7)
					(thickness 0.15)
				)
				(justify left bottom)
			)
		)
		(fp_text user "License: Apache-2.0"
			(at -0.939 5.799 0)
			(layer "F.Fab")
			(effects
				(font
					(size 0.7 0.7)
					(thickness 0.15)
				)
				(justify left bottom)
			)
		)
		(pad "1" smd roundrect
			(at -0.48 0)
			(size 0.59 0.64)
			(layers "F.Cu" "F.Mask" "F.Paste")
			(roundrect_rratio 0.25)
			(net 1 "GND")
			(pintype "passive")
		)
		(pad "2" smd roundrect
			(at 0.48 0)
			(size 0.59 0.64)
			(layers "F.Cu" "F.Mask" "F.Paste")
			(roundrect_rratio 0.25)
			(net 5 "+5V")
			(pintype "passive")
		)
	)
	(footprint "antmicro-footprints:R_0402_1005Metric"
		(layer "F.Cu")
		(at 140.7 111.72 -90)
		(descr "Resistor SMD 0402")
		(tags "resistor SMD 0402")
		(property "Reference" "R405"
			(at 0.78 0.4 90)
			(layer "F.SilkS")
			(effects
				(font
					(size 0.7 0.7)
					(thickness 0.15)
				)
				(justify right top)
			)
		)
		(property "Value" "R_0R_0402"
			(at -1.011843 1.772047 90)
			(layer "F.Fab")
			(effects
				(font
					(size 0.7 0.7)
					(thickness 0.15)
				)
				(justify right top)
			)
		)
		(property "Datasheet" "https://industrial.panasonic.com/cdbs/www-data/pdf/RDA0000/AOA0000C301.pdf"
			(at 0 0 90)
			(layer "F.Fab")
			(hide yes)
			(effects
				(font
					(size 1.27 1.27)
					(thickness 0.15)
				)
			)
		)
		(property "Description" "SMD Chip Resistor, Jumper, 0 ohm, 100 mW, 0402 [1005 Metric], Thick Film, General Purpose"
			(at 0 0 90)
			(layer "F.Fab")
			(hide yes)
			(effects
				(font
					(size 1.27 1.27)
					(thickness 0.15)
				)
			)
		)
		(property "MPN" "ERJ2GE0R00X"
			(at 0 0 270)
			(unlocked yes)
			(layer "F.Fab")
			(hide yes)
			(effects
				(font
					(size 1 1)
					(thickness 0.15)
				)
			)
		)
		(property "Manufacturer" "Panasonic"
			(at 0 0 270)
			(unlocked yes)
			(layer "F.Fab")
			(hide yes)
			(effects
				(font
					(size 1 1)
					(thickness 0.15)
				)
			)
		)
		(property "License" "Apache-2.0"
			(at 0 0 270)
			(unlocked yes)
			(layer "F.Fab")
			(hide yes)
			(effects
				(font
					(size 1 1)
					(thickness 0.15)
				)
			)
		)
		(property "Author" "Antmicro"
			(at 0 0 270)
			(unlocked yes)
			(layer "F.Fab")
			(hide yes)
			(effects
				(font
					(size 1 1)
					(thickness 0.15)
				)
			)
		)
		(property "Val" "0R"
			(at 0 0 270)
			(unlocked yes)
			(layer "F.Fab")
			(hide yes)
			(effects
				(font
					(size 1 1)
					(thickness 0.15)
				)
			)
		)
		(property "Tolerance" "~"
			(at 0 0 270)
			(unlocked yes)
			(layer "F.Fab")
			(hide yes)
			(effects
				(font
					(size 1 1)
					(thickness 0.15)
				)
			)
		)
		(property "Current" "1A"
			(at 0 0 270)
			(unlocked yes)
			(layer "F.Fab")
			(hide yes)
			(effects
				(font
					(size 1 1)
					(thickness 0.15)
				)
			)
		)
		(sheetname "/Peripherals/")
		(sheetfile "peripherals.kicad_sch")
		(attr smd)
		(fp_rect
			(start -0.925 -0.47)
			(end 0.925 0.47)
			(stroke
				(width 0.05)
				(type default)
			)
			(fill no)
			(layer "F.CrtYd")
		)
		(fp_rect
			(start -0.5 -0.25)
			(end 0.5 0.25)
			(stroke
				(width 0.15)
				(type solid)
			)
			(fill no)
			(layer "F.Fab")
		)
		(fp_text user "License: Apache-2.0"
			(at -0.95 5.169 90)
			(layer "F.Fab")
			(effects
				(font
					(size 0.7 0.7)
					(thickness 0.15)
				)
				(justify right top)
			)
		)
		(fp_text user "Author: Antmicro"
			(at -0.95 4.169 90)
			(layer "F.Fab")
			(effects
				(font
					(size 0.7 0.7)
					(thickness 0.15)
				)
				(justify right top)
			)
		)
		(fp_text user "${REFERENCE}"
			(at -0.95 3.168 90)
			(layer "F.Fab")
			(effects
				(font
					(size 0.7 0.7)
					(thickness 0.15)
				)
				(justify right top)
			)
		)
		(pad "1" smd roundrect
			(at -0.48 0 270)
			(size 0.59 0.64)
			(layers "F.Cu" "F.Mask" "F.Paste")
			(roundrect_rratio 0.25)
			(net 1318 "/Peripherals/GPIOEX_P0_6")
			(pintype "passive")
		)
		(pad "2" smd roundrect
			(at 0.48 0 270)
			(size 0.59 0.64)
			(layers "F.Cu" "F.Mask" "F.Paste")
			(roundrect_rratio 0.25)
			(net 90 "/Peripherals/I2C_CONN_PEN")
			(pintype "passive")
		)
	)
	(footprint "antmicro-footprints:C_0402_1005Metric"
		(layer "F.Cu")
		(at 153.5 107.5 180)
		(descr "Capacitor SMD 0402")
		(tags "capacitor SMD 0402")
		(property "Reference" "C216"
			(at -3.8 0.4 0)
			(layer "F.SilkS")
			(effects
				(font
					(size 0.7 0.7)
					(thickness 0.15)
				)
				(justify right top)
			)
		)
		(property "Value" "C_100n_0402"
			(at -1.022927 2.155213 0)
			(layer "F.Fab")
			(effects
				(font
					(size 0.7 0.7)
					(thickness 0.15)
				)
				(justify right top)
			)
		)
		(property "Datasheet" "https://www.murata.com/products/productdetail?partno=GRM155R61H104KE14%23"
			(at 0 0 0)
			(layer "F.Fab")
			(hide yes)
			(effects
				(font
					(size 1.27 1.27)
					(thickness 0.15)
				)
			)
		)
		(property "Description" "SMD Multilayer Ceramic Capacitor, 0.1 µF, 50 V, 0402 [1005 Metric], ± 10%, X5R, GRM Series"
			(at 0 0 0)
			(layer "F.Fab")
			(hide yes)
			(effects
				(font
					(size 1.27 1.27)
					(thickness 0.15)
				)
			)
		)
		(property "Manufacturer" "Murata"
			(at 0 0 180)
			(unlocked yes)
			(layer "F.Fab")
			(hide yes)
			(effects
				(font
					(size 1 1)
					(thickness 0.15)
				)
			)
		)
		(property "MPN" "GRM155R61H104KE14D"
			(at 0 0 180)
			(unlocked yes)
			(layer "F.Fab")
			(hide yes)
			(effects
				(font
					(size 1 1)
					(thickness 0.15)
				)
			)
		)
		(property "Val" "100n"
			(at 0 0 180)
			(unlocked yes)
			(layer "F.Fab")
			(hide yes)
			(effects
				(font
					(size 1 1)
					(thickness 0.15)
				)
			)
		)
		(property "License" "Apache-2.0"
			(at 0 0 180)
			(unlocked yes)
			(layer "F.Fab")
			(hide yes)
			(effects
				(font
					(size 1 1)
					(thickness 0.15)
				)
			)
		)
		(property "Author" "Antmicro"
			(at 0 0 180)
			(unlocked yes)
			(layer "F.Fab")
			(hide yes)
			(effects
				(font
					(size 1 1)
					(thickness 0.15)
				)
			)
		)
		(property "Voltage" "50V"
			(at 0 0 180)
			(unlocked yes)
			(layer "F.Fab")
			(hide yes)
			(effects
				(font
					(size 1 1)
					(thickness 0.15)
				)
			)
		)
		(property "Dielectric" "X5R"
			(at 0 0 180)
			(unlocked yes)
			(layer "F.Fab")
			(hide yes)
			(effects
				(font
					(size 1 1)
					(thickness 0.15)
				)
			)
		)
		(sheetname "/SoM_IO/")
		(sheetfile "som_io.kicad_sch")
		(attr smd)
		(fp_poly
			(pts
				(xy -0.925 -0.47) (xy 0.925 -0.47) (xy 0.925 0.47) (xy -0.925 0.47)
			)
			(stroke
				(width 0.05)
				(type default)
			)
			(fill no)
			(layer "F.CrtYd")
		)
		(fp_line
			(start 0.504 0.248)
			(end -0.494 0.248)
			(stroke
				(width 0.15)
				(type solid)
			)
			(layer "F.Fab")
		)
		(fp_line
			(start 0.504 -0.25)
			(end 0.504 0.248)
			(stroke
				(width 0.15)
				(type solid)
			)
			(layer "F.Fab")
		)
		(fp_line
			(start -0.494 0.248)
			(end -0.494 -0.25)
			(stroke
				(width 0.15)
				(type solid)
			)
			(layer "F.Fab")
		)
		(fp_line
			(start -0.494 -0.25)
			(end 0.504 -0.25)
			(stroke
				(width 0.15)
				(type solid)
			)
			(layer "F.Fab")
		)
		(fp_text user "License: Apache-2.0"
			(at -0.939 5.799 0)
			(layer "F.Fab")
			(effects
				(font
					(size 0.7 0.7)
					(thickness 0.15)
				)
				(justify right top)
			)
		)
		(fp_text user "Author: Antmicro"
			(at -0.939 3.399 0)
			(layer "F.Fab")
			(effects
				(font
					(size 0.7 0.7)
					(thickness 0.15)
				)
				(justify right top)
			)
		)
		(fp_text user "${REFERENCE}"
			(at -0.939 4.599 0)
			(layer "F.Fab")
			(effects
				(font
					(size 0.7 0.7)
					(thickness 0.15)
				)
				(justify right top)
			)
		)
		(pad "1" smd roundrect
			(at -0.48 0 180)
			(size 0.59 0.64)
			(layers "F.Cu" "F.Mask" "F.Paste")
			(roundrect_rratio 0.25)
			(net 1 "GND")
			(pintype "passive")
		)
		(pad "2" smd roundrect
			(at 0.48 0 180)
			(size 0.59 0.64)
			(layers "F.Cu" "F.Mask" "F.Paste")
			(roundrect_rratio 0.25)
			(net 11 "+1V8")
			(pintype "passive")
		)
	)
	(footprint "antmicro-footprints:R_0402_1005Metric"
		(layer "F.Cu")
		(at 145.424391 125.91 90)
		(descr "Resistor SMD 0402")
		(tags "resistor SMD 0402")
		(property "Reference" "R317"
			(at 1.71 0.408 90)
			(layer "F.SilkS")
			(effects
				(font
					(size 0.7 0.7)
					(thickness 0.15)
				)
				(justify left bottom)
			)
		)
		(property "Value" "R_30k_0402"
			(at -1.011843 1.772047 90)
			(layer "F.Fab")
			(effects
				(font
					(size 0.7 0.7)
					(thickness 0.15)
				)
				(justify left bottom)
			)
		)
		(property "Datasheet" "https://www.bourns.com/docs/product-datasheets/cr.pdf"
			(at 0 0 90)
			(layer "F.Fab")
			(hide yes)
			(effects
				(font
					(size 1.27 1.27)
					(thickness 0.15)
				)
			)
		)
		(property "Description" "SMD Chip Resistor, 30 kohm, ± 1%, 63 mW, 0402 [1005 Metric], Thick Film, General Purpose"
			(at 0 0 90)
			(layer "F.Fab")
			(hide yes)
			(effects
				(font
					(size 1.27 1.27)
					(thickness 0.15)
				)
			)
		)
		(property "MPN" "CR0402-FX-3002GLF"
			(at 0 0 90)
			(unlocked yes)
			(layer "F.Fab")
			(hide yes)
			(effects
				(font
					(size 1 1)
					(thickness 0.15)
				)
			)
		)
		(property "Manufacturer" "Bourns"
			(at 0 0 90)
			(unlocked yes)
			(layer "F.Fab")
			(hide yes)
			(effects
				(font
					(size 1 1)
					(thickness 0.15)
				)
			)
		)
		(property "License" "Apache-2.0"
			(at 0 0 90)
			(unlocked yes)
			(layer "F.Fab")
			(hide yes)
			(effects
				(font
					(size 1 1)
					(thickness 0.15)
				)
			)
		)
		(property "Author" "Antmicro"
			(at 0 0 90)
			(unlocked yes)
			(layer "F.Fab")
			(hide yes)
			(effects
				(font
					(size 1 1)
					(thickness 0.15)
				)
			)
		)
		(property "Val" "30k"
			(at 0 0 90)
			(unlocked yes)
			(layer "F.Fab")
			(hide yes)
			(effects
				(font
					(size 1 1)
					(thickness 0.15)
				)
			)
		)
		(property "Tolerance" "1%"
			(at 0 0 90)
			(unlocked yes)
			(layer "F.Fab")
			(hide yes)
			(effects
				(font
					(size 1 1)
					(thickness 0.15)
				)
			)
		)
		(component_classes
			(class "DCDC_1V8")
		)
		(sheetname "/DCDC/")
		(sheetfile "dcdc.kicad_sch")
		(attr smd)
		(fp_rect
			(start -0.925 -0.47)
			(end 0.925 0.47)
			(stroke
				(width 0.05)
				(type default)
			)
			(fill no)
			(layer "F.CrtYd")
		)
		(fp_rect
			(start -0.5 -0.25)
			(end 0.5 0.25)
			(stroke
				(width 0.15)
				(type solid)
			)
			(fill no)
			(layer "F.Fab")
		)
		(fp_text user "License: Apache-2.0"
			(at -0.95 5.169 90)
			(layer "F.Fab")
			(effects
				(font
					(size 0.7 0.7)
					(thickness 0.15)
				)
				(justify left bottom)
			)
		)
		(fp_text user "Author: Antmicro"
			(at -0.95 4.169 90)
			(layer "F.Fab")
			(effects
				(font
					(size 0.7 0.7)
					(thickness 0.15)
				)
				(justify left bottom)
			)
		)
		(fp_text user "${REFERENCE}"
			(at -0.95 3.168 90)
			(layer "F.Fab")
			(effects
				(font
					(size 0.7 0.7)
					(thickness 0.15)
				)
				(justify left bottom)
			)
		)
		(pad "1" smd roundrect
			(at -0.48 0 90)
			(size 0.59 0.64)
			(layers "F.Cu" "F.Mask" "F.Paste")
			(roundrect_rratio 0.25)
			(net 1222 "/DCDC/1V8_FB")
			(pintype "passive")
		)
		(pad "2" smd roundrect
			(at 0.48 0 90)
			(size 0.59 0.64)
			(layers "F.Cu" "F.Mask" "F.Paste")
			(roundrect_rratio 0.25)
			(net 17 "/DCDC/1V8_OUT")
			(pintype "passive")
		)
	)
	(footprint "antmicro-footprints:R_0402_1005Metric"
		(layer "F.Cu")
		(at 156.6 119.4 180)
		(descr "Resistor SMD 0402")
		(tags "resistor SMD 0402")
		(property "Reference" "R358"
			(at -3.6 0.4 0)
			(layer "F.SilkS")
			(effects
				(font
					(size 0.7 0.7)
					(thickness 0.15)
				)
				(justify right top)
			)
		)
		(property "Value" "R_2k2_0402"
			(at -1.011843 1.772047 0)
			(layer "F.Fab")
			(effects
				(font
					(size 0.7 0.7)
					(thickness 0.15)
				)
				(justify right top)
			)
		)
		(property "Datasheet" "https://www.bourns.com/docs/product-datasheets/cr.pdf"
			(at 0 0 0)
			(layer "F.Fab")
			(hide yes)
			(effects
				(font
					(size 1.27 1.27)
					(thickness 0.15)
				)
			)
		)
		(property "Description" "SMD Chip Resistor, 2.2 kohm, ± 1%, 62.5 mW, 0402 [1005 Metric], Thick Film, General Purpose"
			(at 0 0 0)
			(layer "F.Fab")
			(hide yes)
			(effects
				(font
					(size 1.27 1.27)
					(thickness 0.15)
				)
			)
		)
		(property "MPN" "CR0402-FX-2201GLF"
			(at 0 0 180)
			(unlocked yes)
			(layer "F.Fab")
			(hide yes)
			(effects
				(font
					(size 1 1)
					(thickness 0.15)
				)
			)
		)
		(property "Manufacturer" "Bourns"
			(at 0 0 180)
			(unlocked yes)
			(layer "F.Fab")
			(hide yes)
			(effects
				(font
					(size 1 1)
					(thickness 0.15)
				)
			)
		)
		(property "License" "Apache-2.0"
			(at 0 0 180)
			(unlocked yes)
			(layer "F.Fab")
			(hide yes)
			(effects
				(font
					(size 1 1)
					(thickness 0.15)
				)
			)
		)
		(property "Author" "Antmicro"
			(at 0 0 180)
			(unlocked yes)
			(layer "F.Fab")
			(hide yes)
			(effects
				(font
					(size 1 1)
					(thickness 0.15)
				)
			)
		)
		(property "Val" "2k2"
			(at 0 0 180)
			(unlocked yes)
			(layer "F.Fab")
			(hide yes)
			(effects
				(font
					(size 1 1)
					(thickness 0.15)
				)
			)
		)
		(property "Tolerance" "1%"
			(at 0 0 180)
			(unlocked yes)
			(layer "F.Fab")
			(hide yes)
			(effects
				(font
					(size 1 1)
					(thickness 0.15)
				)
			)
		)
		(sheetname "/SoM_IO/")
		(sheetfile "som_io.kicad_sch")
		(attr smd exclude_from_pos_files exclude_from_bom dnp)
		(fp_rect
			(start -0.925 -0.47)
			(end 0.925 0.47)
			(stroke
				(width 0.05)
				(type default)
			)
			(fill no)
			(layer "F.CrtYd")
		)
		(fp_rect
			(start -0.5 -0.25)
			(end 0.5 0.25)
			(stroke
				(width 0.15)
				(type solid)
			)
			(fill no)
			(layer "F.Fab")
		)
		(fp_text user "License: Apache-2.0"
			(at -0.95 5.169 0)
			(layer "F.Fab")
			(effects
				(font
					(size 0.7 0.7)
					(thickness 0.15)
				)
				(justify right top)
			)
		)
		(fp_text user "${REFERENCE}"
			(at -0.95 3.168 0)
			(layer "F.Fab")
			(effects
				(font
					(size 0.7 0.7)
					(thickness 0.15)
				)
				(justify right top)
			)
		)
		(fp_text user "Author: Antmicro"
			(at -0.95 4.169 0)
			(layer "F.Fab")
			(effects
				(font
					(size 0.7 0.7)
					(thickness 0.15)
				)
				(justify right top)
			)
		)
		(pad "1" smd roundrect
			(at -0.48 0 180)
			(size 0.59 0.64)
			(layers "F.Cu" "F.Mask" "F.Paste")
			(roundrect_rratio 0.25)
			(net 11 "+1V8")
			(pintype "passive")
		)
		(pad "2" smd roundrect
			(at 0.48 0 180)
			(size 0.59 0.64)
			(layers "F.Cu" "F.Mask" "F.Paste")
			(roundrect_rratio 0.25)
			(net 145 "/SoM_IO/I2C3_SDA_1V8")
			(pintype "passive")
		)
	)
	(footprint "antmicro-footprints:R_0402_1005Metric"
		(layer "F.Cu")
		(at 181.75 107.15 -90)
		(descr "Resistor SMD 0402")
		(tags "resistor SMD 0402")
		(property "Reference" "R42"
			(at -3.17 0.44 90)
			(layer "F.SilkS")
			(effects
				(font
					(size 0.7 0.7)
					(thickness 0.15)
				)
				(justify right top)
			)
		)
		(property "Value" "R_200k_0402"
			(at -1.011843 1.772047 90)
			(layer "F.Fab")
			(effects
				(font
					(size 0.7 0.7)
					(thickness 0.15)
				)
				(justify right top)
			)
		)
		(property "Datasheet" "https://www.bourns.com/docs/product-datasheets/cr.pdf"
			(at 0 0 90)
			(layer "F.Fab")
			(hide yes)
			(effects
				(font
					(size 1.27 1.27)
					(thickness 0.15)
				)
			)
		)
		(property "Description" "SMD Chip Resistor, 200 kohm, ± 1%, 62.5 mW, 0402 [1005 Metric], Thick Film, General Purpose"
			(at 0 0 90)
			(layer "F.Fab")
			(hide yes)
			(effects
				(font
					(size 1.27 1.27)
					(thickness 0.15)
				)
			)
		)
		(property "MPN" "CR0402-FX-2003GLF"
			(at 0 0 270)
			(unlocked yes)
			(layer "F.Fab")
			(hide yes)
			(effects
				(font
					(size 1 1)
					(thickness 0.15)
				)
			)
		)
		(property "Manufacturer" "Bourns"
			(at 0 0 270)
			(unlocked yes)
			(layer "F.Fab")
			(hide yes)
			(effects
				(font
					(size 1 1)
					(thickness 0.15)
				)
			)
		)
		(property "License" "Apache-2.0"
			(at 0 0 270)
			(unlocked yes)
			(layer "F.Fab")
			(hide yes)
			(effects
				(font
					(size 1 1)
					(thickness 0.15)
				)
			)
		)
		(property "Author" "Antmicro"
			(at 0 0 270)
			(unlocked yes)
			(layer "F.Fab")
			(hide yes)
			(effects
				(font
					(size 1 1)
					(thickness 0.15)
				)
			)
		)
		(property "Val" "200k"
			(at 0 0 270)
			(unlocked yes)
			(layer "F.Fab")
			(hide yes)
			(effects
				(font
					(size 1 1)
					(thickness 0.15)
				)
			)
		)
		(property "Tolerance" "1%"
			(at 0 0 270)
			(unlocked yes)
			(layer "F.Fab")
			(hide yes)
			(effects
				(font
					(size 1 1)
					(thickness 0.15)
				)
			)
		)
		(sheetname "/DCDC/")
		(sheetfile "dcdc.kicad_sch")
		(attr smd)
		(fp_rect
			(start -0.925 -0.47)
			(end 0.925 0.47)
			(stroke
				(width 0.05)
				(type default)
			)
			(fill no)
			(layer "F.CrtYd")
		)
		(fp_rect
			(start -0.5 -0.25)
			(end 0.5 0.25)
			(stroke
				(width 0.15)
				(type solid)
			)
			(fill no)
			(layer "F.Fab")
		)
		(fp_text user "${REFERENCE}"
			(at -0.95 3.168 90)
			(layer "F.Fab")
			(effects
				(font
					(size 0.7 0.7)
					(thickness 0.15)
				)
				(justify right top)
			)
		)
		(fp_text user "Author: Antmicro"
			(at -0.95 4.169 90)
			(layer "F.Fab")
			(effects
				(font
					(size 0.7 0.7)
					(thickness 0.15)
				)
				(justify right top)
			)
		)
		(fp_text user "License: Apache-2.0"
			(at -0.95 5.169 90)
			(layer "F.Fab")
			(effects
				(font
					(size 0.7 0.7)
					(thickness 0.15)
				)
				(justify right top)
			)
		)
		(pad "1" smd roundrect
			(at -0.48 0 270)
			(size 0.59 0.64)
			(layers "F.Cu" "F.Mask" "F.Paste")
			(roundrect_rratio 0.25)
			(net 1 "GND")
			(pintype "passive")
		)
		(pad "2" smd roundrect
			(at 0.48 0 270)
			(size 0.59 0.64)
			(layers "F.Cu" "F.Mask" "F.Paste")
			(roundrect_rratio 0.25)
			(net 1215 "/DCDC/5V_MODE2")
			(pintype "passive")
		)
	)
	(footprint "antmicro-footprints:R_0402_1005Metric"
		(layer "F.Cu")
		(at 162.694468 98.145 90)
		(descr "Resistor SMD 0402")
		(tags "resistor SMD 0402")
		(property "Reference" "R364"
			(at -0.955 -1.694468 90)
			(layer "F.SilkS")
			(effects
				(font
					(size 0.7 0.7)
					(thickness 0.15)
				)
				(justify left bottom)
			)
		)
		(property "Value" "R_27R_0402"
			(at -1.011843 1.772047 90)
			(layer "F.Fab")
			(effects
				(font
					(size 0.7 0.7)
					(thickness 0.15)
				)
				(justify left bottom)
			)
		)
		(property "Datasheet" "https://www.bourns.com/docs/product-datasheets/cr.pdf"
			(at 0 0 90)
			(layer "F.Fab")
			(hide yes)
			(effects
				(font
					(size 1.27 1.27)
					(thickness 0.15)
				)
			)
		)
		(property "Description" "SMD Chip Resistor, 27 ohm, ± 1%, 63 mW, 0402 [1005 Metric], Thick Film, General Purpose"
			(at 0 0 90)
			(layer "F.Fab")
			(hide yes)
			(effects
				(font
					(size 1.27 1.27)
					(thickness 0.15)
				)
			)
		)
		(property "Manufacturer" "Bourns"
			(at 0 0 90)
			(unlocked yes)
			(layer "F.Fab")
			(hide yes)
			(effects
				(font
					(size 1 1)
					(thickness 0.15)
				)
			)
		)
		(property "MPN" "CR0402-FX-27R0GLF"
			(at 0 0 90)
			(unlocked yes)
			(layer "F.Fab")
			(hide yes)
			(effects
				(font
					(size 1 1)
					(thickness 0.15)
				)
			)
		)
		(property "Val" "27R"
			(at 0 0 90)
			(unlocked yes)
			(layer "F.Fab")
			(hide yes)
			(effects
				(font
					(size 1 1)
					(thickness 0.15)
				)
			)
		)
		(property "License" "Apache-2.0"
			(at 0 0 90)
			(unlocked yes)
			(layer "F.Fab")
			(hide yes)
			(effects
				(font
					(size 1 1)
					(thickness 0.15)
				)
			)
		)
		(property "Author" "Antmicro"
			(at 0 0 90)
			(unlocked yes)
			(layer "F.Fab")
			(hide yes)
			(effects
				(font
					(size 1 1)
					(thickness 0.15)
				)
			)
		)
		(property "Tolerance" "1%"
			(at 0 0 90)
			(unlocked yes)
			(layer "F.Fab")
			(hide yes)
			(effects
				(font
					(size 1 1)
					(thickness 0.15)
				)
			)
		)
		(component_classes
			(class "DCDC_SOM")
		)
		(sheetname "/DCDC/")
		(sheetfile "dcdc.kicad_sch")
		(attr smd)
		(fp_rect
			(start -0.925 -0.47)
			(end 0.925 0.47)
			(stroke
				(width 0.05)
				(type default)
			)
			(fill no)
			(layer "F.CrtYd")
		)
		(fp_rect
			(start -0.5 -0.25)
			(end 0.5 0.25)
			(stroke
				(width 0.15)
				(type solid)
			)
			(fill no)
			(layer "F.Fab")
		)
		(fp_text user "${REFERENCE}"
			(at -0.95 3.168 90)
			(layer "F.Fab")
			(effects
				(font
					(size 0.7 0.7)
					(thickness 0.15)
				)
				(justify left bottom)
			)
		)
		(fp_text user "Author: Antmicro"
			(at -0.95 4.169 90)
			(layer "F.Fab")
			(effects
				(font
					(size 0.7 0.7)
					(thickness 0.15)
				)
				(justify left bottom)
			)
		)
		(fp_text user "License: Apache-2.0"
			(at -0.95 5.169 90)
			(layer "F.Fab")
			(effects
				(font
					(size 0.7 0.7)
					(thickness 0.15)
				)
				(justify left bottom)
			)
		)
		(pad "1" smd roundrect
			(at -0.48 0 90)
			(size 0.59 0.64)
			(layers "F.Cu" "F.Mask" "F.Paste")
			(roundrect_rratio 0.25)
			(net 1283 "Net-(U22-IN+)")
			(pintype "passive")
		)
		(pad "2" smd roundrect
			(at 0.48 0 90)
			(size 0.59 0.64)
			(layers "F.Cu" "F.Mask" "F.Paste")
			(roundrect_rratio 0.25)
			(net 903 "/DCDC/16V_OUT")
			(pintype "passive")
		)
	)
	(footprint "antmicro-footprints:R_0603_1608Metric"
		(layer "F.Cu")
		(at 147.944391 124.83 180)
		(descr "Resistor SMD 0603")
		(tags "resistor SMD 0603")
		(property "Reference" "R10"
			(at -3.355609 0.33 0)
			(layer "F.SilkS")
			(effects
				(font
					(size 0.7 0.7)
					(thickness 0.15)
				)
				(justify right top)
			)
		)
		(property "Value" "R_0R_22.4A_0603"
			(at 0 1.6 0)
			(layer "F.Fab")
			(effects
				(font
					(size 0.7 0.7)
					(thickness 0.15)
				)
				(justify right top)
			)
		)
		(property "Datasheet" "https://fscdn.rohm.com/en/products/databook/datasheet/passive/resistor/chip_resistor/pmr-jpw-e.pdf"
			(at 0 0 0)
			(layer "F.Fab")
			(hide yes)
			(effects
				(font
					(size 1.27 1.27)
					(thickness 0.15)
				)
			)
		)
		(property "Description" "SMD Chip Resistor"
			(at 0 0 0)
			(layer "F.Fab")
			(hide yes)
			(effects
				(font
					(size 1.27 1.27)
					(thickness 0.15)
				)
			)
		)
		(property "Manufacturer" "ROHM Semiconductor"
			(at 0 0 180)
			(unlocked yes)
			(layer "F.Fab")
			(hide yes)
			(effects
				(font
					(size 1 1)
					(thickness 0.15)
				)
			)
		)
		(property "MPN" "PMR03EZPJ000"
			(at 0 0 180)
			(unlocked yes)
			(layer "F.Fab")
			(hide yes)
			(effects
				(font
					(size 1 1)
					(thickness 0.15)
				)
			)
		)
		(property "Val" "0R"
			(at 0 0 180)
			(unlocked yes)
			(layer "F.Fab")
			(hide yes)
			(effects
				(font
					(size 1 1)
					(thickness 0.15)
				)
			)
		)
		(property "Author" "Antmicro"
			(at 0 0 180)
			(unlocked yes)
			(layer "F.Fab")
			(hide yes)
			(effects
				(font
					(size 1 1)
					(thickness 0.15)
				)
			)
		)
		(property "License" "Apache-2.0"
			(at 0 0 180)
			(unlocked yes)
			(layer "F.Fab")
			(hide yes)
			(effects
				(font
					(size 1 1)
					(thickness 0.15)
				)
			)
		)
		(property "Max. Curr." "22.4A"
			(at 0 0 180)
			(unlocked yes)
			(layer "F.Fab")
			(hide yes)
			(effects
				(font
					(size 1 1)
					(thickness 0.15)
				)
			)
		)
		(property "Tolerance" "template_tolerance"
			(at 0 0 180)
			(unlocked yes)
			(layer "F.Fab")
			(hide yes)
			(effects
				(font
					(size 1 1)
					(thickness 0.15)
				)
			)
		)
		(component_classes
			(class "DCDC_1V8")
		)
		(sheetname "/DCDC/")
		(sheetfile "dcdc.kicad_sch")
		(attr smd)
		(fp_line
			(start -0.15 0.4)
			(end 0.15 0.4)
			(stroke
				(width 0.15)
				(type solid)
			)
			(layer "F.SilkS")
		)
		(fp_line
			(start -0.15 -0.4)
			(end 0.15 -0.4)
			(stroke
				(width 0.15)
				(type solid)
			)
			(layer "F.SilkS")
		)
		(fp_rect
			(start -1.25 -0.65)
			(end 1.25 0.65)
			(stroke
				(width 0.05)
				(type solid)
			)
			(fill no)
			(layer "F.CrtYd")
		)
		(fp_rect
			(start -0.8 -0.4)
			(end 0.8 0.4)
			(stroke
				(width 0.15)
				(type solid)
			)
			(fill no)
			(layer "F.Fab")
		)
		(fp_text user "${REFERENCE}"
			(at -1.25 3.898 0)
			(layer "F.Fab")
			(effects
				(font
					(size 0.7 0.7)
					(thickness 0.15)
				)
				(justify right top)
			)
		)
		(fp_text user "License: Apache-2.0"
			(at -1.25 5.9 0)
			(layer "F.Fab")
			(effects
				(font
					(size 0.7 0.7)
					(thickness 0.15)
				)
				(justify right top)
			)
		)
		(fp_text user "Author: Antmicro"
			(at -1.25 4.9 0)
			(layer "F.Fab")
			(effects
				(font
					(size 0.7 0.7)
					(thickness 0.15)
				)
				(justify right top)
			)
		)
		(pad "1" smd roundrect
			(at -0.7 0 180)
			(size 0.8 1)
			(layers "F.Cu" "F.Mask" "F.Paste")
			(roundrect_rratio 0.2)
			(net 17 "/DCDC/1V8_OUT")
			(pintype "passive")
		)
		(pad "2" smd roundrect
			(at 0.7 0 180)
			(size 0.8 1)
			(layers "F.Cu" "F.Mask" "F.Paste")
			(roundrect_rratio 0.2)
			(net 11 "+1V8")
			(pintype "passive")
		)
	)
	(footprint "antmicro-footprints:C_0402_1005Metric"
		(layer "F.Cu")
		(at 195.25 57.25 90)
		(descr "Capacitor SMD 0402")
		(tags "capacitor SMD 0402")
		(property "Reference" "C39"
			(at -1.65 -0.55 90)
			(layer "F.SilkS")
			(effects
				(font
					(size 0.7 0.7)
					(thickness 0.15)
				)
				(justify left bottom)
			)
		)
		(property "Value" "C_100n_0402"
			(at -1.022927 2.155213 90)
			(layer "F.Fab")
			(effects
				(font
					(size 0.7 0.7)
					(thickness 0.15)
				)
				(justify left bottom)
			)
		)
		(property "Datasheet" "https://www.murata.com/products/productdetail?partno=GRM155R61H104KE14%23"
			(at 0 0 90)
			(layer "F.Fab")
			(hide yes)
			(effects
				(font
					(size 1.27 1.27)
					(thickness 0.15)
				)
			)
		)
		(property "Description" "SMD Multilayer Ceramic Capacitor, 0.1 µF, 50 V, 0402 [1005 Metric], ± 10%, X5R, GRM Series"
			(at 0 0 90)
			(layer "F.Fab")
			(hide yes)
			(effects
				(font
					(size 1.27 1.27)
					(thickness 0.15)
				)
			)
		)
		(property "Manufacturer" "Murata"
			(at 0 0 90)
			(unlocked yes)
			(layer "F.Fab")
			(hide yes)
			(effects
				(font
					(size 1 1)
					(thickness 0.15)
				)
			)
		)
		(property "MPN" "GRM155R61H104KE14D"
			(at 0 0 90)
			(unlocked yes)
			(layer "F.Fab")
			(hide yes)
			(effects
				(font
					(size 1 1)
					(thickness 0.15)
				)
			)
		)
		(property "Val" "100n"
			(at 0 0 90)
			(unlocked yes)
			(layer "F.Fab")
			(hide yes)
			(effects
				(font
					(size 1 1)
					(thickness 0.15)
				)
			)
		)
		(property "License" "Apache-2.0"
			(at 0 0 90)
			(unlocked yes)
			(layer "F.Fab")
			(hide yes)
			(effects
				(font
					(size 1 1)
					(thickness 0.15)
				)
			)
		)
		(property "Author" "Antmicro"
			(at 0 0 90)
			(unlocked yes)
			(layer "F.Fab")
			(hide yes)
			(effects
				(font
					(size 1 1)
					(thickness 0.15)
				)
			)
		)
		(property "Voltage" "50V"
			(at 0 0 90)
			(unlocked yes)
			(layer "F.Fab")
			(hide yes)
			(effects
				(font
					(size 1 1)
					(thickness 0.15)
				)
			)
		)
		(property "Dielectric" "X5R"
			(at 0 0 90)
			(unlocked yes)
			(layer "F.Fab")
			(hide yes)
			(effects
				(font
					(size 1 1)
					(thickness 0.15)
				)
			)
		)
		(sheetname "/SoM_Power/")
		(sheetfile "som_power.kicad_sch")
		(attr smd)
		(fp_poly
			(pts
				(xy -0.925 -0.47) (xy 0.925 -0.47) (xy 0.925 0.47) (xy -0.925 0.47)
			)
			(stroke
				(width 0.05)
				(type default)
			)
			(fill no)
			(layer "F.CrtYd")
		)
		(fp_line
			(start 0.504 -0.25)
			(end 0.504 0.248)
			(stroke
				(width 0.15)
				(type solid)
			)
			(layer "F.Fab")
		)
		(fp_line
			(start -0.494 -0.25)
			(end 0.504 -0.25)
			(stroke
				(width 0.15)
				(type solid)
			)
			(layer "F.Fab")
		)
		(fp_line
			(start 0.504 0.248)
			(end -0.494 0.248)
			(stroke
				(width 0.15)
				(type solid)
			)
			(layer "F.Fab")
		)
		(fp_line
			(start -0.494 0.248)
			(end -0.494 -0.25)
			(stroke
				(width 0.15)
				(type solid)
			)
			(layer "F.Fab")
		)
		(fp_text user "License: Apache-2.0"
			(at -0.939 5.799 90)
			(layer "F.Fab")
			(effects
				(font
					(size 0.7 0.7)
					(thickness 0.15)
				)
				(justify left bottom)
			)
		)
		(fp_text user "${REFERENCE}"
			(at -0.939 4.599 90)
			(layer "F.Fab")
			(effects
				(font
					(size 0.7 0.7)
					(thickness 0.15)
				)
				(justify left bottom)
			)
		)
		(fp_text user "Author: Antmicro"
			(at -0.939 3.399 90)
			(layer "F.Fab")
			(effects
				(font
					(size 0.7 0.7)
					(thickness 0.15)
				)
				(justify left bottom)
			)
		)
		(pad "1" smd roundrect
			(at -0.48 0 90)
			(size 0.59 0.64)
			(layers "F.Cu" "F.Mask" "F.Paste")
			(roundrect_rratio 0.25)
			(net 1 "GND")
			(pintype "passive")
		)
		(pad "2" smd roundrect
			(at 0.48 0 90)
			(size 0.59 0.64)
			(layers "F.Cu" "F.Mask" "F.Paste")
			(roundrect_rratio 0.25)
			(net 702 "/SoM_Power/~{SYS_RESET}")
			(pintype "passive")
		)
	)
	(footprint "antmicro-footprints:Oscillator_SMD_Abracon_AX3_3.2x2.5x1mm"
		(layer "F.Cu")
		(at 87.37 148.090499)
		(property "Reference" "Y1"
			(at -0.319502 2.000001 0)
			(layer "F.SilkS")
			(effects
				(font
					(size 0.7 0.7)
					(thickness 0.15)
				)
				(justify right top)
			)
		)
		(property "Value" "Oscillator_100MHz_NX324"
			(at 0 2.8 0)
			(layer "F.Fab")
			(effects
				(font
					(size 0.7 0.7)
					(thickness 0.15)
				)
				(justify left bottom)
			)
		)
		(property "Datasheet" "https://www.diodes.com/assets/Datasheets/NX324.pdf"
			(at 0 0 0)
			(layer "F.Fab")
			(hide yes)
			(effects
				(font
					(size 1.27 1.27)
					(thickness 0.15)
				)
			)
		)
		(property "Description" "100 MHz XO (Standard) HCSL Oscillator 3.3V Enable/Disable 6-SMD, No Lead"
			(at 0 0 0)
			(layer "F.Fab")
			(hide yes)
			(effects
				(font
					(size 1.27 1.27)
					(thickness 0.15)
				)
			)
		)
		(property "Manufacturer" "Diodes Incorporated"
			(at 0 0 180)
			(unlocked yes)
			(layer "F.Fab")
			(hide yes)
			(effects
				(font
					(size 1 1)
					(thickness 0.15)
				)
			)
		)
		(property "MPN" "NX3241E0100.000000"
			(at 0 0 180)
			(unlocked yes)
			(layer "F.Fab")
			(hide yes)
			(effects
				(font
					(size 1 1)
					(thickness 0.15)
				)
			)
		)
		(property "Val" "100 MHz"
			(at 0 0 180)
			(unlocked yes)
			(layer "F.Fab")
			(hide yes)
			(effects
				(font
					(size 1 1)
					(thickness 0.15)
				)
			)
		)
		(property "Author" "Antmicro"
			(at 0 0 180)
			(unlocked yes)
			(layer "F.Fab")
			(hide yes)
			(effects
				(font
					(size 1 1)
					(thickness 0.15)
				)
			)
		)
		(property "License" "Apache-2.0"
			(at 0 0 180)
			(unlocked yes)
			(layer "F.Fab")
			(hide yes)
			(effects
				(font
					(size 1 1)
					(thickness 0.15)
				)
			)
		)
		(sheetname "/SoM_IO2/")
		(sheetfile "som_io2.kicad_sch")
		(attr smd)
		(fp_line
			(start -1.5 -1.8)
			(end -1.5 -1.5)
			(stroke
				(width 0.12)
				(type solid)
			)
			(layer "F.SilkS")
		)
		(fp_line
			(start -1.5 1.5)
			(end -1.5 1.8)
			(stroke
				(width 0.12)
				(type solid)
			)
			(layer "F.SilkS")
		)
		(fp_line
			(start -1.5 1.8)
			(end 1.5 1.8)
			(stroke
				(width 0.12)
				(type solid)
			)
			(layer "F.SilkS")
		)
		(fp_line
			(start 1.5 -1.8)
			(end -1.5 -1.8)
			(stroke
				(width 0.12)
				(type solid)
			)
			(layer "F.SilkS")
		)
		(fp_line
			(start 1.5 -1.5)
			(end 1.5 -1.8)
			(stroke
				(width 0.12)
				(type solid)
			)
			(layer "F.SilkS")
		)
		(fp_line
			(start 1.5 1.8)
			(end 1.5 1.5)
			(stroke
				(width 0.12)
				(type solid)
			)
			(layer "F.SilkS")
		)
		(fp_circle
			(center -1.7 -1.899999)
			(end -1.7 -1.85)
			(stroke
				(width 0.15)
				(type solid)
			)
			(fill yes)
			(layer "F.SilkS")
		)
		(fp_poly
			(pts
				(xy 1.6 -1.9) (xy 1.6 1.9) (xy -1.6 1.9) (xy -1.6 -1.9)
			)
			(stroke
				(width 0.05)
				(type solid)
			)
			(fill no)
			(layer "F.CrtYd")
		)
		(fp_line
			(start -0.6 -1.6)
			(end -1.3 -0.9)
			(stroke
				(width 0.15)
				(type solid)
			)
			(layer "F.Fab")
		)
		(fp_poly
			(pts
				(xy 1.3 -1.601) (xy 1.3 1.599) (xy -1.3 1.599) (xy -1.3 -1.601)
			)
			(stroke
				(width 0.15)
				(type solid)
			)
			(fill no)
			(layer "F.Fab")
		)
		(fp_text user "License: Apache-2.0"
			(at -1.6 6.499 0)
			(layer "F.Fab")
			(effects
				(font
					(size 0.7 0.7)
					(thickness 0.15)
				)
				(justify left bottom)
			)
		)
		(fp_text user "${REFERENCE}"
			(at -1.6 4.1 0)
			(layer "F.Fab")
			(effects
				(font
					(size 0.7 0.7)
					(thickness 0.15)
				)
				(justify left bottom)
			)
		)
		(fp_text user "Author: Antmicro"
			(at -1.6 5.3 0)
			(layer "F.Fab")
			(effects
				(font
					(size 0.7 0.7)
					(thickness 0.15)
				)
				(justify left bottom)
			)
		)
		(pad "1" smd rect
			(at -0.799999 -1.199 270)
			(size 0.9 1.1)
			(layers "F.Cu" "F.Mask" "F.Paste")
			(net 893 "Net-(Y1-EN)")
			(pinfunction "EN")
			(pintype "input")
		)
		(pad "2" smd rect
			(at -0.799999 0 270)
			(size 0.9 1.1)
			(layers "F.Cu" "F.Mask" "F.Paste")
			(net 1125 "unconnected-(Y1-NC-Pad2)")
			(pinfunction "NC")
			(pintype "no_connect")
		)
		(pad "3" smd rect
			(at -0.799999 1.199 270)
			(size 0.9 1.1)
			(layers "F.Cu" "F.Mask" "F.Paste")
			(net 1 "GND")
			(pinfunction "GND")
			(pintype "power_in")
		)
		(pad "4" smd rect
			(at 0.801001 1.199 270)
			(size 0.9 1.1)
			(layers "F.Cu" "F.Mask" "F.Paste")
			(net 897 "/SoM_IO2/C2_CLK+")
			(pinfunction "OUT+")
			(pintype "output")
		)
		(pad "5" smd rect
			(at 0.801001 0 270)
			(size 0.9 1.1)
			(layers "F.Cu" "F.Mask" "F.Paste")
			(net 1001 "/SoM_IO2/C2_CLK-")
			(pinfunction "OUT-")
			(pintype "output")
		)
		(pad "6" smd rect
			(at 0.801001 -1.199 270)
			(size 0.9 1.1)
			(layers "F.Cu" "F.Mask" "F.Paste")
			(net 2 "+3V3")
			(pinfunction "VCC")
			(pintype "power_in")
		)
	)
	(footprint "antmicro-footprints:C_0402_1005Metric"
		(layer "F.Cu")
		(at 219.124 104.225 180)
		(descr "Capacitor SMD 0402")
		(tags "capacitor SMD 0402")
		(property "Reference" "C109"
			(at -1.37 1.475 0)
			(layer "F.SilkS")
			(effects
				(font
					(size 0.7 0.7)
					(thickness 0.15)
				)
				(justify right top)
			)
		)
		(property "Value" "C_100n_0402"
			(at -1.022927 2.155213 0)
			(layer "F.Fab")
			(effects
				(font
					(size 0.7 0.7)
					(thickness 0.15)
				)
				(justify right top)
			)
		)
		(property "Datasheet" "https://www.murata.com/products/productdetail?partno=GRM155R61H104KE14%23"
			(at 0 0 0)
			(layer "F.Fab")
			(hide yes)
			(effects
				(font
					(size 1.27 1.27)
					(thickness 0.15)
				)
			)
		)
		(property "Description" "SMD Multilayer Ceramic Capacitor, 0.1 µF, 50 V, 0402 [1005 Metric], ± 10%, X5R, GRM Series"
			(at 0 0 0)
			(layer "F.Fab")
			(hide yes)
			(effects
				(font
					(size 1.27 1.27)
					(thickness 0.15)
				)
			)
		)
		(property "Manufacturer" "Murata"
			(at 0 0 180)
			(unlocked yes)
			(layer "F.Fab")
			(hide yes)
			(effects
				(font
					(size 1 1)
					(thickness 0.15)
				)
			)
		)
		(property "MPN" "GRM155R61H104KE14D"
			(at 0 0 180)
			(unlocked yes)
			(layer "F.Fab")
			(hide yes)
			(effects
				(font
					(size 1 1)
					(thickness 0.15)
				)
			)
		)
		(property "Val" "100n"
			(at 0 0 180)
			(unlocked yes)
			(layer "F.Fab")
			(hide yes)
			(effects
				(font
					(size 1 1)
					(thickness 0.15)
				)
			)
		)
		(property "License" "Apache-2.0"
			(at 0 0 180)
			(unlocked yes)
			(layer "F.Fab")
			(hide yes)
			(effects
				(font
					(size 1 1)
					(thickness 0.15)
				)
			)
		)
		(property "Author" "Antmicro"
			(at 0 0 180)
			(unlocked yes)
			(layer "F.Fab")
			(hide yes)
			(effects
				(font
					(size 1 1)
					(thickness 0.15)
				)
			)
		)
		(property "Voltage" "50V"
			(at 0 0 180)
			(unlocked yes)
			(layer "F.Fab")
			(hide yes)
			(effects
				(font
					(size 1 1)
					(thickness 0.15)
				)
			)
		)
		(property "Dielectric" "X5R"
			(at 0 0 180)
			(unlocked yes)
			(layer "F.Fab")
			(hide yes)
			(effects
				(font
					(size 1 1)
					(thickness 0.15)
				)
			)
		)
		(sheetname "/Recovery USB/")
		(sheetfile "recovery_usb.kicad_sch")
		(attr smd)
		(fp_rect
			(start -0.925 -0.47)
			(end 0.925 0.47)
			(stroke
				(width 0.05)
				(type default)
			)
			(fill no)
			(layer "F.CrtYd")
		)
		(fp_line
			(start 0.504 0.248)
			(end -0.494 0.248)
			(stroke
				(width 0.15)
				(type solid)
			)
			(layer "F.Fab")
		)
		(fp_line
			(start 0.504 -0.25)
			(end 0.504 0.248)
			(stroke
				(width 0.15)
				(type solid)
			)
			(layer "F.Fab")
		)
		(fp_line
			(start -0.494 0.248)
			(end -0.494 -0.25)
			(stroke
				(width 0.15)
				(type solid)
			)
			(layer "F.Fab")
		)
		(fp_line
			(start -0.494 -0.25)
			(end 0.504 -0.25)
			(stroke
				(width 0.15)
				(type solid)
			)
			(layer "F.Fab")
		)
		(fp_text user "Author: Antmicro"
			(at -0.939 3.399 0)
			(layer "F.Fab")
			(effects
				(font
					(size 0.7 0.7)
					(thickness 0.15)
				)
				(justify right top)
			)
		)
		(fp_text user "${REFERENCE}"
			(at -0.939 4.599 0)
			(layer "F.Fab")
			(effects
				(font
					(size 0.7 0.7)
					(thickness 0.15)
				)
				(justify right top)
			)
		)
		(fp_text user "License: Apache-2.0"
			(at -0.939 5.799 0)
			(layer "F.Fab")
			(effects
				(font
					(size 0.7 0.7)
					(thickness 0.15)
				)
				(justify right top)
			)
		)
		(pad "1" smd roundrect
			(at -0.48 0 180)
			(size 0.59 0.64)
			(layers "F.Cu" "F.Mask" "F.Paste")
			(roundrect_rratio 0.25)
			(net 245 "/Recovery USB/USBC2_CONN_TX1_P")
			(pintype "passive")
		)
		(pad "2" smd roundrect
			(at 0.48 0 180)
			(size 0.59 0.64)
			(layers "F.Cu" "F.Mask" "F.Paste")
			(roundrect_rratio 0.25)
			(net 242 "/Recovery USB/USBC2_TX1_P")
			(pintype "passive")
		)
	)
	(footprint "antmicro-footprints:QFN-2L_1.6x1x0.55mm"
		(layer "F.Cu")
		(at 159.9 74.1 90)
		(property "Reference" "D56"
			(at -0.7 -0.8 90)
			(layer "F.SilkS")
			(effects
				(font
					(size 0.7 0.7)
					(thickness 0.15)
				)
				(justify left bottom)
			)
		)
		(property "Value" "ESDA25P35-1U1M"
			(at 0 1.7 90)
			(layer "F.Fab")
			(effects
				(font
					(size 0.7 0.7)
					(thickness 0.15)
				)
				(justify left bottom)
			)
		)
		(property "Datasheet" "https://www.st.com/resource/en/datasheet/esda25p35-1u1m.pdf"
			(at 0 0 90)
			(layer "F.Fab")
			(hide yes)
			(effects
				(font
					(size 1.27 1.27)
					(thickness 0.15)
				)
			)
		)
		(property "Description" "Unidirectional TVS, 30 kV, QFN-2L, 22 V, 195 pF"
			(at 0 0 90)
			(layer "F.Fab")
			(hide yes)
			(effects
				(font
					(size 1.27 1.27)
					(thickness 0.15)
				)
			)
		)
		(property "Manufacturer" "STMicroelectronics"
			(at 0 0 90)
			(unlocked yes)
			(layer "F.Fab")
			(hide yes)
			(effects
				(font
					(size 1 1)
					(thickness 0.15)
				)
			)
		)
		(property "MPN" "ESDA25P35-1U1M"
			(at 0 0 90)
			(unlocked yes)
			(layer "F.Fab")
			(hide yes)
			(effects
				(font
					(size 1 1)
					(thickness 0.15)
				)
			)
		)
		(property "Author" "Antmicro"
			(at 0 0 90)
			(unlocked yes)
			(layer "F.Fab")
			(hide yes)
			(effects
				(font
					(size 1 1)
					(thickness 0.15)
				)
			)
		)
		(property "License" "Apache-2.0"
			(at 0 0 90)
			(unlocked yes)
			(layer "F.Fab")
			(hide yes)
			(effects
				(font
					(size 1 1)
					(thickness 0.15)
				)
			)
		)
		(component_classes
			(class "DCDC_20V")
		)
		(sheetname "/DCDC/")
		(sheetfile "dcdc.kicad_sch")
		(attr smd)
		(fp_line
			(start 0.23 -0.45)
			(end -0.23 -0.45)
			(stroke
				(width 0.15)
				(type solid)
			)
			(layer "F.SilkS")
		)
		(fp_line
			(start -1.2 -0.4)
			(end -1.2 0.4)
			(stroke
				(width 0.15)
				(type solid)
			)
			(layer "F.SilkS")
		)
		(fp_line
			(start 0.23 0.45)
			(end -0.23 0.45)
			(stroke
				(width 0.15)
				(type solid)
			)
			(layer "F.SilkS")
		)
		(fp_rect
			(start 1.25 0.65)
			(end -1.25 -0.65)
			(stroke
				(width 0.05)
				(type solid)
			)
			(fill no)
			(layer "F.CrtYd")
		)
		(fp_line
			(start 0.201 -0.202)
			(end -0.101 0)
			(stroke
				(width 0.15)
				(type solid)
			)
			(layer "F.Fab")
		)
		(fp_line
			(start -0.199 -0.202)
			(end -0.199 0.1)
			(stroke
				(width 0.15)
				(type solid)
			)
			(layer "F.Fab")
		)
		(fp_line
			(start 0.599 0)
			(end 0.201 0)
			(stroke
				(width 0.15)
				(type solid)
			)
			(layer "F.Fab")
		)
		(fp_line
			(start 0.201 0)
			(end 0.201 -0.202)
			(stroke
				(width 0.15)
				(type solid)
			)
			(layer "F.Fab")
		)
		(fp_line
			(start -0.101 0)
			(end 0.201 0.2)
			(stroke
				(width 0.15)
				(type solid)
			)
			(layer "F.Fab")
		)
		(fp_line
			(start -0.199 0)
			(end -0.597 0)
			(stroke
				(width 0.15)
				(type solid)
			)
			(layer "F.Fab")
		)
		(fp_line
			(start 0.201 0.2)
			(end 0.201 0)
			(stroke
				(width 0.15)
				(type solid)
			)
			(layer "F.Fab")
		)
		(fp_line
			(start -0.199 0.2)
			(end -0.199 0.1)
			(stroke
				(width 0.15)
				(type solid)
			)
			(layer "F.Fab")
		)
		(fp_rect
			(start 0.848 0.4)
			(end -0.85 -0.402)
			(stroke
				(width 0.15)
				(type solid)
			)
			(fill no)
			(layer "F.Fab")
		)
		(fp_text user "${REFERENCE}"
			(at -1.31 3.769 90)
			(layer "F.Fab")
			(effects
				(font
					(size 0.7 0.7)
					(thickness 0.15)
				)
				(justify left bottom)
			)
		)
		(fp_text user "Author: Antmicro"
			(at -1.31 4.769 90)
			(layer "F.Fab")
			(effects
				(font
					(size 0.7 0.7)
					(thickness 0.15)
				)
				(justify left bottom)
			)
		)
		(fp_text user "License: Apache-2.0"
			(at -1.31 5.769 90)
			(layer "F.Fab")
			(effects
				(font
					(size 0.7 0.7)
					(thickness 0.15)
				)
				(justify left bottom)
			)
		)
		(pad "1" smd roundrect
			(at -0.7 0 270)
			(size 0.8 1)
			(layers "F.Cu" "F.Mask" "F.Paste")
			(roundrect_rratio 0.2)
			(net 904 "+20V")
			(pinfunction "C")
			(pintype "passive")
		)
		(pad "2" smd roundrect
			(at 0.7 0 270)
			(size 0.8 1)
			(layers "F.Cu" "F.Mask" "F.Paste")
			(roundrect_rratio 0.2)
			(net 1 "GND")
			(pinfunction "A")
			(pintype "passive")
		)
	)
	(footprint "antmicro-footprints:R_0402_1005Metric"
		(layer "F.Cu")
		(at 203.6 135.7 180)
		(descr "Resistor SMD 0402")
		(tags "resistor SMD 0402")
		(property "Reference" "R82"
			(at 2.8 0.4 0)
			(layer "F.SilkS")
			(effects
				(font
					(size 0.7 0.7)
					(thickness 0.15)
				)
				(justify right top)
			)
		)
		(property "Value" "R_49k9_0402"
			(at -1.011843 1.772046 0)
			(layer "F.Fab")
			(effects
				(font
					(size 0.7 0.7)
					(thickness 0.15)
				)
				(justify right top)
			)
		)
		(property "Datasheet" "https://www.bourns.com/docs/product-datasheets/cr.pdf"
			(at 0 0 0)
			(layer "F.Fab")
			(hide yes)
			(effects
				(font
					(size 1.27 1.27)
					(thickness 0.15)
				)
			)
		)
		(property "Description" "SMD Chip Resistor, 49.9 kohm, ± 1%, 63 mW, 0402 [1005 Metric], Thick Film, General Purpose"
			(at 0 0 0)
			(layer "F.Fab")
			(hide yes)
			(effects
				(font
					(size 1.27 1.27)
					(thickness 0.15)
				)
			)
		)
		(property "MPN" "CR0402-FX-4992GLF"
			(at 0 0 180)
			(unlocked yes)
			(layer "F.Fab")
			(hide yes)
			(effects
				(font
					(size 1 1)
					(thickness 0.15)
				)
			)
		)
		(property "Manufacturer" "Bourns"
			(at 0 0 180)
			(unlocked yes)
			(layer "F.Fab")
			(hide yes)
			(effects
				(font
					(size 1 1)
					(thickness 0.15)
				)
			)
		)
		(property "License" "Apache-2.0"
			(at 0 0 180)
			(unlocked yes)
			(layer "F.Fab")
			(hide yes)
			(effects
				(font
					(size 1 1)
					(thickness 0.15)
				)
			)
		)
		(property "Author" "Antmicro"
			(at 0 0 180)
			(unlocked yes)
			(layer "F.Fab")
			(hide yes)
			(effects
				(font
					(size 1 1)
					(thickness 0.15)
				)
			)
		)
		(property "Val" "49k9"
			(at 0 0 180)
			(unlocked yes)
			(layer "F.Fab")
			(hide yes)
			(effects
				(font
					(size 1 1)
					(thickness 0.15)
				)
			)
		)
		(property "Tolerance" "1%"
			(at 0 0 180)
			(unlocked yes)
			(layer "F.Fab")
			(hide yes)
			(effects
				(font
					(size 1 1)
					(thickness 0.15)
				)
			)
		)
		(sheetname "/USB Hub/")
		(sheetfile "usb_hub.kicad_sch")
		(attr smd)
		(fp_poly
			(pts
				(xy -0.925 -0.47) (xy -0.925 0.47) (xy 0.925 0.47) (xy 0.925 -0.47)
			)
			(stroke
				(width 0.05)
				(type default)
			)
			(fill no)
			(layer "F.CrtYd")
		)
		(fp_poly
			(pts
				(xy -0.5 -0.25) (xy -0.5 0.25) (xy 0.5 0.25) (xy 0.5 -0.25)
			)
			(stroke
				(width 0.15)
				(type solid)
			)
			(fill no)
			(layer "F.Fab")
		)
		(fp_text user "Author: Antmicro"
			(at -0.95 4.169 0)
			(layer "F.Fab")
			(effects
				(font
					(size 0.7 0.7)
					(thickness 0.15)
				)
				(justify right top)
			)
		)
		(fp_text user "${REFERENCE}"
			(at -0.95 3.168 0)
			(layer "F.Fab")
			(effects
				(font
					(size 0.7 0.7)
					(thickness 0.15)
				)
				(justify right top)
			)
		)
		(fp_text user "License: Apache-2.0"
			(at -0.949999 5.169 0)
			(layer "F.Fab")
			(effects
				(font
					(size 0.7 0.7)
					(thickness 0.15)
				)
				(justify right top)
			)
		)
		(pad "1" smd roundrect
			(at -0.48 0 180)
			(size 0.59 0.64)
			(layers "F.Cu" "F.Mask" "F.Paste")
			(roundrect_rratio 0.25)
			(net 1 "GND")
			(pintype "passive")
		)
		(pad "2" smd roundrect
			(at 0.48 0 180)
			(size 0.59 0.64)
			(layers "F.Cu" "F.Mask" "F.Paste")
			(roundrect_rratio 0.25)
			(net 1164 "/USB Hub/VBUS_MON_UP")
			(pintype "passive")
		)
	)
	(footprint "antmicro-footprints:SW_KMR211NGLFS_SMD"
		(layer "F.Cu")
		(at 199 55.52)
		(property "Reference" "S1"
			(at -3.2 2.78 180)
			(layer "F.SilkS")
			(hide yes)
			(effects
				(font
					(size 0.7 0.7)
					(thickness 0.15)
				)
				(justify left bottom)
			)
		)
		(property "Value" "SW_KMR211NGLFS_SMD"
			(at 0 2.8 0)
			(layer "F.Fab")
			(effects
				(font
					(size 0.7 0.7)
					(thickness 0.15)
				)
				(justify left bottom)
			)
		)
		(property "Datasheet" "http://www.farnell.com/datasheets/2631211.pdf"
			(at 0 0 0)
			(layer "F.Fab")
			(hide yes)
			(effects
				(font
					(size 1.27 1.27)
					(thickness 0.15)
				)
			)
		)
		(property "Description" "Tactile Switch, KMR 2 Series, Top Actuated, Surface Mount, Oval Button, 120 gf, 50mA at 32VDC"
			(at 0 0 0)
			(layer "F.Fab")
			(hide yes)
			(effects
				(font
					(size 1.27 1.27)
					(thickness 0.15)
				)
			)
		)
		(property "MPN" "KMR211NGLFS"
			(at 0 0 0)
			(unlocked yes)
			(layer "F.Fab")
			(hide yes)
			(effects
				(font
					(size 1 1)
					(thickness 0.15)
				)
			)
		)
		(property "Manufacturer" "C&K"
			(at 0 0 0)
			(unlocked yes)
			(layer "F.Fab")
			(hide yes)
			(effects
				(font
					(size 1 1)
					(thickness 0.15)
				)
			)
		)
		(property "Author" "Antmicro"
			(at 0 0 0)
			(unlocked yes)
			(layer "F.Fab")
			(hide yes)
			(effects
				(font
					(size 1 1)
					(thickness 0.15)
				)
			)
		)
		(property "License" "Apache-2.0"
			(at 0 0 0)
			(unlocked yes)
			(layer "F.Fab")
			(hide yes)
			(effects
				(font
					(size 1 1)
					(thickness 0.15)
				)
			)
		)
		(sheetname "/SoM_Power/")
		(sheetfile "som_power.kicad_sch")
		(attr smd)
		(fp_line
			(start -2.1 -1.6)
			(end -2.1 -1.499)
			(stroke
				(width 0.15)
				(type solid)
			)
			(layer "F.SilkS")
		)
		(fp_line
			(start -2.1 1.601)
			(end -2.1 1.48)
			(stroke
				(width 0.15)
				(type solid)
			)
			(layer "F.SilkS")
		)
		(fp_line
			(start 2.101 -1.6)
			(end -2.1 -1.6)
			(stroke
				(width 0.15)
				(type solid)
			)
			(layer "F.SilkS")
		)
		(fp_line
			(start 2.101 -1.58)
			(end 2.101 -1.459)
			(stroke
				(width 0.15)
				(type solid)
			)
			(layer "F.SilkS")
		)
		(fp_line
			(start 2.101 1.601)
			(end -2.1 1.601)
			(stroke
				(width 0.15)
				(type solid)
			)
			(layer "F.SilkS")
		)
		(fp_line
			(start 2.101 1.601)
			(end 2.101 1.48)
			(stroke
				(width 0.15)
				(type solid)
			)
			(layer "F.SilkS")
		)
		(fp_poly
			(pts
				(xy 2.751 1.75) (xy 2.751 -1.749) (xy -2.748 -1.749) (xy -2.748 1.749999)
			)
			(stroke
				(width 0.05)
				(type solid)
			)
			(fill no)
			(layer "F.CrtYd")
		)
		(fp_line
			(start -2.1 -1.6)
			(end -2.1 1.601)
			(stroke
				(width 0.15)
				(type solid)
			)
			(layer "F.Fab")
		)
		(fp_line
			(start -2.1 1.601)
			(end 2.101 1.601)
			(stroke
				(width 0.15)
				(type solid)
			)
			(layer "F.Fab")
		)
		(fp_line
			(start -0.248 -0.8)
			(end 0.25 -0.8)
			(stroke
				(width 0.15)
				(type solid)
			)
			(layer "F.Fab")
		)
		(fp_line
			(start 0.25 0.802)
			(end -0.248 0.802)
			(stroke
				(width 0.15)
				(type solid)
			)
			(layer "F.Fab")
		)
		(fp_line
			(start 2.101 -1.6)
			(end -2.1 -1.6)
			(stroke
				(width 0.15)
				(type solid)
			)
			(layer "F.Fab")
		)
		(fp_line
			(start 2.101 1.601)
			(end 2.101 -1.6)
			(stroke
				(width 0.15)
				(type solid)
			)
			(layer "F.Fab")
		)
		(fp_arc
			(start -0.248 0.802)
			(mid -1.050001 0.001)
			(end -0.248 -0.8)
			(stroke
				(width 0.15)
				(type solid)
			)
			(layer "F.Fab")
		)
		(fp_arc
			(start 0.25 -0.8)
			(mid 1.051001 0.001)
			(end 0.25 0.802)
			(stroke
				(width 0.15)
				(type solid)
			)
			(layer "F.Fab")
		)
		(fp_text user "Author: Antmicro"
			(at -3 5.5 0)
			(layer "F.Fab")
			(effects
				(font
					(size 0.7 0.7)
					(thickness 0.15)
				)
				(justify left bottom)
			)
		)
		(fp_text user "License: Apache-2.0"
			(at -3 6.75 0)
			(layer "F.Fab")
			(effects
				(font
					(size 0.7 0.7)
					(thickness 0.15)
				)
				(justify left bottom)
			)
		)
		(fp_text user "${REFERENCE}"
			(at -3 4.25 0)
			(layer "F.Fab")
			(effects
				(font
					(size 0.7 0.7)
					(thickness 0.15)
				)
				(justify left bottom)
			)
		)
		(pad "1" smd rect
			(at -2.048 -0.8 180)
			(size 0.9 1)
			(layers "F.Cu" "F.Mask" "F.Paste")
			(net 1 "GND")
			(pinfunction "1")
			(pintype "passive")
		)
		(pad "2" smd rect
			(at 2.049999 -0.8 180)
			(size 0.9 1)
			(layers "F.Cu" "F.Mask" "F.Paste")
			(net 1 "GND")
			(pinfunction "2")
			(pintype "passive")
		)
		(pad "3" smd rect
			(at -2.048 0.802 180)
			(size 0.9 1)
			(layers "F.Cu" "F.Mask" "F.Paste")
			(net 702 "/SoM_Power/~{SYS_RESET}")
			(pinfunction "3")
			(pintype "passive")
		)
		(pad "4" smd rect
			(at 2.05 0.802001 180)
			(size 0.9 1)
			(layers "F.Cu" "F.Mask" "F.Paste")
			(net 702 "/SoM_Power/~{SYS_RESET}")
			(pinfunction "4")
			(pintype "passive")
		)
	)
	(footprint "antmicro-footprints:TP_SMD_0.75mm"
		(layer "F.Cu")
		(at 67.51 58.29 90)
		(property "Reference" "TP26"
			(at 1.59 -2.86 90)
			(layer "F.SilkS")
			(effects
				(font
					(size 0.7 0.7)
					(thickness 0.15)
				)
				(justify left bottom)
			)
		)
		(property "Value" "TP_0.75mm_SMD"
			(at 0 1.2 90)
			(layer "F.Fab")
			(effects
				(font
					(size 0.7 0.7)
					(thickness 0.15)
				)
				(justify left bottom)
			)
		)
		(property "Description" "SMT test point"
			(at 0 0 90)
			(layer "F.Fab")
			(hide yes)
			(effects
				(font
					(size 1.27 1.27)
					(thickness 0.15)
				)
			)
		)
		(property "MPN" ""
			(at 0 0 90)
			(unlocked yes)
			(layer "F.Fab")
			(hide yes)
			(effects
				(font
					(size 1 1)
					(thickness 0.15)
				)
			)
		)
		(property "Manufacturer" ""
			(at 0 0 90)
			(unlocked yes)
			(layer "F.Fab")
			(hide yes)
			(effects
				(font
					(size 1 1)
					(thickness 0.15)
				)
			)
		)
		(property "Author" "Antmicro"
			(at 0 0 90)
			(unlocked yes)
			(layer "F.Fab")
			(hide yes)
			(effects
				(font
					(size 1 1)
					(thickness 0.15)
				)
			)
		)
		(property "License" "Apache-2.0"
			(at 0 0 90)
			(unlocked yes)
			(layer "F.Fab")
			(hide yes)
			(effects
				(font
					(size 1 1)
					(thickness 0.15)
				)
			)
		)
		(sheetname "/CSI/")
		(sheetfile "csi.kicad_sch")
		(attr exclude_from_pos_files exclude_from_bom)
		(fp_circle
			(center 0 0)
			(end 0.475 0)
			(stroke
				(width 0.05)
				(type default)
			)
			(fill no)
			(layer "F.CrtYd")
		)
		(fp_text user "License: Apache-2.0"
			(at -0.4 5.101 90)
			(layer "F.Fab")
			(effects
				(font
					(size 0.7 0.7)
					(thickness 0.15)
				)
				(justify left bottom)
			)
		)
		(fp_text user "Author: Antmicro"
			(at -0.4 3.901 90)
			(layer "F.Fab")
			(effects
				(font
					(size 0.7 0.7)
					(thickness 0.15)
				)
				(justify left bottom)
			)
		)
		(fp_text user "${REFERENCE}"
			(at -0.4 2.7 90)
			(layer "F.Fab")
			(effects
				(font
					(size 0.7 0.7)
					(thickness 0.15)
				)
				(justify left bottom)
			)
		)
		(pad "1" smd circle
			(at 0 0 90)
			(size 0.75 0.75)
			(layers "F.Cu" "F.Mask")
			(net 1050 "/CSI/MUX_I2C_6_SCL")
			(pinfunction "1")
			(pintype "passive")
		)
	)
	(footprint "antmicro-footprints:R_0402_1005Metric"
		(layer "F.Cu")
		(at 190.6 81.4)
		(descr "Resistor SMD 0402")
		(tags "resistor SMD 0402")
		(property "Reference" "R105"
			(at -3.8 0.5 0)
			(layer "F.SilkS")
			(effects
				(font
					(size 0.7 0.7)
					(thickness 0.15)
				)
				(justify left bottom)
			)
		)
		(property "Value" "R_4k7_0402"
			(at -1.011843 1.772046 0)
			(layer "F.Fab")
			(effects
				(font
					(size 0.7 0.7)
					(thickness 0.15)
				)
				(justify left bottom)
			)
		)
		(property "Datasheet" "https://www.bourns.com/docs/product-datasheets/cr.pdf"
			(at 0 0 0)
			(layer "F.Fab")
			(hide yes)
			(effects
				(font
					(size 1.27 1.27)
					(thickness 0.15)
				)
			)
		)
		(property "Description" "SMD Chip Resistor, 4.7 kohm, ± 1%, 62.5 mW, 0402 [1005 Metric], Thick Film, General Purpose"
			(at 0 0 0)
			(layer "F.Fab")
			(hide yes)
			(effects
				(font
					(size 1.27 1.27)
					(thickness 0.15)
				)
			)
		)
		(property "Manufacturer" "Bourns"
			(at 0 0 0)
			(unlocked yes)
			(layer "F.Fab")
			(hide yes)
			(effects
				(font
					(size 1 1)
					(thickness 0.15)
				)
			)
		)
		(property "MPN" "CR0402-FX-4701GLF"
			(at 0 0 0)
			(unlocked yes)
			(layer "F.Fab")
			(hide yes)
			(effects
				(font
					(size 1 1)
					(thickness 0.15)
				)
			)
		)
		(property "Val" "4k7"
			(at 0 0 0)
			(unlocked yes)
			(layer "F.Fab")
			(hide yes)
			(effects
				(font
					(size 1 1)
					(thickness 0.15)
				)
			)
		)
		(property "License" "Apache-2.0"
			(at 0 0 0)
			(unlocked yes)
			(layer "F.Fab")
			(hide yes)
			(effects
				(font
					(size 1 1)
					(thickness 0.15)
				)
			)
		)
		(property "Author" "Antmicro"
			(at 0 0 0)
			(unlocked yes)
			(layer "F.Fab")
			(hide yes)
			(effects
				(font
					(size 1 1)
					(thickness 0.15)
				)
			)
		)
		(property "Tolerance" "1%"
			(at 0 0 0)
			(unlocked yes)
			(layer "F.Fab")
			(hide yes)
			(effects
				(font
					(size 1 1)
					(thickness 0.15)
				)
			)
		)
		(sheetname "/USB Debug, PD/")
		(sheetfile "usb_debug_pd.kicad_sch")
		(attr smd)
		(fp_poly
			(pts
				(xy -0.925 -0.47) (xy -0.925 0.47) (xy 0.925 0.47) (xy 0.925 -0.47)
			)
			(stroke
				(width 0.05)
				(type default)
			)
			(fill no)
			(layer "F.CrtYd")
		)
		(fp_poly
			(pts
				(xy -0.5 -0.25) (xy -0.5 0.25) (xy 0.5 0.25) (xy 0.5 -0.25)
			)
			(stroke
				(width 0.15)
				(type solid)
			)
			(fill no)
			(layer "F.Fab")
		)
		(fp_text user "License: Apache-2.0"
			(at -0.949999 5.169 0)
			(layer "F.Fab")
			(effects
				(font
					(size 0.7 0.7)
					(thickness 0.15)
				)
				(justify left bottom)
			)
		)
		(fp_text user "Author: Antmicro"
			(at -0.95 4.169 0)
			(layer "F.Fab")
			(effects
				(font
					(size 0.7 0.7)
					(thickness 0.15)
				)
				(justify left bottom)
			)
		)
		(fp_text user "${REFERENCE}"
			(at -0.95 3.168 0)
			(layer "F.Fab")
			(effects
				(font
					(size 0.7 0.7)
					(thickness 0.15)
				)
				(justify left bottom)
			)
		)
		(pad "1" smd roundrect
			(at -0.48 0)
			(size 0.59 0.64)
			(layers "F.Cu" "F.Mask" "F.Paste")
			(roundrect_rratio 0.25)
			(net 2 "+3V3")
			(pintype "passive")
		)
		(pad "2" smd roundrect
			(at 0.48 0)
			(size 0.59 0.64)
			(layers "F.Cu" "F.Mask" "F.Paste")
			(roundrect_rratio 0.25)
			(net 947 "/USB Debug, PD/PDC_I2C2_SCL")
			(pintype "passive")
		)
	)
	(footprint "antmicro-footprints:C_0402_1005Metric"
		(layer "F.Cu")
		(at 212.544132 84.292 -90)
		(descr "Capacitor SMD 0402")
		(tags "capacitor SMD 0402")
		(property "Reference" "C128"
			(at -3.682 0.324132 90)
			(layer "F.SilkS")
			(effects
				(font
					(size 0.7 0.7)
					(thickness 0.15)
				)
				(justify right top)
			)
		)
		(property "Value" "C_100n_0402"
			(at -1.022927 2.155213 90)
			(layer "F.Fab")
			(effects
				(font
					(size 0.7 0.7)
					(thickness 0.15)
				)
				(justify right top)
			)
		)
		(property "Datasheet" "https://www.murata.com/products/productdetail?partno=GRM155R61H104KE14%23"
			(at 0 0 90)
			(layer "F.Fab")
			(hide yes)
			(effects
				(font
					(size 1.27 1.27)
					(thickness 0.15)
				)
			)
		)
		(property "Description" "SMD Multilayer Ceramic Capacitor, 0.1 µF, 50 V, 0402 [1005 Metric], ± 10%, X5R, GRM Series"
			(at 0 0 90)
			(layer "F.Fab")
			(hide yes)
			(effects
				(font
					(size 1.27 1.27)
					(thickness 0.15)
				)
			)
		)
		(property "Manufacturer" "Murata"
			(at 0 0 270)
			(unlocked yes)
			(layer "F.Fab")
			(hide yes)
			(effects
				(font
					(size 1 1)
					(thickness 0.15)
				)
			)
		)
		(property "MPN" "GRM155R61H104KE14D"
			(at 0 0 270)
			(unlocked yes)
			(layer "F.Fab")
			(hide yes)
			(effects
				(font
					(size 1 1)
					(thickness 0.15)
				)
			)
		)
		(property "Val" "100n"
			(at 0 0 270)
			(unlocked yes)
			(layer "F.Fab")
			(hide yes)
			(effects
				(font
					(size 1 1)
					(thickness 0.15)
				)
			)
		)
		(property "License" "Apache-2.0"
			(at 0 0 270)
			(unlocked yes)
			(layer "F.Fab")
			(hide yes)
			(effects
				(font
					(size 1 1)
					(thickness 0.15)
				)
			)
		)
		(property "Author" "Antmicro"
			(at 0 0 270)
			(unlocked yes)
			(layer "F.Fab")
			(hide yes)
			(effects
				(font
					(size 1 1)
					(thickness 0.15)
				)
			)
		)
		(property "Voltage" "50V"
			(at 0 0 270)
			(unlocked yes)
			(layer "F.Fab")
			(hide yes)
			(effects
				(font
					(size 1 1)
					(thickness 0.15)
				)
			)
		)
		(property "Dielectric" "X5R"
			(at 0 0 270)
			(unlocked yes)
			(layer "F.Fab")
			(hide yes)
			(effects
				(font
					(size 1 1)
					(thickness 0.15)
				)
			)
		)
		(sheetname "/USB DP Alt mode/")
		(sheetfile "usb_dp.kicad_sch")
		(attr smd)
		(fp_rect
			(start -0.925 -0.47)
			(end 0.925 0.47)
			(stroke
				(width 0.05)
				(type default)
			)
			(fill no)
			(layer "F.CrtYd")
		)
		(fp_line
			(start -0.494 0.248)
			(end -0.494 -0.25)
			(stroke
				(width 0.15)
				(type solid)
			)
			(layer "F.Fab")
		)
		(fp_line
			(start 0.504 0.248)
			(end -0.494 0.248)
			(stroke
				(width 0.15)
				(type solid)
			)
			(layer "F.Fab")
		)
		(fp_line
			(start -0.494 -0.25)
			(end 0.504 -0.25)
			(stroke
				(width 0.15)
				(type solid)
			)
			(layer "F.Fab")
		)
		(fp_line
			(start 0.504 -0.25)
			(end 0.504 0.248)
			(stroke
				(width 0.15)
				(type solid)
			)
			(layer "F.Fab")
		)
		(fp_text user "Author: Antmicro"
			(at -0.939 3.399 90)
			(layer "F.Fab")
			(effects
				(font
					(size 0.7 0.7)
					(thickness 0.15)
				)
				(justify right top)
			)
		)
		(fp_text user "${REFERENCE}"
			(at -0.939 4.599 90)
			(layer "F.Fab")
			(effects
				(font
					(size 0.7 0.7)
					(thickness 0.15)
				)
				(justify right top)
			)
		)
		(fp_text user "License: Apache-2.0"
			(at -0.939 5.799 90)
			(layer "F.Fab")
			(effects
				(font
					(size 0.7 0.7)
					(thickness 0.15)
				)
				(justify right top)
			)
		)
		(pad "1" smd roundrect
			(at -0.48 0 270)
			(size 0.59 0.64)
			(layers "F.Cu" "F.Mask" "F.Paste")
			(roundrect_rratio 0.25)
			(net 329 "/SoM_IO2/USBSS1.TX-")
			(pintype "passive")
		)
		(pad "2" smd roundrect
			(at 0.48 0 270)
			(size 0.59 0.64)
			(layers "F.Cu" "F.Mask" "F.Paste")
			(roundrect_rratio 0.25)
			(net 310 "/USB DP Alt mode/USBSS1_TX_C_P")
			(pintype "passive")
		)
	)
	(footprint "antmicro-footprints:C_0402_1005Metric"
		(layer "F.Cu")
		(at 207.34 117.8 -90)
		(descr "Capacitor SMD 0402")
		(tags "capacitor SMD 0402")
		(property "Reference" "C95"
			(at -3 0.44 90)
			(layer "F.SilkS")
			(effects
				(font
					(size 0.7 0.7)
					(thickness 0.15)
				)
				(justify right top)
			)
		)
		(property "Value" "C_100n_0402"
			(at -1.022927 2.155213 90)
			(layer "F.Fab")
			(effects
				(font
					(size 0.7 0.7)
					(thickness 0.15)
				)
				(justify right top)
			)
		)
		(property "Datasheet" "https://www.murata.com/products/productdetail?partno=GRM155R61H104KE14%23"
			(at 0 0 90)
			(layer "F.Fab")
			(hide yes)
			(effects
				(font
					(size 1.27 1.27)
					(thickness 0.15)
				)
			)
		)
		(property "Description" "SMD Multilayer Ceramic Capacitor, 0.1 µF, 50 V, 0402 [1005 Metric], ± 10%, X5R, GRM Series"
			(at 0 0 90)
			(layer "F.Fab")
			(hide yes)
			(effects
				(font
					(size 1.27 1.27)
					(thickness 0.15)
				)
			)
		)
		(property "MPN" "GRM155R61H104KE14D"
			(at 0 0 270)
			(unlocked yes)
			(layer "F.Fab")
			(hide yes)
			(effects
				(font
					(size 1 1)
					(thickness 0.15)
				)
			)
		)
		(property "Val" "100n"
			(at 0 0 270)
			(unlocked yes)
			(layer "F.Fab")
			(hide yes)
			(effects
				(font
					(size 1 1)
					(thickness 0.15)
				)
			)
		)
		(property "Voltage" "50V"
			(at 0 0 270)
			(unlocked yes)
			(layer "F.Fab")
			(hide yes)
			(effects
				(font
					(size 1 1)
					(thickness 0.15)
				)
			)
		)
		(property "Dielectric" "X5R"
			(at 0 0 270)
			(unlocked yes)
			(layer "F.Fab")
			(hide yes)
			(effects
				(font
					(size 1 1)
					(thickness 0.15)
				)
			)
		)
		(property "Manufacturer" "Murata"
			(at 0 0 270)
			(unlocked yes)
			(layer "F.Fab")
			(hide yes)
			(effects
				(font
					(size 1 1)
					(thickness 0.15)
				)
			)
		)
		(property "License" "Apache-2.0"
			(at 0 0 270)
			(unlocked yes)
			(layer "F.Fab")
			(hide yes)
			(effects
				(font
					(size 1 1)
					(thickness 0.15)
				)
			)
		)
		(property "Author" "Antmicro"
			(at 0 0 270)
			(unlocked yes)
			(layer "F.Fab")
			(hide yes)
			(effects
				(font
					(size 1 1)
					(thickness 0.15)
				)
			)
		)
		(sheetname "/USB Hub/")
		(sheetfile "usb_hub.kicad_sch")
		(attr smd)
		(fp_poly
			(pts
				(xy -0.925 -0.47) (xy -0.925 0.47) (xy 0.925 0.47) (xy 0.925 -0.47)
			)
			(stroke
				(width 0.05)
				(type default)
			)
			(fill no)
			(layer "F.CrtYd")
		)
		(fp_line
			(start -0.494 0.248)
			(end -0.494 -0.25)
			(stroke
				(width 0.15)
				(type solid)
			)
			(layer "F.Fab")
		)
		(fp_line
			(start 0.504 0.248)
			(end -0.494 0.248)
			(stroke
				(width 0.15)
				(type solid)
			)
			(layer "F.Fab")
		)
		(fp_line
			(start -0.494 -0.25)
			(end 0.504 -0.25)
			(stroke
				(width 0.15)
				(type solid)
			)
			(layer "F.Fab")
		)
		(fp_line
			(start 0.504 -0.25)
			(end 0.504 0.248)
			(stroke
				(width 0.15)
				(type solid)
			)
			(layer "F.Fab")
		)
		(fp_text user "${REFERENCE}"
			(at -0.939 4.599 90)
			(layer "F.Fab")
			(effects
				(font
					(size 0.7 0.7)
					(thickness 0.15)
				)
				(justify right top)
			)
		)
		(fp_text user "License: Apache-2.0"
			(at -0.939 5.799 90)
			(layer "F.Fab")
			(effects
				(font
					(size 0.7 0.7)
					(thickness 0.15)
				)
				(justify right top)
			)
		)
		(fp_text user "Author: Antmicro"
			(at -0.939 3.399 90)
			(layer "F.Fab")
			(effects
				(font
					(size 0.7 0.7)
					(thickness 0.15)
				)
				(justify right top)
			)
		)
		(pad "1" smd roundrect
			(at -0.48 0 270)
			(size 0.59 0.64)
			(layers "F.Cu" "F.Mask" "F.Paste")
			(roundrect_rratio 0.25)
			(net 1 "GND")
			(pintype "passive")
		)
		(pad "2" smd roundrect
			(at 0.48 0 270)
			(size 0.59 0.64)
			(layers "F.Cu" "F.Mask" "F.Paste")
			(roundrect_rratio 0.25)
			(net 282 "+1V15")
			(pintype "passive")
		)
	)
	(footprint "antmicro-footprints:R_0402_1005Metric"
		(layer "F.Cu")
		(at 133.8 56.27 -90)
		(descr "Resistor SMD 0402")
		(tags "resistor SMD 0402")
		(property "Reference" "R75"
			(at 0.26 -10.78 90)
			(layer "F.SilkS")
			(effects
				(font
					(size 0.7 0.7)
					(thickness 0.15)
				)
				(justify right top)
			)
		)
		(property "Value" "R_49k9_0402"
			(at -1.011843 1.772047 90)
			(layer "F.Fab")
			(effects
				(font
					(size 0.7 0.7)
					(thickness 0.15)
				)
				(justify right top)
			)
		)
		(property "Datasheet" "https://www.bourns.com/docs/product-datasheets/cr.pdf"
			(at 0 0 90)
			(layer "F.Fab")
			(hide yes)
			(effects
				(font
					(size 1.27 1.27)
					(thickness 0.15)
				)
			)
		)
		(property "Description" "SMD Chip Resistor, 49.9 kohm, ± 1%, 63 mW, 0402 [1005 Metric], Thick Film, General Purpose"
			(at 0 0 90)
			(layer "F.Fab")
			(hide yes)
			(effects
				(font
					(size 1.27 1.27)
					(thickness 0.15)
				)
			)
		)
		(property "MPN" "CR0402-FX-4992GLF"
			(at 0 0 270)
			(unlocked yes)
			(layer "F.Fab")
			(hide yes)
			(effects
				(font
					(size 1 1)
					(thickness 0.15)
				)
			)
		)
		(property "Manufacturer" "Bourns"
			(at 0 0 270)
			(unlocked yes)
			(layer "F.Fab")
			(hide yes)
			(effects
				(font
					(size 1 1)
					(thickness 0.15)
				)
			)
		)
		(property "License" "Apache-2.0"
			(at 0 0 270)
			(unlocked yes)
			(layer "F.Fab")
			(hide yes)
			(effects
				(font
					(size 1 1)
					(thickness 0.15)
				)
			)
		)
		(property "Author" "Antmicro"
			(at 0 0 270)
			(unlocked yes)
			(layer "F.Fab")
			(hide yes)
			(effects
				(font
					(size 1 1)
					(thickness 0.15)
				)
			)
		)
		(property "Val" "49k9"
			(at 0 0 270)
			(unlocked yes)
			(layer "F.Fab")
			(hide yes)
			(effects
				(font
					(size 1 1)
					(thickness 0.15)
				)
			)
		)
		(property "Tolerance" "1%"
			(at 0 0 270)
			(unlocked yes)
			(layer "F.Fab")
			(hide yes)
			(effects
				(font
					(size 1 1)
					(thickness 0.15)
				)
			)
		)
		(sheetname "/DCDC/")
		(sheetfile "dcdc.kicad_sch")
		(attr smd)
		(fp_rect
			(start -0.925 -0.47)
			(end 0.925 0.47)
			(stroke
				(width 0.05)
				(type default)
			)
			(fill no)
			(layer "F.CrtYd")
		)
		(fp_rect
			(start -0.5 -0.25)
			(end 0.5 0.25)
			(stroke
				(width 0.15)
				(type solid)
			)
			(fill no)
			(layer "F.Fab")
		)
		(fp_text user "License: Apache-2.0"
			(at -0.95 5.169 90)
			(layer "F.Fab")
			(effects
				(font
					(size 0.7 0.7)
					(thickness 0.15)
				)
				(justify right top)
			)
		)
		(fp_text user "Author: Antmicro"
			(at -0.95 4.169 90)
			(layer "F.Fab")
			(effects
				(font
					(size 0.7 0.7)
					(thickness 0.15)
				)
				(justify right top)
			)
		)
		(fp_text user "${REFERENCE}"
			(at -0.95 3.168 90)
			(layer "F.Fab")
			(effects
				(font
					(size 0.7 0.7)
					(thickness 0.15)
				)
				(justify right top)
			)
		)
		(pad "1" smd roundrect
			(at -0.48 0 270)
			(size 0.59 0.64)
			(layers "F.Cu" "F.Mask" "F.Paste")
			(roundrect_rratio 0.25)
			(net 1305 "/DCDC/5V_{AON}_EN")
			(pintype "passive")
		)
		(pad "2" smd roundrect
			(at 0.48 0 270)
			(size 0.59 0.64)
			(layers "F.Cu" "F.Mask" "F.Paste")
			(roundrect_rratio 0.25)
			(net 13 "VCC")
			(pintype "passive")
		)
	)
	(footprint "antmicro-footprints:C_0402_1005Metric"
		(layer "F.Cu")
		(at 92 65.45)
		(descr "Capacitor SMD 0402")
		(tags "capacitor SMD 0402")
		(property "Reference" "C404"
			(at -0.4 1.3 0)
			(layer "F.SilkS")
			(effects
				(font
					(size 0.7 0.7)
					(thickness 0.15)
				)
				(justify left bottom)
			)
		)
		(property "Value" "C_1u_25V_0402"
			(at -1.022927 2.155213 0)
			(layer "F.Fab")
			(effects
				(font
					(size 0.7 0.7)
					(thickness 0.15)
				)
				(justify left bottom)
			)
		)
		(property "Datasheet" "https://www.murata.com/products/productdetail?partno=GRM155R61E105KE11%23"
			(at 0 0 0)
			(layer "F.Fab")
			(hide yes)
			(effects
				(font
					(size 1.27 1.27)
					(thickness 0.15)
				)
			)
		)
		(property "Description" "SMD Multilayer Ceramic Capacitor, 1 µF, 25 V, 0402 [1005 Metric], ± 10%, X5R, GRM Series"
			(at 0 0 0)
			(layer "F.Fab")
			(hide yes)
			(effects
				(font
					(size 1.27 1.27)
					(thickness 0.15)
				)
			)
		)
		(property "MPN" "GRM155R61E105KE11J"
			(at 0 0 0)
			(unlocked yes)
			(layer "F.Fab")
			(hide yes)
			(effects
				(font
					(size 1 1)
					(thickness 0.15)
				)
			)
		)
		(property "Manufacturer" "Murata"
			(at 0 0 0)
			(unlocked yes)
			(layer "F.Fab")
			(hide yes)
			(effects
				(font
					(size 1 1)
					(thickness 0.15)
				)
			)
		)
		(property "License" "Apache-2.0"
			(at 0 0 0)
			(unlocked yes)
			(layer "F.Fab")
			(hide yes)
			(effects
				(font
					(size 1 1)
					(thickness 0.15)
				)
			)
		)
		(property "Author" "Antmicro"
			(at 0 0 0)
			(unlocked yes)
			(layer "F.Fab")
			(hide yes)
			(effects
				(font
					(size 1 1)
					(thickness 0.15)
				)
			)
		)
		(property "Val" "1u"
			(at 0 0 0)
			(unlocked yes)
			(layer "F.Fab")
			(hide yes)
			(effects
				(font
					(size 1 1)
					(thickness 0.15)
				)
			)
		)
		(property "Voltage" "25V"
			(at 0 0 0)
			(unlocked yes)
			(layer "F.Fab")
			(hide yes)
			(effects
				(font
					(size 1 1)
					(thickness 0.15)
				)
			)
		)
		(property "Dielectric" "X5R"
			(at 0 0 0)
			(unlocked yes)
			(layer "F.Fab")
			(hide yes)
			(effects
				(font
					(size 1 1)
					(thickness 0.15)
				)
			)
		)
		(sheetname "/SoM_Power/")
		(sheetfile "som_power.kicad_sch")
		(attr smd)
		(fp_poly
			(pts
				(xy -0.925 -0.47) (xy 0.925 -0.47) (xy 0.925 0.47) (xy -0.925 0.47)
			)
			(stroke
				(width 0.05)
				(type default)
			)
			(fill no)
			(layer "F.CrtYd")
		)
		(fp_line
			(start -0.494 -0.25)
			(end 0.504 -0.25)
			(stroke
				(width 0.15)
				(type solid)
			)
			(layer "F.Fab")
		)
		(fp_line
			(start -0.494 0.248)
			(end -0.494 -0.25)
			(stroke
				(width 0.15)
				(type solid)
			)
			(layer "F.Fab")
		)
		(fp_line
			(start 0.504 -0.25)
			(end 0.504 0.248)
			(stroke
				(width 0.15)
				(type solid)
			)
			(layer "F.Fab")
		)
		(fp_line
			(start 0.504 0.248)
			(end -0.494 0.248)
			(stroke
				(width 0.15)
				(type solid)
			)
			(layer "F.Fab")
		)
		(fp_text user "${REFERENCE}"
			(at -0.939 4.599 0)
			(layer "F.Fab")
			(effects
				(font
					(size 0.7 0.7)
					(thickness 0.15)
				)
				(justify left bottom)
			)
		)
		(fp_text user "Author: Antmicro"
			(at -0.939 3.399 0)
			(layer "F.Fab")
			(effects
				(font
					(size 0.7 0.7)
					(thickness 0.15)
				)
				(justify left bottom)
			)
		)
		(fp_text user "License: Apache-2.0"
			(at -0.939 5.799 0)
			(layer "F.Fab")
			(effects
				(font
					(size 0.7 0.7)
					(thickness 0.15)
				)
				(justify left bottom)
			)
		)
		(pad "1" smd roundrect
			(at -0.48 0)
			(size 0.59 0.64)
			(layers "F.Cu" "F.Mask" "F.Paste")
			(roundrect_rratio 0.25)
			(net 1 "GND")
			(pintype "passive")
		)
		(pad "2" smd roundrect
			(at 0.48 0)
			(size 0.59 0.64)
			(layers "F.Cu" "F.Mask" "F.Paste")
			(roundrect_rratio 0.25)
			(net 1285 "/SoM_Power/VIN_PWR_ON")
			(pintype "passive")
		)
	)
	(footprint "antmicro-footprints:C_0402_1005Metric"
		(layer "F.Cu")
		(at 218.8 117.9 180)
		(descr "Capacitor SMD 0402")
		(tags "capacitor SMD 0402")
		(property "Reference" "C112"
			(at -1.005 2.4 0)
			(layer "F.SilkS")
			(effects
				(font
					(size 0.7 0.7)
					(thickness 0.15)
				)
				(justify right top)
			)
		)
		(property "Value" "C_100n_0402"
			(at -1.022927 2.155213 0)
			(layer "F.Fab")
			(effects
				(font
					(size 0.7 0.7)
					(thickness 0.15)
				)
				(justify right top)
			)
		)
		(property "Datasheet" "https://www.murata.com/products/productdetail?partno=GRM155R61H104KE14%23"
			(at 0 0 0)
			(layer "F.Fab")
			(hide yes)
			(effects
				(font
					(size 1.27 1.27)
					(thickness 0.15)
				)
			)
		)
		(property "Description" "SMD Multilayer Ceramic Capacitor, 0.1 µF, 50 V, 0402 [1005 Metric], ± 10%, X5R, GRM Series"
			(at 0 0 0)
			(layer "F.Fab")
			(hide yes)
			(effects
				(font
					(size 1.27 1.27)
					(thickness 0.15)
				)
			)
		)
		(property "Manufacturer" "Murata"
			(at 0 0 180)
			(unlocked yes)
			(layer "F.Fab")
			(hide yes)
			(effects
				(font
					(size 1 1)
					(thickness 0.15)
				)
			)
		)
		(property "MPN" "GRM155R61H104KE14D"
			(at 0 0 180)
			(unlocked yes)
			(layer "F.Fab")
			(hide yes)
			(effects
				(font
					(size 1 1)
					(thickness 0.15)
				)
			)
		)
		(property "Val" "100n"
			(at 0 0 180)
			(unlocked yes)
			(layer "F.Fab")
			(hide yes)
			(effects
				(font
					(size 1 1)
					(thickness 0.15)
				)
			)
		)
		(property "License" "Apache-2.0"
			(at 0 0 180)
			(unlocked yes)
			(layer "F.Fab")
			(hide yes)
			(effects
				(font
					(size 1 1)
					(thickness 0.15)
				)
			)
		)
		(property "Author" "Antmicro"
			(at 0 0 180)
			(unlocked yes)
			(layer "F.Fab")
			(hide yes)
			(effects
				(font
					(size 1 1)
					(thickness 0.15)
				)
			)
		)
		(property "Voltage" "50V"
			(at 0 0 180)
			(unlocked yes)
			(layer "F.Fab")
			(hide yes)
			(effects
				(font
					(size 1 1)
					(thickness 0.15)
				)
			)
		)
		(property "Dielectric" "X5R"
			(at 0 0 180)
			(unlocked yes)
			(layer "F.Fab")
			(hide yes)
			(effects
				(font
					(size 1 1)
					(thickness 0.15)
				)
			)
		)
		(sheetname "/USB Hub/")
		(sheetfile "usb_hub.kicad_sch")
		(attr smd)
		(fp_rect
			(start -0.925 -0.47)
			(end 0.925 0.47)
			(stroke
				(width 0.05)
				(type default)
			)
			(fill no)
			(layer "F.CrtYd")
		)
		(fp_line
			(start 0.504 0.248)
			(end -0.494 0.248)
			(stroke
				(width 0.15)
				(type solid)
			)
			(layer "F.Fab")
		)
		(fp_line
			(start 0.504 -0.25)
			(end 0.504 0.248)
			(stroke
				(width 0.15)
				(type solid)
			)
			(layer "F.Fab")
		)
		(fp_line
			(start -0.494 0.248)
			(end -0.494 -0.25)
			(stroke
				(width 0.15)
				(type solid)
			)
			(layer "F.Fab")
		)
		(fp_line
			(start -0.494 -0.25)
			(end 0.504 -0.25)
			(stroke
				(width 0.15)
				(type solid)
			)
			(layer "F.Fab")
		)
		(fp_text user "Author: Antmicro"
			(at -0.939 3.399 0)
			(layer "F.Fab")
			(effects
				(font
					(size 0.7 0.7)
					(thickness 0.15)
				)
				(justify right top)
			)
		)
		(fp_text user "${REFERENCE}"
			(at -0.939 4.599 0)
			(layer "F.Fab")
			(effects
				(font
					(size 0.7 0.7)
					(thickness 0.15)
				)
				(justify right top)
			)
		)
		(fp_text user "License: Apache-2.0"
			(at -0.939 5.799 0)
			(layer "F.Fab")
			(effects
				(font
					(size 0.7 0.7)
					(thickness 0.15)
				)
				(justify right top)
			)
		)
		(pad "1" smd roundrect
			(at -0.48 0 180)
			(size 0.59 0.64)
			(layers "F.Cu" "F.Mask" "F.Paste")
			(roundrect_rratio 0.25)
			(net 164 "/USB Hub/USBC3_CONN_TX1_P")
			(pintype "passive")
		)
		(pad "2" smd roundrect
			(at 0.48 0 180)
			(size 0.59 0.64)
			(layers "F.Cu" "F.Mask" "F.Paste")
			(roundrect_rratio 0.25)
			(net 283 "/USB Hub/USBC3_TX_{1}-")
			(pintype "passive")
		)
	)
	(footprint "antmicro-footprints:C_0402_1005Metric"
		(layer "F.Cu")
		(at 125.569999 64.88 180)
		(descr "Capacitor SMD 0402")
		(tags "capacitor SMD 0402")
		(property "Reference" "C376"
			(at -0.990001 -0.6 0)
			(layer "F.SilkS")
			(effects
				(font
					(size 0.7 0.7)
					(thickness 0.15)
				)
				(justify right top)
			)
		)
		(property "Value" "C_4u7_25V_0402"
			(at -1.022927 2.155213 0)
			(layer "F.Fab")
			(effects
				(font
					(size 0.7 0.7)
					(thickness 0.15)
				)
				(justify right top)
			)
		)
		(property "Datasheet" "https://www.murata.com/products/productdetail?partno=GRM155C61E475ME15%23"
			(at 0 0 0)
			(layer "F.Fab")
			(hide yes)
			(effects
				(font
					(size 1.27 1.27)
					(thickness 0.15)
				)
			)
		)
		(property "Description" "SMD Multilayer Ceramic Capacitor"
			(at 0 0 0)
			(layer "F.Fab")
			(hide yes)
			(effects
				(font
					(size 1.27 1.27)
					(thickness 0.15)
				)
			)
		)
		(property "MPN" "GRM155C61E475ME15J"
			(at 0 0 180)
			(unlocked yes)
			(layer "F.Fab")
			(hide yes)
			(effects
				(font
					(size 1 1)
					(thickness 0.15)
				)
			)
		)
		(property "Manufacturer" "Murata"
			(at 0 0 180)
			(unlocked yes)
			(layer "F.Fab")
			(hide yes)
			(effects
				(font
					(size 1 1)
					(thickness 0.15)
				)
			)
		)
		(property "License" "Apache-2.0"
			(at 0 0 180)
			(unlocked yes)
			(layer "F.Fab")
			(hide yes)
			(effects
				(font
					(size 1 1)
					(thickness 0.15)
				)
			)
		)
		(property "Author" "Antmicro"
			(at 0 0 180)
			(unlocked yes)
			(layer "F.Fab")
			(hide yes)
			(effects
				(font
					(size 1 1)
					(thickness 0.15)
				)
			)
		)
		(property "Val" "4u7"
			(at 0 0 180)
			(unlocked yes)
			(layer "F.Fab")
			(hide yes)
			(effects
				(font
					(size 1 1)
					(thickness 0.15)
				)
			)
		)
		(property "Voltage" "25V"
			(at 0 0 180)
			(unlocked yes)
			(layer "F.Fab")
			(hide yes)
			(effects
				(font
					(size 1 1)
					(thickness 0.15)
				)
			)
		)
		(property "Dielectric" "X5S"
			(at 0 0 180)
			(unlocked yes)
			(layer "F.Fab")
			(hide yes)
			(effects
				(font
					(size 1 1)
					(thickness 0.15)
				)
			)
		)
		(sheetname "/DCDC/")
		(sheetfile "dcdc.kicad_sch")
		(attr smd)
		(fp_poly
			(pts
				(xy -0.925 -0.47) (xy -0.925 0.47) (xy 0.925 0.47) (xy 0.925 -0.47)
			)
			(stroke
				(width 0.05)
				(type default)
			)
			(fill no)
			(layer "F.CrtYd")
		)
		(fp_line
			(start 0.504 0.248)
			(end -0.494 0.248)
			(stroke
				(width 0.15)
				(type solid)
			)
			(layer "F.Fab")
		)
		(fp_line
			(start 0.504 -0.25)
			(end 0.504 0.248)
			(stroke
				(width 0.15)
				(type solid)
			)
			(layer "F.Fab")
		)
		(fp_line
			(start -0.494 0.248)
			(end -0.494 -0.25)
			(stroke
				(width 0.15)
				(type solid)
			)
			(layer "F.Fab")
		)
		(fp_line
			(start -0.494 -0.25)
			(end 0.504 -0.25)
			(stroke
				(width 0.15)
				(type solid)
			)
			(layer "F.Fab")
		)
		(fp_text user "${REFERENCE}"
			(at -0.939 4.599 0)
			(layer "F.Fab")
			(effects
				(font
					(size 0.7 0.7)
					(thickness 0.15)
				)
				(justify right top)
			)
		)
		(fp_text user "License: Apache-2.0"
			(at -0.939 5.799 0)
			(layer "F.Fab")
			(effects
				(font
					(size 0.7 0.7)
					(thickness 0.15)
				)
				(justify right top)
			)
		)
		(fp_text user "Author: Antmicro"
			(at -0.939 3.399 0)
			(layer "F.Fab")
			(effects
				(font
					(size 0.7 0.7)
					(thickness 0.15)
				)
				(justify right top)
			)
		)
		(pad "1" smd roundrect
			(at -0.48 0 180)
			(size 0.59 0.64)
			(layers "F.Cu" "F.Mask" "F.Paste")
			(roundrect_rratio 0.25)
			(net 1 "GND")
			(pintype "passive")
		)
		(pad "2" smd roundrect
			(at 0.48 0 180)
			(size 0.59 0.64)
			(layers "F.Cu" "F.Mask" "F.Paste")
			(roundrect_rratio 0.25)
			(net 1275 "/DCDC/5V_{AON}_VDRV")
			(pintype "passive")
		)
	)
	(footprint "antmicro-footprints:R_0402_1005Metric"
		(layer "F.Cu")
		(at 132.465349 62.97 180)
		(descr "Resistor SMD 0402")
		(tags "resistor SMD 0402")
		(property "Reference" "R311"
			(at -0.844651 -1.31 0)
			(layer "F.SilkS")
			(effects
				(font
					(size 0.7 0.7)
					(thickness 0.15)
				)
				(justify left bottom)
			)
		)
		(property "Value" "R_100k_0402"
			(at -1.011843 1.772046 0)
			(layer "F.Fab")
			(effects
				(font
					(size 0.7 0.7)
					(thickness 0.15)
				)
				(justify right top)
			)
		)
		(property "Datasheet" "https://www.bourns.com/docs/product-datasheets/cr.pdf"
			(at 0 0 0)
			(layer "F.Fab")
			(hide yes)
			(effects
				(font
					(size 1.27 1.27)
					(thickness 0.15)
				)
			)
		)
		(property "Description" "SMD Chip Resistor, 100 kohm, ± 1%, 62.5 mW, 0402 [1005 Metric], Thick Film, General Purpose"
			(at 0 0 0)
			(layer "F.Fab")
			(hide yes)
			(effects
				(font
					(size 1.27 1.27)
					(thickness 0.15)
				)
			)
		)
		(property "MPN" "CR0402-FX-1003GLF"
			(at 0 0 180)
			(unlocked yes)
			(layer "F.Fab")
			(hide yes)
			(effects
				(font
					(size 1 1)
					(thickness 0.15)
				)
			)
		)
		(property "Manufacturer" "Bourns"
			(at 0 0 180)
			(unlocked yes)
			(layer "F.Fab")
			(hide yes)
			(effects
				(font
					(size 1 1)
					(thickness 0.15)
				)
			)
		)
		(property "License" "Apache-2.0"
			(at 0 0 180)
			(unlocked yes)
			(layer "F.Fab")
			(hide yes)
			(effects
				(font
					(size 1 1)
					(thickness 0.15)
				)
			)
		)
		(property "Author" "Antmicro"
			(at 0 0 180)
			(unlocked yes)
			(layer "F.Fab")
			(hide yes)
			(effects
				(font
					(size 1 1)
					(thickness 0.15)
				)
			)
		)
		(property "Val" "100k"
			(at 0 0 180)
			(unlocked yes)
			(layer "F.Fab")
			(hide yes)
			(effects
				(font
					(size 1 1)
					(thickness 0.15)
				)
			)
		)
		(property "Tolerance" "1%"
			(at 0 0 180)
			(unlocked yes)
			(layer "F.Fab")
			(hide yes)
			(effects
				(font
					(size 1 1)
					(thickness 0.15)
				)
			)
		)
		(sheetname "/DCDC/")
		(sheetfile "dcdc.kicad_sch")
		(attr smd)
		(fp_poly
			(pts
				(xy -0.925 -0.47) (xy 0.925 -0.47) (xy 0.925 0.47) (xy -0.925 0.47)
			)
			(stroke
				(width 0.05)
				(type default)
			)
			(fill no)
			(layer "F.CrtYd")
		)
		(fp_poly
			(pts
				(xy -0.5 -0.25) (xy 0.5 -0.25) (xy 0.5 0.25) (xy -0.5 0.25)
			)
			(stroke
				(width 0.15)
				(type solid)
			)
			(fill no)
			(layer "F.Fab")
		)
		(fp_text user "Author: Antmicro"
			(at -0.95 4.169 0)
			(layer "F.Fab")
			(effects
				(font
					(size 0.7 0.7)
					(thickness 0.15)
				)
				(justify right top)
			)
		)
		(fp_text user "${REFERENCE}"
			(at -0.95 3.168 0)
			(layer "F.Fab")
			(effects
				(font
					(size 0.7 0.7)
					(thickness 0.15)
				)
				(justify right top)
			)
		)
		(fp_text user "License: Apache-2.0"
			(at -0.949999 5.169 0)
			(layer "F.Fab")
			(effects
				(font
					(size 0.7 0.7)
					(thickness 0.15)
				)
				(justify right top)
			)
		)
		(pad "1" smd roundrect
			(at -0.48 0 180)
			(size 0.59 0.64)
			(layers "F.Cu" "F.Mask" "F.Paste")
			(roundrect_rratio 0.25)
			(net 1 "GND")
			(pintype "passive")
		)
		(pad "2" smd roundrect
			(at 0.48 0 180)
			(size 0.59 0.64)
			(layers "F.Cu" "F.Mask" "F.Paste")
			(roundrect_rratio 0.25)
			(net 1307 "/DCDC/5V_{AON}_MODE2")
			(pintype "passive")
		)
	)
	(footprint "antmicro-footprints:LED_0603_1608Metric_G"
		(layer "F.Cu")
		(at 182 55.32 -90)
		(descr "LED SMD 0603 Green")
		(tags "LED SMD 0603 Green")
		(property "Reference" "D6"
			(at -0.28 1.47 90)
			(layer "F.SilkS")
			(effects
				(font
					(size 0.7 0.7)
					(thickness 0.15)
				)
				(justify right top)
			)
		)
		(property "Value" "LED_G_0603_LTST-C190GKT"
			(at -0.001 1.599 90)
			(layer "F.Fab")
			(effects
				(font
					(size 0.7 0.7)
					(thickness 0.15)
				)
				(justify right top)
			)
		)
		(property "Datasheet" "https://media.digikey.com/pdf/Data%20Sheets/Lite-On%20PDFs/LTST-C190GKT.pdf"
			(at 0 0 90)
			(layer "F.Fab")
			(hide yes)
			(effects
				(font
					(size 1.27 1.27)
					(thickness 0.15)
				)
			)
		)
		(property "Description" "LED, Green, SMD, 0603, 20 mA, 2.1 V, 569 nm"
			(at 0 0 90)
			(layer "F.Fab")
			(hide yes)
			(effects
				(font
					(size 1.27 1.27)
					(thickness 0.15)
				)
			)
		)
		(property "MPN" "LTST-C190GKT"
			(at 0 0 270)
			(unlocked yes)
			(layer "F.Fab")
			(hide yes)
			(effects
				(font
					(size 1 1)
					(thickness 0.15)
				)
			)
		)
		(property "Manufacturer" "Lite-On"
			(at 0 0 270)
			(unlocked yes)
			(layer "F.Fab")
			(hide yes)
			(effects
				(font
					(size 1 1)
					(thickness 0.15)
				)
			)
		)
		(property "Author" "Antmicro"
			(at 0 0 270)
			(unlocked yes)
			(layer "F.Fab")
			(hide yes)
			(effects
				(font
					(size 1 1)
					(thickness 0.15)
				)
			)
		)
		(property "License" "Apache-2.0"
			(at 0 0 270)
			(unlocked yes)
			(layer "F.Fab")
			(hide yes)
			(effects
				(font
					(size 1 1)
					(thickness 0.15)
				)
			)
		)
		(property "Color" "Green"
			(at 0 0 270)
			(unlocked yes)
			(layer "F.Fab")
			(hide yes)
			(effects
				(font
					(size 1 1)
					(thickness 0.15)
				)
			)
		)
		(sheetname "/Power/")
		(sheetfile "power.kicad_sch")
		(attr smd)
		(fp_line
			(start 0.22 0.35)
			(end -0.22 0.35)
			(stroke
				(width 0.15)
				(type solid)
			)
			(layer "F.SilkS")
		)
		(fp_line
			(start -0.094672 0.201008)
			(end -0.094672 -0.198992)
			(stroke
				(width 0.1)
				(type solid)
			)
			(layer "F.SilkS")
		)
		(fp_line
			(start 0.105328 0.201008)
			(end -0.094672 0.001008)
			(stroke
				(width 0.1)
				(type solid)
			)
			(layer "F.SilkS")
		)
		(fp_line
			(start 0.105328 0.201008)
			(end 0.105328 -0.198992)
			(stroke
				(width 0.1)
				(type solid)
			)
			(layer "F.SilkS")
		)
		(fp_line
			(start -0.094672 0.001008)
			(end -0.24 0.001008)
			(stroke
				(width 0.1)
				(type solid)
			)
			(layer "F.SilkS")
		)
		(fp_line
			(start -0.094672 0.001008)
			(end 0.105328 -0.198992)
			(stroke
				(width 0.1)
				(type solid)
			)
			(layer "F.SilkS")
		)
		(fp_line
			(start 0.105328 0.001008)
			(end 0.24 0.001)
			(stroke
				(width 0.1)
				(type solid)
			)
			(layer "F.SilkS")
		)
		(fp_line
			(start -1.18 -0.319)
			(end -1.18 0.321)
			(stroke
				(width 0.15)
				(type solid)
			)
			(layer "F.SilkS")
		)
		(fp_line
			(start 0.22 -0.35)
			(end -0.22 -0.35)
			(stroke
				(width 0.15)
				(type solid)
			)
			(layer "F.SilkS")
		)
		(fp_rect
			(start 1.25 0.65)
			(end -1.25 -0.65)
			(stroke
				(width 0.05)
				(type solid)
			)
			(fill no)
			(layer "F.CrtYd")
		)
		(fp_line
			(start -0.199 0.2)
			(end -0.199 0.1)
			(stroke
				(width 0.15)
				(type solid)
			)
			(layer "F.Fab")
		)
		(fp_line
			(start 0.201 0.2)
			(end 0.201 0)
			(stroke
				(width 0.15)
				(type solid)
			)
			(layer "F.Fab")
		)
		(fp_line
			(start -0.199 0)
			(end -0.597 0)
			(stroke
				(width 0.15)
				(type solid)
			)
			(layer "F.Fab")
		)
		(fp_line
			(start -0.101 0)
			(end 0.201 0.2)
			(stroke
				(width 0.15)
				(type solid)
			)
			(layer "F.Fab")
		)
		(fp_line
			(start 0.201 0)
			(end 0.201 -0.202)
			(stroke
				(width 0.15)
				(type solid)
			)
			(layer "F.Fab")
		)
		(fp_line
			(start 0.599 0)
			(end 0.201 0)
			(stroke
				(width 0.15)
				(type solid)
			)
			(layer "F.Fab")
		)
		(fp_line
			(start -0.199 -0.202)
			(end -0.199 0.1)
			(stroke
				(width 0.15)
				(type solid)
			)
			(layer "F.Fab")
		)
		(fp_line
			(start 0.201 -0.202)
			(end -0.101 0)
			(stroke
				(width 0.15)
				(type solid)
			)
			(layer "F.Fab")
		)
		(fp_rect
			(start 0.848 0.4)
			(end -0.85 -0.402)
			(stroke
				(width 0.15)
				(type solid)
			)
			(fill no)
			(layer "F.Fab")
		)
		(fp_text user "${REFERENCE}"
			(at -1.4224 5.999 90)
			(layer "F.Fab")
			(effects
				(font
					(size 0.7 0.7)
					(thickness 0.15)
				)
				(justify right top)
			)
		)
		(fp_text user "License: Apache-2.0"
			(at -1.4224 3.599 90)
			(layer "F.Fab")
			(effects
				(font
					(size 0.7 0.7)
					(thickness 0.15)
				)
				(justify right top)
			)
		)
		(fp_text user "Author: Antmicro"
			(at -1.4224 4.799 90)
			(layer "F.Fab")
			(effects
				(font
					(size 0.7 0.7)
					(thickness 0.15)
				)
				(justify right top)
			)
		)
		(pad "1" smd roundrect
			(at -0.7 0 90)
			(size 0.8 1)
			(layers "F.Cu" "F.Mask" "F.Paste")
			(roundrect_rratio 0.2)
			(net 1 "GND")
			(pinfunction "C")
			(pintype "passive")
		)
		(pad "2" smd roundrect
			(at 0.7 0 90)
			(size 0.8 1)
			(layers "F.Cu" "F.Mask" "F.Paste")
			(roundrect_rratio 0.2)
			(net 1108 "Net-(D6-A)")
			(pinfunction "A")
			(pintype "passive")
		)
	)
	(footprint "antmicro-footprints:C_0402_1005Metric"
		(layer "F.Cu")
		(at 206.75 88.470856 180)
		(descr "Capacitor SMD 0402")
		(tags "capacitor SMD 0402")
		(property "Reference" "C316"
			(at -0.95 -0.429144 180)
			(layer "F.SilkS")
			(effects
				(font
					(size 0.7 0.7)
					(thickness 0.15)
				)
				(justify left bottom)
			)
		)
		(property "Value" "C_100n_0402"
			(at -1.022927 2.155213 180)
			(layer "F.Fab")
			(effects
				(font
					(size 0.7 0.7)
					(thickness 0.15)
				)
				(justify left bottom)
			)
		)
		(property "Datasheet" "https://www.murata.com/products/productdetail?partno=GRM155R61H104KE14%23"
			(at 0 0 180)
			(layer "F.Fab")
			(hide yes)
			(effects
				(font
					(size 1.27 1.27)
					(thickness 0.15)
				)
			)
		)
		(property "Description" "SMD Multilayer Ceramic Capacitor, 0.1 µF, 50 V, 0402 [1005 Metric], ± 10%, X5R, GRM Series"
			(at 0 0 180)
			(layer "F.Fab")
			(hide yes)
			(effects
				(font
					(size 1.27 1.27)
					(thickness 0.15)
				)
			)
		)
		(property "Manufacturer" "Murata"
			(at 0 0 180)
			(unlocked yes)
			(layer "F.Fab")
			(hide yes)
			(effects
				(font
					(size 1 1)
					(thickness 0.15)
				)
			)
		)
		(property "MPN" "GRM155R61H104KE14D"
			(at 0 0 180)
			(unlocked yes)
			(layer "F.Fab")
			(hide yes)
			(effects
				(font
					(size 1 1)
					(thickness 0.15)
				)
			)
		)
		(property "Val" "100n"
			(at 0 0 180)
			(unlocked yes)
			(layer "F.Fab")
			(hide yes)
			(effects
				(font
					(size 1 1)
					(thickness 0.15)
				)
			)
		)
		(property "License" "Apache-2.0"
			(at 0 0 180)
			(unlocked yes)
			(layer "F.Fab")
			(hide yes)
			(effects
				(font
					(size 1 1)
					(thickness 0.15)
				)
			)
		)
		(property "Author" "Antmicro"
			(at 0 0 180)
			(unlocked yes)
			(layer "F.Fab")
			(hide yes)
			(effects
				(font
					(size 1 1)
					(thickness 0.15)
				)
			)
		)
		(property "Voltage" "50V"
			(at 0 0 180)
			(unlocked yes)
			(layer "F.Fab")
			(hide yes)
			(effects
				(font
					(size 1 1)
					(thickness 0.15)
				)
			)
		)
		(property "Dielectric" "X5R"
			(at 0 0 180)
			(unlocked yes)
			(layer "F.Fab")
			(hide yes)
			(effects
				(font
					(size 1 1)
					(thickness 0.15)
				)
			)
		)
		(sheetname "/SoM_IO2/")
		(sheetfile "som_io2.kicad_sch")
		(attr smd)
		(fp_rect
			(start -0.925 -0.47)
			(end 0.925 0.47)
			(stroke
				(width 0.05)
				(type default)
			)
			(fill no)
			(layer "F.CrtYd")
		)
		(fp_line
			(start 0.504 0.248)
			(end -0.494 0.248)
			(stroke
				(width 0.15)
				(type solid)
			)
			(layer "F.Fab")
		)
		(fp_line
			(start 0.504 -0.25)
			(end 0.504 0.248)
			(stroke
				(width 0.15)
				(type solid)
			)
			(layer "F.Fab")
		)
		(fp_line
			(start -0.494 0.248)
			(end -0.494 -0.25)
			(stroke
				(width 0.15)
				(type solid)
			)
			(layer "F.Fab")
		)
		(fp_line
			(start -0.494 -0.25)
			(end 0.504 -0.25)
			(stroke
				(width 0.15)
				(type solid)
			)
			(layer "F.Fab")
		)
		(fp_text user "${REFERENCE}"
			(at -0.939 4.599 180)
			(layer "F.Fab")
			(effects
				(font
					(size 0.7 0.7)
					(thickness 0.15)
				)
				(justify left bottom)
			)
		)
		(fp_text user "License: Apache-2.0"
			(at -0.939 5.799 180)
			(layer "F.Fab")
			(effects
				(font
					(size 0.7 0.7)
					(thickness 0.15)
				)
				(justify left bottom)
			)
		)
		(fp_text user "Author: Antmicro"
			(at -0.939 3.399 180)
			(layer "F.Fab")
			(effects
				(font
					(size 0.7 0.7)
					(thickness 0.15)
				)
				(justify left bottom)
			)
		)
		(pad "1" smd roundrect
			(at -0.48 0 180)
			(size 0.59 0.64)
			(layers "F.Cu" "F.Mask" "F.Paste")
			(roundrect_rratio 0.25)
			(net 612 "/SoM_IO2/DP0.TX1+")
			(pintype "passive")
		)
		(pad "2" smd roundrect
			(at 0.48 0 180)
			(size 0.59 0.64)
			(layers "F.Cu" "F.Mask" "F.Paste")
			(roundrect_rratio 0.25)
			(net 596 "/SoM_IO2/DP0.TX1_C+")
			(pintype "passive")
		)
	)
	(footprint "antmicro-footprints:R_0402_1005Metric"
		(layer "F.Cu")
		(at 138.2 104.8 -90)
		(descr "Resistor SMD 0402")
		(tags "resistor SMD 0402")
		(property "Reference" "R345"
			(at -3.8 0.3 90)
			(layer "F.SilkS")
			(effects
				(font
					(size 0.7 0.7)
					(thickness 0.15)
				)
				(justify right top)
			)
		)
		(property "Value" "R_0R_0402"
			(at -1.011843 1.772047 90)
			(layer "F.Fab")
			(effects
				(font
					(size 0.7 0.7)
					(thickness 0.15)
				)
				(justify right top)
			)
		)
		(property "Datasheet" "https://industrial.panasonic.com/cdbs/www-data/pdf/RDA0000/AOA0000C301.pdf"
			(at 0 0 90)
			(layer "F.Fab")
			(hide yes)
			(effects
				(font
					(size 1.27 1.27)
					(thickness 0.15)
				)
			)
		)
		(property "Description" "SMD Chip Resistor, Jumper, 0 ohm, 100 mW, 0402 [1005 Metric], Thick Film, General Purpose"
			(at 0 0 90)
			(layer "F.Fab")
			(hide yes)
			(effects
				(font
					(size 1.27 1.27)
					(thickness 0.15)
				)
			)
		)
		(property "Manufacturer" "Panasonic"
			(at 0 0 270)
			(unlocked yes)
			(layer "F.Fab")
			(hide yes)
			(effects
				(font
					(size 1 1)
					(thickness 0.15)
				)
			)
		)
		(property "MPN" "ERJ2GE0R00X"
			(at 0 0 270)
			(unlocked yes)
			(layer "F.Fab")
			(hide yes)
			(effects
				(font
					(size 1 1)
					(thickness 0.15)
				)
			)
		)
		(property "Val" "0R"
			(at 0 0 270)
			(unlocked yes)
			(layer "F.Fab")
			(hide yes)
			(effects
				(font
					(size 1 1)
					(thickness 0.15)
				)
			)
		)
		(property "License" "Apache-2.0"
			(at 0 0 270)
			(unlocked yes)
			(layer "F.Fab")
			(hide yes)
			(effects
				(font
					(size 1 1)
					(thickness 0.15)
				)
			)
		)
		(property "Author" "Antmicro"
			(at 0 0 270)
			(unlocked yes)
			(layer "F.Fab")
			(hide yes)
			(effects
				(font
					(size 1 1)
					(thickness 0.15)
				)
			)
		)
		(property "Tolerance" "~"
			(at 0 0 270)
			(unlocked yes)
			(layer "F.Fab")
			(hide yes)
			(effects
				(font
					(size 1 1)
					(thickness 0.15)
				)
			)
		)
		(property "Current" "1A"
			(at 0 0 270)
			(unlocked yes)
			(layer "F.Fab")
			(hide yes)
			(effects
				(font
					(size 1 1)
					(thickness 0.15)
				)
			)
		)
		(sheetname "/Peripherals/")
		(sheetfile "peripherals.kicad_sch")
		(attr smd)
		(fp_rect
			(start -0.925 -0.47)
			(end 0.925 0.47)
			(stroke
				(width 0.05)
				(type default)
			)
			(fill no)
			(layer "F.CrtYd")
		)
		(fp_rect
			(start -0.5 -0.25)
			(end 0.5 0.25)
			(stroke
				(width 0.15)
				(type solid)
			)
			(fill no)
			(layer "F.Fab")
		)
		(fp_text user "License: Apache-2.0"
			(at -0.95 5.169 90)
			(layer "F.Fab")
			(effects
				(font
					(size 0.7 0.7)
					(thickness 0.15)
				)
				(justify right top)
			)
		)
		(fp_text user "${REFERENCE}"
			(at -0.95 3.168 90)
			(layer "F.Fab")
			(effects
				(font
					(size 0.7 0.7)
					(thickness 0.15)
				)
				(justify right top)
			)
		)
		(fp_text user "Author: Antmicro"
			(at -0.95 4.169 90)
			(layer "F.Fab")
			(effects
				(font
					(size 0.7 0.7)
					(thickness 0.15)
				)
				(justify right top)
			)
		)
		(pad "1" smd roundrect
			(at -0.48 0 270)
			(size 0.59 0.64)
			(layers "F.Cu" "F.Mask" "F.Paste")
			(roundrect_rratio 0.25)
			(net 1 "GND")
			(pintype "passive")
		)
		(pad "2" smd roundrect
			(at 0.48 0 270)
			(size 0.59 0.64)
			(layers "F.Cu" "F.Mask" "F.Paste")
			(roundrect_rratio 0.25)
			(net 1311 "Net-(U71-ADDR)")
			(pintype "passive")
		)
	)
	(footprint "antmicro-footprints:C_0402_1005Metric"
		(layer "F.Cu")
		(at 218.7 126.7 180)
		(descr "Capacitor SMD 0402")
		(tags "capacitor SMD 0402")
		(property "Reference" "C82"
			(at 0.835 0.365 0)
			(layer "F.SilkS")
			(effects
				(font
					(size 0.7 0.7)
					(thickness 0.15)
				)
				(justify right top)
			)
		)
		(property "Value" "C_100n_0402"
			(at -1.022927 2.155213 0)
			(layer "F.Fab")
			(effects
				(font
					(size 0.7 0.7)
					(thickness 0.15)
				)
				(justify right top)
			)
		)
		(property "Datasheet" "https://www.murata.com/products/productdetail?partno=GRM155R61H104KE14%23"
			(at 0 0 0)
			(layer "F.Fab")
			(hide yes)
			(effects
				(font
					(size 1.27 1.27)
					(thickness 0.15)
				)
			)
		)
		(property "Description" "SMD Multilayer Ceramic Capacitor, 0.1 µF, 50 V, 0402 [1005 Metric], ± 10%, X5R, GRM Series"
			(at 0 0 0)
			(layer "F.Fab")
			(hide yes)
			(effects
				(font
					(size 1.27 1.27)
					(thickness 0.15)
				)
			)
		)
		(property "Manufacturer" "Murata"
			(at 0 0 180)
			(unlocked yes)
			(layer "F.Fab")
			(hide yes)
			(effects
				(font
					(size 1 1)
					(thickness 0.15)
				)
			)
		)
		(property "MPN" "GRM155R61H104KE14D"
			(at 0 0 180)
			(unlocked yes)
			(layer "F.Fab")
			(hide yes)
			(effects
				(font
					(size 1 1)
					(thickness 0.15)
				)
			)
		)
		(property "Val" "100n"
			(at 0 0 180)
			(unlocked yes)
			(layer "F.Fab")
			(hide yes)
			(effects
				(font
					(size 1 1)
					(thickness 0.15)
				)
			)
		)
		(property "License" "Apache-2.0"
			(at 0 0 180)
			(unlocked yes)
			(layer "F.Fab")
			(hide yes)
			(effects
				(font
					(size 1 1)
					(thickness 0.15)
				)
			)
		)
		(property "Author" "Antmicro"
			(at 0 0 180)
			(unlocked yes)
			(layer "F.Fab")
			(hide yes)
			(effects
				(font
					(size 1 1)
					(thickness 0.15)
				)
			)
		)
		(property "Voltage" "50V"
			(at 0 0 180)
			(unlocked yes)
			(layer "F.Fab")
			(hide yes)
			(effects
				(font
					(size 1 1)
					(thickness 0.15)
				)
			)
		)
		(property "Dielectric" "X5R"
			(at 0 0 180)
			(unlocked yes)
			(layer "F.Fab")
			(hide yes)
			(effects
				(font
					(size 1 1)
					(thickness 0.15)
				)
			)
		)
		(sheetname "/USB Hub/")
		(sheetfile "usb_hub.kicad_sch")
		(attr smd)
		(fp_rect
			(start -0.925 -0.47)
			(end 0.925 0.47)
			(stroke
				(width 0.05)
				(type default)
			)
			(fill no)
			(layer "F.CrtYd")
		)
		(fp_line
			(start 0.504 0.248)
			(end -0.494 0.248)
			(stroke
				(width 0.15)
				(type solid)
			)
			(layer "F.Fab")
		)
		(fp_line
			(start 0.504 -0.25)
			(end 0.504 0.248)
			(stroke
				(width 0.15)
				(type solid)
			)
			(layer "F.Fab")
		)
		(fp_line
			(start -0.494 0.248)
			(end -0.494 -0.25)
			(stroke
				(width 0.15)
				(type solid)
			)
			(layer "F.Fab")
		)
		(fp_line
			(start -0.494 -0.25)
			(end 0.504 -0.25)
			(stroke
				(width 0.15)
				(type solid)
			)
			(layer "F.Fab")
		)
		(fp_text user "${REFERENCE}"
			(at -0.939 4.599 0)
			(layer "F.Fab")
			(effects
				(font
					(size 0.7 0.7)
					(thickness 0.15)
				)
				(justify right top)
			)
		)
		(fp_text user "Author: Antmicro"
			(at -0.939 3.399 0)
			(layer "F.Fab")
			(effects
				(font
					(size 0.7 0.7)
					(thickness 0.15)
				)
				(justify right top)
			)
		)
		(fp_text user "License: Apache-2.0"
			(at -0.939 5.799 0)
			(layer "F.Fab")
			(effects
				(font
					(size 0.7 0.7)
					(thickness 0.15)
				)
				(justify right top)
			)
		)
		(pad "1" smd roundrect
			(at -0.48 0 180)
			(size 0.59 0.64)
			(layers "F.Cu" "F.Mask" "F.Paste")
			(roundrect_rratio 0.25)
			(net 80 "/USB Hub/USBC4_CONN_TX2_P")
			(pintype "passive")
		)
		(pad "2" smd roundrect
			(at 0.48 0 180)
			(size 0.59 0.64)
			(layers "F.Cu" "F.Mask" "F.Paste")
			(roundrect_rratio 0.25)
			(net 41 "/USB Hub/USBC4_TX_{2}+")
			(pintype "passive")
		)
	)
	(footprint "antmicro-footprints:C_0402_1005Metric"
		(layer "F.Cu")
		(at 152.48 109.5)
		(descr "Capacitor SMD 0402")
		(tags "capacitor SMD 0402")
		(property "Reference" "C10"
			(at 1.12 0.4 0)
			(layer "F.SilkS")
			(effects
				(font
					(size 0.7 0.7)
					(thickness 0.15)
				)
				(justify left bottom)
			)
		)
		(property "Value" "C_100n_0402"
			(at -1.022927 2.155213 0)
			(layer "F.Fab")
			(effects
				(font
					(size 0.7 0.7)
					(thickness 0.15)
				)
				(justify left bottom)
			)
		)
		(property "Datasheet" "https://www.murata.com/products/productdetail?partno=GRM155R61H104KE14%23"
			(at 0 0 0)
			(layer "F.Fab")
			(hide yes)
			(effects
				(font
					(size 1.27 1.27)
					(thickness 0.15)
				)
			)
		)
		(property "Description" "SMD Multilayer Ceramic Capacitor, 0.1 µF, 50 V, 0402 [1005 Metric], ± 10%, X5R, GRM Series"
			(at 0 0 0)
			(layer "F.Fab")
			(hide yes)
			(effects
				(font
					(size 1.27 1.27)
					(thickness 0.15)
				)
			)
		)
		(property "Manufacturer" "Murata"
			(at 0 0 0)
			(unlocked yes)
			(layer "F.Fab")
			(hide yes)
			(effects
				(font
					(size 1 1)
					(thickness 0.15)
				)
			)
		)
		(property "MPN" "GRM155R61H104KE14D"
			(at 0 0 0)
			(unlocked yes)
			(layer "F.Fab")
			(hide yes)
			(effects
				(font
					(size 1 1)
					(thickness 0.15)
				)
			)
		)
		(property "Val" "100n"
			(at 0 0 0)
			(unlocked yes)
			(layer "F.Fab")
			(hide yes)
			(effects
				(font
					(size 1 1)
					(thickness 0.15)
				)
			)
		)
		(property "License" "Apache-2.0"
			(at 0 0 0)
			(unlocked yes)
			(layer "F.Fab")
			(hide yes)
			(effects
				(font
					(size 1 1)
					(thickness 0.15)
				)
			)
		)
		(property "Author" "Antmicro"
			(at 0 0 0)
			(unlocked yes)
			(layer "F.Fab")
			(hide yes)
			(effects
				(font
					(size 1 1)
					(thickness 0.15)
				)
			)
		)
		(property "Voltage" "50V"
			(at 0 0 0)
			(unlocked yes)
			(layer "F.Fab")
			(hide yes)
			(effects
				(font
					(size 1 1)
					(thickness 0.15)
				)
			)
		)
		(property "Dielectric" "X5R"
			(at 0 0 0)
			(unlocked yes)
			(layer "F.Fab")
			(hide yes)
			(effects
				(font
					(size 1 1)
					(thickness 0.15)
				)
			)
		)
		(sheetname "/SoM_IO/")
		(sheetfile "som_io.kicad_sch")
		(attr smd)
		(fp_poly
			(pts
				(xy -0.925 -0.47) (xy -0.925 0.47) (xy 0.925 0.47) (xy 0.925 -0.47)
			)
			(stroke
				(width 0.05)
				(type default)
			)
			(fill no)
			(layer "F.CrtYd")
		)
		(fp_line
			(start -0.494 -0.25)
			(end 0.504 -0.25)
			(stroke
				(width 0.15)
				(type solid)
			)
			(layer "F.Fab")
		)
		(fp_line
			(start -0.494 0.248)
			(end -0.494 -0.25)
			(stroke
				(width 0.15)
				(type solid)
			)
			(layer "F.Fab")
		)
		(fp_line
			(start 0.504 -0.25)
			(end 0.504 0.248)
			(stroke
				(width 0.15)
				(type solid)
			)
			(layer "F.Fab")
		)
		(fp_line
			(start 0.504 0.248)
			(end -0.494 0.248)
			(stroke
				(width 0.15)
				(type solid)
			)
			(layer "F.Fab")
		)
		(fp_text user "License: Apache-2.0"
			(at -0.939 5.799 0)
			(layer "F.Fab")
			(effects
				(font
					(size 0.7 0.7)
					(thickness 0.15)
				)
				(justify left bottom)
			)
		)
		(fp_text user "Author: Antmicro"
			(at -0.939 3.399 0)
			(layer "F.Fab")
			(effects
				(font
					(size 0.7 0.7)
					(thickness 0.15)
				)
				(justify left bottom)
			)
		)
		(fp_text user "${REFERENCE}"
			(at -0.939 4.599 0)
			(layer "F.Fab")
			(effects
				(font
					(size 0.7 0.7)
					(thickness 0.15)
				)
				(justify left bottom)
			)
		)
		(pad "1" smd roundrect
			(at -0.48 0)
			(size 0.59 0.64)
			(layers "F.Cu" "F.Mask" "F.Paste")
			(roundrect_rratio 0.25)
			(net 1 "GND")
			(pintype "passive")
		)
		(pad "2" smd roundrect
			(at 0.48 0)
			(size 0.59 0.64)
			(layers "F.Cu" "F.Mask" "F.Paste")
			(roundrect_rratio 0.25)
			(net 2 "+3V3")
			(pintype "passive")
		)
	)
	(footprint "antmicro-footprints:C_0402_1005Metric"
		(layer "F.Cu")
		(at 151.5 107.5)
		(descr "Capacitor SMD 0402")
		(tags "capacitor SMD 0402")
		(property "Reference" "C356"
			(at -3.8 0.3 0)
			(layer "F.SilkS")
			(effects
				(font
					(size 0.7 0.7)
					(thickness 0.15)
				)
				(justify left bottom)
			)
		)
		(property "Value" "C_100n_0402"
			(at -1.022927 2.155213 0)
			(layer "F.Fab")
			(effects
				(font
					(size 0.7 0.7)
					(thickness 0.15)
				)
				(justify left bottom)
			)
		)
		(property "Datasheet" "https://www.murata.com/products/productdetail?partno=GRM155R61H104KE14%23"
			(at 0 0 0)
			(layer "F.Fab")
			(hide yes)
			(effects
				(font
					(size 1.27 1.27)
					(thickness 0.15)
				)
			)
		)
		(property "Description" "SMD Multilayer Ceramic Capacitor, 0.1 µF, 50 V, 0402 [1005 Metric], ± 10%, X5R, GRM Series"
			(at 0 0 0)
			(layer "F.Fab")
			(hide yes)
			(effects
				(font
					(size 1.27 1.27)
					(thickness 0.15)
				)
			)
		)
		(property "Manufacturer" "Murata"
			(at 0 0 0)
			(unlocked yes)
			(layer "F.Fab")
			(hide yes)
			(effects
				(font
					(size 1 1)
					(thickness 0.15)
				)
			)
		)
		(property "MPN" "GRM155R61H104KE14D"
			(at 0 0 0)
			(unlocked yes)
			(layer "F.Fab")
			(hide yes)
			(effects
				(font
					(size 1 1)
					(thickness 0.15)
				)
			)
		)
		(property "Val" "100n"
			(at 0 0 0)
			(unlocked yes)
			(layer "F.Fab")
			(hide yes)
			(effects
				(font
					(size 1 1)
					(thickness 0.15)
				)
			)
		)
		(property "License" "Apache-2.0"
			(at 0 0 0)
			(unlocked yes)
			(layer "F.Fab")
			(hide yes)
			(effects
				(font
					(size 1 1)
					(thickness 0.15)
				)
			)
		)
		(property "Author" "Antmicro"
			(at 0 0 0)
			(unlocked yes)
			(layer "F.Fab")
			(hide yes)
			(effects
				(font
					(size 1 1)
					(thickness 0.15)
				)
			)
		)
		(property "Voltage" "50V"
			(at 0 0 0)
			(unlocked yes)
			(layer "F.Fab")
			(hide yes)
			(effects
				(font
					(size 1 1)
					(thickness 0.15)
				)
			)
		)
		(property "Dielectric" "X5R"
			(at 0 0 0)
			(unlocked yes)
			(layer "F.Fab")
			(hide yes)
			(effects
				(font
					(size 1 1)
					(thickness 0.15)
				)
			)
		)
		(sheetname "/SoM_IO/")
		(sheetfile "som_io.kicad_sch")
		(attr smd)
		(fp_poly
			(pts
				(xy -0.925 -0.47) (xy 0.925 -0.47) (xy 0.925 0.47) (xy -0.925 0.47)
			)
			(stroke
				(width 0.05)
				(type default)
			)
			(fill no)
			(layer "F.CrtYd")
		)
		(fp_line
			(start -0.494 -0.25)
			(end 0.504 -0.25)
			(stroke
				(width 0.15)
				(type solid)
			)
			(layer "F.Fab")
		)
		(fp_line
			(start -0.494 0.248)
			(end -0.494 -0.25)
			(stroke
				(width 0.15)
				(type solid)
			)
			(layer "F.Fab")
		)
		(fp_line
			(start 0.504 -0.25)
			(end 0.504 0.248)
			(stroke
				(width 0.15)
				(type solid)
			)
			(layer "F.Fab")
		)
		(fp_line
			(start 0.504 0.248)
			(end -0.494 0.248)
			(stroke
				(width 0.15)
				(type solid)
			)
			(layer "F.Fab")
		)
		(fp_text user "Author: Antmicro"
			(at -0.939 3.399 0)
			(layer "F.Fab")
			(effects
				(font
					(size 0.7 0.7)
					(thickness 0.15)
				)
				(justify left bottom)
			)
		)
		(fp_text user "License: Apache-2.0"
			(at -0.939 5.799 0)
			(layer "F.Fab")
			(effects
				(font
					(size 0.7 0.7)
					(thickness 0.15)
				)
				(justify left bottom)
			)
		)
		(fp_text user "${REFERENCE}"
			(at -0.939 4.599 0)
			(layer "F.Fab")
			(effects
				(font
					(size 0.7 0.7)
					(thickness 0.15)
				)
				(justify left bottom)
			)
		)
		(pad "1" smd roundrect
			(at -0.48 0)
			(size 0.59 0.64)
			(layers "F.Cu" "F.Mask" "F.Paste")
			(roundrect_rratio 0.25)
			(net 1 "GND")
			(pintype "passive")
		)
		(pad "2" smd roundrect
			(at 0.48 0)
			(size 0.59 0.64)
			(layers "F.Cu" "F.Mask" "F.Paste")
			(roundrect_rratio 0.25)
			(net 2 "+3V3")
			(pintype "passive")
		)
	)
	(footprint "antmicro-footprints:TP_SMD_0.75mm"
		(layer "F.Cu")
		(at 208.3 62 90)
		(property "Reference" "TP116"
			(at -0.4 -3.8 180)
			(layer "F.SilkS")
			(effects
				(font
					(size 0.7 0.7)
					(thickness 0.15)
				)
				(justify left bottom)
			)
		)
		(property "Value" "TP_0.75mm_SMD"
			(at 0 1.2 90)
			(layer "F.Fab")
			(effects
				(font
					(size 0.7 0.7)
					(thickness 0.15)
				)
				(justify left bottom)
			)
		)
		(property "Description" "SMT test point"
			(at 0 0 90)
			(layer "F.Fab")
			(hide yes)
			(effects
				(font
					(size 1.27 1.27)
					(thickness 0.15)
				)
			)
		)
		(property "MPN" ""
			(at 0 0 90)
			(unlocked yes)
			(layer "F.Fab")
			(hide yes)
			(effects
				(font
					(size 1 1)
					(thickness 0.15)
				)
			)
		)
		(property "Manufacturer" ""
			(at 0 0 90)
			(unlocked yes)
			(layer "F.Fab")
			(hide yes)
			(effects
				(font
					(size 1 1)
					(thickness 0.15)
				)
			)
		)
		(property "Author" "Antmicro"
			(at 0 0 90)
			(unlocked yes)
			(layer "F.Fab")
			(hide yes)
			(effects
				(font
					(size 1 1)
					(thickness 0.15)
				)
			)
		)
		(property "License" "Apache-2.0"
			(at 0 0 90)
			(unlocked yes)
			(layer "F.Fab")
			(hide yes)
			(effects
				(font
					(size 1 1)
					(thickness 0.15)
				)
			)
		)
		(sheetname "/Power/")
		(sheetfile "power.kicad_sch")
		(attr exclude_from_pos_files exclude_from_bom)
		(fp_circle
			(center 0 0)
			(end 0.475 0)
			(stroke
				(width 0.05)
				(type default)
			)
			(fill no)
			(layer "F.CrtYd")
		)
		(fp_text user "License: Apache-2.0"
			(at -0.4 5.101 90)
			(layer "F.Fab")
			(effects
				(font
					(size 0.7 0.7)
					(thickness 0.15)
				)
				(justify left bottom)
			)
		)
		(fp_text user "Author: Antmicro"
			(at -0.4 3.901 90)
			(layer "F.Fab")
			(effects
				(font
					(size 0.7 0.7)
					(thickness 0.15)
				)
				(justify left bottom)
			)
		)
		(fp_text user "${REFERENCE}"
			(at -0.4 2.7 90)
			(layer "F.Fab")
			(effects
				(font
					(size 0.7 0.7)
					(thickness 0.15)
				)
				(justify left bottom)
			)
		)
		(pad "1" smd circle
			(at 0 0 90)
			(size 0.75 0.75)
			(layers "F.Cu" "F.Mask")
			(net 1383 "VCC_NO_OVP")
			(pinfunction "1")
			(pintype "passive")
		)
	)
	(footprint "antmicro-footprints:R_0402_1005Metric"
		(layer "F.Cu")
		(at 191.3 122.6 90)
		(descr "Resistor SMD 0402")
		(tags "resistor SMD 0402")
		(property "Reference" "R88"
			(at 7.1 -2.4 90)
			(layer "F.SilkS")
			(effects
				(font
					(size 0.7 0.7)
					(thickness 0.15)
				)
				(justify left bottom)
			)
		)
		(property "Value" "R_0R_0402"
			(at -1.011843 1.772047 90)
			(layer "F.Fab")
			(effects
				(font
					(size 0.7 0.7)
					(thickness 0.15)
				)
				(justify left bottom)
			)
		)
		(property "Datasheet" "https://industrial.panasonic.com/cdbs/www-data/pdf/RDA0000/AOA0000C301.pdf"
			(at 0 0 90)
			(layer "F.Fab")
			(hide yes)
			(effects
				(font
					(size 1.27 1.27)
					(thickness 0.15)
				)
			)
		)
		(property "Description" "SMD Chip Resistor, Jumper, 0 ohm, 100 mW, 0402 [1005 Metric], Thick Film, General Purpose"
			(at 0 0 90)
			(layer "F.Fab")
			(hide yes)
			(effects
				(font
					(size 1.27 1.27)
					(thickness 0.15)
				)
			)
		)
		(property "MPN" "ERJ2GE0R00X"
			(at 0 0 90)
			(unlocked yes)
			(layer "F.Fab")
			(hide yes)
			(effects
				(font
					(size 1 1)
					(thickness 0.15)
				)
			)
		)
		(property "Manufacturer" "Panasonic"
			(at 0 0 90)
			(unlocked yes)
			(layer "F.Fab")
			(hide yes)
			(effects
				(font
					(size 1 1)
					(thickness 0.15)
				)
			)
		)
		(property "License" "Apache-2.0"
			(at 0 0 90)
			(unlocked yes)
			(layer "F.Fab")
			(hide yes)
			(effects
				(font
					(size 1 1)
					(thickness 0.15)
				)
			)
		)
		(property "Author" "Antmicro"
			(at 0 0 90)
			(unlocked yes)
			(layer "F.Fab")
			(hide yes)
			(effects
				(font
					(size 1 1)
					(thickness 0.15)
				)
			)
		)
		(property "Val" "0R"
			(at 0 0 90)
			(unlocked yes)
			(layer "F.Fab")
			(hide yes)
			(effects
				(font
					(size 1 1)
					(thickness 0.15)
				)
			)
		)
		(property "Tolerance" "~"
			(at 0 0 90)
			(unlocked yes)
			(layer "F.Fab")
			(hide yes)
			(effects
				(font
					(size 1 1)
					(thickness 0.15)
				)
			)
		)
		(property "Current" "1A"
			(at 0 0 90)
			(unlocked yes)
			(layer "F.Fab")
			(hide yes)
			(effects
				(font
					(size 1 1)
					(thickness 0.15)
				)
			)
		)
		(sheetname "/USB Hub/")
		(sheetfile "usb_hub.kicad_sch")
		(attr smd exclude_from_pos_files exclude_from_bom dnp)
		(fp_rect
			(start -0.925 -0.47)
			(end 0.925 0.47)
			(stroke
				(width 0.05)
				(type default)
			)
			(fill no)
			(layer "F.CrtYd")
		)
		(fp_rect
			(start -0.5 -0.25)
			(end 0.5 0.25)
			(stroke
				(width 0.15)
				(type solid)
			)
			(fill no)
			(layer "F.Fab")
		)
		(fp_text user "License: Apache-2.0"
			(at -0.95 5.169 90)
			(layer "F.Fab")
			(effects
				(font
					(size 0.7 0.7)
					(thickness 0.15)
				)
				(justify left bottom)
			)
		)
		(fp_text user "Author: Antmicro"
			(at -0.95 4.169 90)
			(layer "F.Fab")
			(effects
				(font
					(size 0.7 0.7)
					(thickness 0.15)
				)
				(justify left bottom)
			)
		)
		(fp_text user "${REFERENCE}"
			(at -0.95 3.168 90)
			(layer "F.Fab")
			(effects
				(font
					(size 0.7 0.7)
					(thickness 0.15)
				)
				(justify left bottom)
			)
		)
		(pad "1" smd roundrect
			(at -0.48 0 90)
			(size 0.59 0.64)
			(layers "F.Cu" "F.Mask" "F.Paste")
			(roundrect_rratio 0.25)
			(net 925 "/USB Hub/HUB_SPI_D0")
			(pintype "passive")
		)
		(pad "2" smd roundrect
			(at 0.48 0 90)
			(size 0.59 0.64)
			(layers "F.Cu" "F.Mask" "F.Paste")
			(roundrect_rratio 0.25)
			(net 923 "/USB Debug, PD/SPI_{HUB_DEBUG}.MISO")
			(pintype "passive")
		)
	)
	(footprint "antmicro-footprints:C_0402_1005Metric"
		(layer "F.Cu")
		(at 61.05 85.95 90)
		(descr "Capacitor SMD 0402")
		(tags "capacitor SMD 0402")
		(property "Reference" "C157"
			(at 0.92 0.35 90)
			(layer "F.SilkS")
			(effects
				(font
					(size 0.7 0.7)
					(thickness 0.15)
				)
				(justify left bottom)
			)
		)
		(property "Value" "C_100n_0402"
			(at -1.022927 2.155213 90)
			(layer "F.Fab")
			(effects
				(font
					(size 0.7 0.7)
					(thickness 0.15)
				)
				(justify left bottom)
			)
		)
		(property "Datasheet" "https://www.murata.com/products/productdetail?partno=GRM155R61H104KE14%23"
			(at 0 0 90)
			(layer "F.Fab")
			(hide yes)
			(effects
				(font
					(size 1.27 1.27)
					(thickness 0.15)
				)
			)
		)
		(property "Description" "SMD Multilayer Ceramic Capacitor, 0.1 µF, 50 V, 0402 [1005 Metric], ± 10%, X5R, GRM Series"
			(at 0 0 90)
			(layer "F.Fab")
			(hide yes)
			(effects
				(font
					(size 1.27 1.27)
					(thickness 0.15)
				)
			)
		)
		(property "Manufacturer" "Murata"
			(at 0 0 90)
			(unlocked yes)
			(layer "F.Fab")
			(hide yes)
			(effects
				(font
					(size 1 1)
					(thickness 0.15)
				)
			)
		)
		(property "MPN" "GRM155R61H104KE14D"
			(at 0 0 90)
			(unlocked yes)
			(layer "F.Fab")
			(hide yes)
			(effects
				(font
					(size 1 1)
					(thickness 0.15)
				)
			)
		)
		(property "Val" "100n"
			(at 0 0 90)
			(unlocked yes)
			(layer "F.Fab")
			(hide yes)
			(effects
				(font
					(size 1 1)
					(thickness 0.15)
				)
			)
		)
		(property "License" "Apache-2.0"
			(at 0 0 90)
			(unlocked yes)
			(layer "F.Fab")
			(hide yes)
			(effects
				(font
					(size 1 1)
					(thickness 0.15)
				)
			)
		)
		(property "Author" "Antmicro"
			(at 0 0 90)
			(unlocked yes)
			(layer "F.Fab")
			(hide yes)
			(effects
				(font
					(size 1 1)
					(thickness 0.15)
				)
			)
		)
		(property "Voltage" "50V"
			(at 0 0 90)
			(unlocked yes)
			(layer "F.Fab")
			(hide yes)
			(effects
				(font
					(size 1 1)
					(thickness 0.15)
				)
			)
		)
		(property "Dielectric" "X5R"
			(at 0 0 90)
			(unlocked yes)
			(layer "F.Fab")
			(hide yes)
			(effects
				(font
					(size 1 1)
					(thickness 0.15)
				)
			)
		)
		(sheetname "/CSI/")
		(sheetfile "csi.kicad_sch")
		(attr smd)
		(fp_rect
			(start -0.925 -0.47)
			(end 0.925 0.47)
			(stroke
				(width 0.05)
				(type default)
			)
			(fill no)
			(layer "F.CrtYd")
		)
		(fp_line
			(start 0.504 -0.25)
			(end 0.504 0.248)
			(stroke
				(width 0.15)
				(type solid)
			)
			(layer "F.Fab")
		)
		(fp_line
			(start -0.494 -0.25)
			(end 0.504 -0.25)
			(stroke
				(width 0.15)
				(type solid)
			)
			(layer "F.Fab")
		)
		(fp_line
			(start 0.504 0.248)
			(end -0.494 0.248)
			(stroke
				(width 0.15)
				(type solid)
			)
			(layer "F.Fab")
		)
		(fp_line
			(start -0.494 0.248)
			(end -0.494 -0.25)
			(stroke
				(width 0.15)
				(type solid)
			)
			(layer "F.Fab")
		)
		(fp_text user "Author: Antmicro"
			(at -0.939 3.399 90)
			(layer "F.Fab")
			(effects
				(font
					(size 0.7 0.7)
					(thickness 0.15)
				)
				(justify left bottom)
			)
		)
		(fp_text user "${REFERENCE}"
			(at -0.939 4.599 90)
			(layer "F.Fab")
			(effects
				(font
					(size 0.7 0.7)
					(thickness 0.15)
				)
				(justify left bottom)
			)
		)
		(fp_text user "License: Apache-2.0"
			(at -0.939 5.799 90)
			(layer "F.Fab")
			(effects
				(font
					(size 0.7 0.7)
					(thickness 0.15)
				)
				(justify left bottom)
			)
		)
		(pad "1" smd roundrect
			(at -0.48 0 90)
			(size 0.59 0.64)
			(layers "F.Cu" "F.Mask" "F.Paste")
			(roundrect_rratio 0.25)
			(net 2 "+3V3")
			(pintype "passive")
		)
		(pad "2" smd roundrect
			(at 0.48 0 90)
			(size 0.59 0.64)
			(layers "F.Cu" "F.Mask" "F.Paste")
			(roundrect_rratio 0.25)
			(net 1 "GND")
			(pintype "passive")
		)
	)
	(footprint "antmicro-footprints:LED_0603_1608Metric_G"
		(layer "F.Cu")
		(at 68.750532 55.84 -90)
		(descr "LED SMD 0603 Green")
		(tags "LED SMD 0603 Green")
		(property "Reference" "D52"
			(at -0.84 3.850532 90)
			(layer "F.SilkS")
			(hide yes)
			(effects
				(font
					(size 0.7 0.7)
					(thickness 0.15)
				)
				(justify right top)
			)
		)
		(property "Value" "LED_G_0603_LTST-C190GKT"
			(at -0.001 1.599 90)
			(layer "F.Fab")
			(effects
				(font
					(size 0.7 0.7)
					(thickness 0.15)
				)
				(justify right top)
			)
		)
		(property "Datasheet" "https://media.digikey.com/pdf/Data%20Sheets/Lite-On%20PDFs/LTST-C190GKT.pdf"
			(at 0 0 90)
			(layer "F.Fab")
			(hide yes)
			(effects
				(font
					(size 1.27 1.27)
					(thickness 0.15)
				)
			)
		)
		(property "Description" "LED, Green, SMD, 0603, 20 mA, 2.1 V, 569 nm"
			(at 0 0 90)
			(layer "F.Fab")
			(hide yes)
			(effects
				(font
					(size 1.27 1.27)
					(thickness 0.15)
				)
			)
		)
		(property "MPN" "LTST-C190GKT"
			(at 0 0 270)
			(unlocked yes)
			(layer "F.Fab")
			(hide yes)
			(effects
				(font
					(size 1 1)
					(thickness 0.15)
				)
			)
		)
		(property "Manufacturer" "Lite-On"
			(at 0 0 270)
			(unlocked yes)
			(layer "F.Fab")
			(hide yes)
			(effects
				(font
					(size 1 1)
					(thickness 0.15)
				)
			)
		)
		(property "Color" "Green"
			(at 0 0 270)
			(unlocked yes)
			(layer "F.Fab")
			(hide yes)
			(effects
				(font
					(size 1 1)
					(thickness 0.15)
				)
			)
		)
		(property "Author" "Antmicro"
			(at 0 0 270)
			(unlocked yes)
			(layer "F.Fab")
			(hide yes)
			(effects
				(font
					(size 1 1)
					(thickness 0.15)
				)
			)
		)
		(property "License" "Apache-2.0"
			(at 0 0 270)
			(unlocked yes)
			(layer "F.Fab")
			(hide yes)
			(effects
				(font
					(size 1 1)
					(thickness 0.15)
				)
			)
		)
		(sheetname "/SoM_Power/")
		(sheetfile "som_power.kicad_sch")
		(attr smd)
		(fp_line
			(start 0.22 0.35)
			(end -0.22 0.35)
			(stroke
				(width 0.15)
				(type solid)
			)
			(layer "F.SilkS")
		)
		(fp_line
			(start -0.094672 0.201008)
			(end -0.094672 -0.198992)
			(stroke
				(width 0.1)
				(type solid)
			)
			(layer "F.SilkS")
		)
		(fp_line
			(start 0.105328 0.201008)
			(end -0.094672 0.001008)
			(stroke
				(width 0.1)
				(type solid)
			)
			(layer "F.SilkS")
		)
		(fp_line
			(start 0.105328 0.201008)
			(end 0.105328 -0.198992)
			(stroke
				(width 0.1)
				(type solid)
			)
			(layer "F.SilkS")
		)
		(fp_line
			(start -0.094672 0.001008)
			(end -0.24 0.001008)
			(stroke
				(width 0.1)
				(type solid)
			)
			(layer "F.SilkS")
		)
		(fp_line
			(start -0.094672 0.001008)
			(end 0.105328 -0.198992)
			(stroke
				(width 0.1)
				(type solid)
			)
			(layer "F.SilkS")
		)
		(fp_line
			(start 0.105328 0.001008)
			(end 0.24 0.001)
			(stroke
				(width 0.1)
				(type solid)
			)
			(layer "F.SilkS")
		)
		(fp_line
			(start -1.18 -0.319)
			(end -1.18 0.321)
			(stroke
				(width 0.15)
				(type solid)
			)
			(layer "F.SilkS")
		)
		(fp_line
			(start 0.22 -0.35)
			(end -0.22 -0.35)
			(stroke
				(width 0.15)
				(type solid)
			)
			(layer "F.SilkS")
		)
		(fp_rect
			(start 1.25 0.65)
			(end -1.25 -0.65)
			(stroke
				(width 0.05)
				(type solid)
			)
			(fill no)
			(layer "F.CrtYd")
		)
		(fp_line
			(start -0.199 0.2)
			(end -0.199 0.1)
			(stroke
				(width 0.15)
				(type solid)
			)
			(layer "F.Fab")
		)
		(fp_line
			(start 0.201 0.2)
			(end 0.201 0)
			(stroke
				(width 0.15)
				(type solid)
			)
			(layer "F.Fab")
		)
		(fp_line
			(start -0.199 0)
			(end -0.597 0)
			(stroke
				(width 0.15)
				(type solid)
			)
			(layer "F.Fab")
		)
		(fp_line
			(start -0.101 0)
			(end 0.201 0.2)
			(stroke
				(width 0.15)
				(type solid)
			)
			(layer "F.Fab")
		)
		(fp_line
			(start 0.201 0)
			(end 0.201 -0.202)
			(stroke
				(width 0.15)
				(type solid)
			)
			(layer "F.Fab")
		)
		(fp_line
			(start 0.599 0)
			(end 0.201 0)
			(stroke
				(width 0.15)
				(type solid)
			)
			(layer "F.Fab")
		)
		(fp_line
			(start -0.199 -0.202)
			(end -0.199 0.1)
			(stroke
				(width 0.15)
				(type solid)
			)
			(layer "F.Fab")
		)
		(fp_line
			(start 0.201 -0.202)
			(end -0.101 0)
			(stroke
				(width 0.15)
				(type solid)
			)
			(layer "F.Fab")
		)
		(fp_rect
			(start 0.848 0.4)
			(end -0.85 -0.402)
			(stroke
				(width 0.15)
				(type solid)
			)
			(fill no)
			(layer "F.Fab")
		)
		(fp_text user "${REFERENCE}"
			(at -1.4224 5.999 90)
			(layer "F.Fab")
			(effects
				(font
					(size 0.7 0.7)
					(thickness 0.15)
				)
				(justify right top)
			)
		)
		(fp_text user "License: Apache-2.0"
			(at -1.4224 3.599 90)
			(layer "F.Fab")
			(effects
				(font
					(size 0.7 0.7)
					(thickness 0.15)
				)
				(justify right top)
			)
		)
		(fp_text user "Author: Antmicro"
			(at -1.4224 4.799 90)
			(layer "F.Fab")
			(effects
				(font
					(size 0.7 0.7)
					(thickness 0.15)
				)
				(justify right top)
			)
		)
		(pad "1" smd roundrect
			(at -0.7 0 90)
			(size 0.8 1)
			(layers "F.Cu" "F.Mask" "F.Paste")
			(roundrect_rratio 0.2)
			(net 550 "Net-(D52-C)")
			(pinfunction "C")
			(pintype "passive")
		)
		(pad "2" smd roundrect
			(at 0.7 0 90)
			(size 0.8 1)
			(layers "F.Cu" "F.Mask" "F.Paste")
			(roundrect_rratio 0.2)
			(net 549 "Net-(D52-A)")
			(pinfunction "A")
			(pintype "passive")
		)
	)
	(footprint "antmicro-footprints:C_0402_1005Metric"
		(layer "F.Cu")
		(at 91.1 100.2)
		(descr "Capacitor SMD 0402")
		(tags "capacitor SMD 0402")
		(property "Reference" "C344"
			(at 1.1 0.5 0)
			(layer "F.SilkS")
			(effects
				(font
					(size 0.7 0.7)
					(thickness 0.15)
				)
				(justify left bottom)
			)
		)
		(property "Value" "C_100n_0402"
			(at -1.022927 2.155213 0)
			(layer "F.Fab")
			(effects
				(font
					(size 0.7 0.7)
					(thickness 0.15)
				)
				(justify left bottom)
			)
		)
		(property "Datasheet" "https://www.murata.com/products/productdetail?partno=GRM155R61H104KE14%23"
			(at 0 0 0)
			(layer "F.Fab")
			(hide yes)
			(effects
				(font
					(size 1.27 1.27)
					(thickness 0.15)
				)
			)
		)
		(property "Description" "SMD Multilayer Ceramic Capacitor, 0.1 µF, 50 V, 0402 [1005 Metric], ± 10%, X5R, GRM Series"
			(at 0 0 0)
			(layer "F.Fab")
			(hide yes)
			(effects
				(font
					(size 1.27 1.27)
					(thickness 0.15)
				)
			)
		)
		(property "Manufacturer" "Murata"
			(at 0 0 0)
			(unlocked yes)
			(layer "F.Fab")
			(hide yes)
			(effects
				(font
					(size 1 1)
					(thickness 0.15)
				)
			)
		)
		(property "MPN" "GRM155R61H104KE14D"
			(at 0 0 0)
			(unlocked yes)
			(layer "F.Fab")
			(hide yes)
			(effects
				(font
					(size 1 1)
					(thickness 0.15)
				)
			)
		)
		(property "Val" "100n"
			(at 0 0 0)
			(unlocked yes)
			(layer "F.Fab")
			(hide yes)
			(effects
				(font
					(size 1 1)
					(thickness 0.15)
				)
			)
		)
		(property "License" "Apache-2.0"
			(at 0 0 0)
			(unlocked yes)
			(layer "F.Fab")
			(hide yes)
			(effects
				(font
					(size 1 1)
					(thickness 0.15)
				)
			)
		)
		(property "Author" "Antmicro"
			(at 0 0 0)
			(unlocked yes)
			(layer "F.Fab")
			(hide yes)
			(effects
				(font
					(size 1 1)
					(thickness 0.15)
				)
			)
		)
		(property "Voltage" "50V"
			(at 0 0 0)
			(unlocked yes)
			(layer "F.Fab")
			(hide yes)
			(effects
				(font
					(size 1 1)
					(thickness 0.15)
				)
			)
		)
		(property "Dielectric" "X5R"
			(at 0 0 0)
			(unlocked yes)
			(layer "F.Fab")
			(hide yes)
			(effects
				(font
					(size 1 1)
					(thickness 0.15)
				)
			)
		)
		(sheetname "/SoM_IO2/")
		(sheetfile "som_io2.kicad_sch")
		(attr smd)
		(fp_poly
			(pts
				(xy -0.925 -0.47) (xy 0.925 -0.47) (xy 0.925 0.47) (xy -0.925 0.47)
			)
			(stroke
				(width 0.05)
				(type default)
			)
			(fill no)
			(layer "F.CrtYd")
		)
		(fp_line
			(start -0.494 -0.25)
			(end 0.504 -0.25)
			(stroke
				(width 0.15)
				(type solid)
			)
			(layer "F.Fab")
		)
		(fp_line
			(start -0.494 0.248)
			(end -0.494 -0.25)
			(stroke
				(width 0.15)
				(type solid)
			)
			(layer "F.Fab")
		)
		(fp_line
			(start 0.504 -0.25)
			(end 0.504 0.248)
			(stroke
				(width 0.15)
				(type solid)
			)
			(layer "F.Fab")
		)
		(fp_line
			(start 0.504 0.248)
			(end -0.494 0.248)
			(stroke
				(width 0.15)
				(type solid)
			)
			(layer "F.Fab")
		)
		(fp_text user "License: Apache-2.0"
			(at -0.939 5.799 0)
			(layer "F.Fab")
			(effects
				(font
					(size 0.7 0.7)
					(thickness 0.15)
				)
				(justify left bottom)
			)
		)
		(fp_text user "Author: Antmicro"
			(at -0.939 3.399 0)
			(layer "F.Fab")
			(effects
				(font
					(size 0.7 0.7)
					(thickness 0.15)
				)
				(justify left bottom)
			)
		)
		(fp_text user "${REFERENCE}"
			(at -0.939 4.599 0)
			(layer "F.Fab")
			(effects
				(font
					(size 0.7 0.7)
					(thickness 0.15)
				)
				(justify left bottom)
			)
		)
		(pad "1" smd roundrect
			(at -0.48 0)
			(size 0.59 0.64)
			(layers "F.Cu" "F.Mask" "F.Paste")
			(roundrect_rratio 0.25)
			(net 691 "/Expansion connector/DP3.TX0+")
			(pintype "passive")
		)
		(pad "2" smd roundrect
			(at 0.48 0)
			(size 0.59 0.64)
			(layers "F.Cu" "F.Mask" "F.Paste")
			(roundrect_rratio 0.25)
			(net 1264 "/SoM_IO2/DP3.TX0_C+")
			(pintype "passive")
		)
	)
	(footprint "antmicro-footprints:Conn_Amphenol_SFP28_1x20_UE763GA202600T"
		(locked yes)
		(layer "F.Cu")
		(at 201.826 144.9 180)
		(property "Reference" "J12"
			(at -7.805 -6.2 0)
			(layer "F.SilkS")
			(effects
				(font
					(size 0.7 0.7)
					(thickness 0.15)
				)
				(justify right top)
			)
		)
		(property "Value" "Amphenol_SFP28_1x20_UE763GA202600T"
			(at -7.805 7.1 0)
			(layer "F.Fab")
			(effects
				(font
					(size 0.7 0.7)
					(thickness 0.15)
				)
				(justify right top)
			)
		)
		(property "Datasheet" "https://cdn.amphenol-cs.com/media/wysiwyg/files/documentation/datasheet/inputoutput/hsio_cn_ultraport_sfp.pdf"
			(at -8 12 0)
			(layer "F.Fab")
			(effects
				(font
					(size 0.7 0.7)
					(thickness 0.15)
				)
				(justify right top)
			)
		)
		(property "Description" "20 Position SFP28 Receptacle with no Cage, Right Angle"
			(at -0.702 23.301 0)
			(layer "F.Fab")
			(effects
				(font
					(size 0.7 0.7)
					(thickness 0.15)
				)
				(justify right top)
			)
		)
		(property "MPN" "UE763GA202600T"
			(at 0 0 180)
			(unlocked yes)
			(layer "F.Fab")
			(hide yes)
			(effects
				(font
					(size 1 1)
					(thickness 0.15)
				)
			)
		)
		(property "Manufacturer" "Amphenol"
			(at 0 0 180)
			(unlocked yes)
			(layer "F.Fab")
			(hide yes)
			(effects
				(font
					(size 1 1)
					(thickness 0.15)
				)
			)
		)
		(property "Author" "Antmicro"
			(at 0 0 180)
			(unlocked yes)
			(layer "F.Fab")
			(hide yes)
			(effects
				(font
					(size 1 1)
					(thickness 0.15)
				)
			)
		)
		(property "License" "Apache-2.0"
			(at 0 0 180)
			(unlocked yes)
			(layer "F.Fab")
			(hide yes)
			(effects
				(font
					(size 1 1)
					(thickness 0.15)
				)
			)
		)
		(sheetname "/SFP/")
		(sheetfile "sfp.kicad_sch")
		(attr smd)
		(fp_circle
			(center -4.7 -3.9)
			(end -4.65 -3.9)
			(stroke
				(width 0.15)
				(type solid)
			)
			(fill yes)
			(layer "F.SilkS")
		)
		(fp_rect
			(start -4.9 -6)
			(end 4.9 6)
			(stroke
				(width 0.05)
				(type solid)
			)
			(fill no)
			(layer "F.CrtYd")
		)
		(fp_text user "Author: Antmicro"
			(at -7.805 10.7 0)
			(layer "F.Fab")
			(effects
				(font
					(size 0.7 0.7)
					(thickness 0.15)
				)
				(justify right top)
			)
		)
		(fp_text user "${REFERENCE}"
			(at -7.805 9.5 0)
			(layer "F.Fab")
			(effects
				(font
					(size 0.7 0.7)
					(thickness 0.15)
				)
				(justify right top)
			)
		)
		(fp_text user "License: Apache-2.0"
			(at -7.805 8.3 0)
			(layer "F.Fab")
			(effects
				(font
					(size 0.7 0.7)
					(thickness 0.15)
				)
				(justify right top)
			)
		)
		(pad "" np_thru_hole circle
			(at 0 -4.8 90)
			(size 1.6 1.6)
			(drill 1.6)
			(layers "*.Cu" "*.Mask")
		)
		(pad "" np_thru_hole circle
			(at 0 4.8 90)
			(size 1.6 1.6)
			(drill 1.6)
			(layers "*.Cu" "*.Mask")
		)
		(pad "1" smd rect
			(at -4.1 -3.4 90)
			(size 0.5 2)
			(layers "F.Cu" "F.Mask" "F.Paste")
			(net 1 "GND")
			(pinfunction "V_{EE}(T)")
			(pintype "passive")
			(solder_mask_margin 0.102)
		)
		(pad "2" smd rect
			(at -4.1 -2.6 90)
			(size 0.5 2)
			(layers "F.Cu" "F.Mask" "F.Paste")
			(net 1371 "Net-(J12-TX_{FAULT})")
			(pinfunction "TX_{FAULT}")
			(pintype "open_collector")
			(solder_mask_margin 0.102)
		)
		(pad "3" smd rect
			(at -4.1 -1.8 90)
			(size 0.5 2)
			(layers "F.Cu" "F.Mask" "F.Paste")
			(net 1367 "Net-(J12-TX_{DISABLE})")
			(pinfunction "TX_{DISABLE}")
			(pintype "input")
			(solder_mask_margin 0.102)
		)
		(pad "4" smd rect
			(at -4.1 -1 90)
			(size 0.5 2)
			(layers "F.Cu" "F.Mask" "F.Paste")
			(net 824 "/SFP/SDA_SFP")
			(pinfunction "SDA")
			(pintype "bidirectional")
			(solder_mask_margin 0.102)
		)
		(pad "5" smd rect
			(at -4.1 -0.2 90)
			(size 0.5 2)
			(layers "F.Cu" "F.Mask" "F.Paste")
			(net 823 "/SFP/SCL_SFP")
			(pinfunction "SCL")
			(pintype "bidirectional")
			(solder_mask_margin 0.102)
		)
		(pad "6" smd rect
			(at -4.1 0.6 90)
			(size 0.5 2)
			(layers "F.Cu" "F.Mask" "F.Paste")
			(net 1296 "/SFP/SFP_MOD_ABS")
			(pinfunction "MOD_{ABS}")
			(pintype "passive")
			(solder_mask_margin 0.102)
		)
		(pad "7" smd rect
			(at -4.1 1.4 90)
			(size 0.5 2)
			(layers "F.Cu" "F.Mask" "F.Paste")
			(net 1368 "Net-(J12-RS0)")
			(pinfunction "RS0")
			(pintype "input")
			(solder_mask_margin 0.102)
		)
		(pad "8" smd rect
			(at -4.1 2.2 90)
			(size 0.5 2)
			(layers "F.Cu" "F.Mask" "F.Paste")
			(net 1370 "Net-(J12-RX_{LOS})")
			(pinfunction "RX_{LOS}")
			(pintype "open_collector")
			(solder_mask_margin 0.102)
		)
		(pad "9" smd rect
			(at -4.1 3 90)
			(size 0.5 2)
			(layers "F.Cu" "F.Mask" "F.Paste")
			(net 1369 "Net-(J12-RS1)")
			(pinfunction "RS1")
			(pintype "input")
			(solder_mask_margin 0.102)
		)
		(pad "10" smd rect
			(at -4.1 3.8 90)
			(size 0.5 2)
			(layers "F.Cu" "F.Mask" "F.Paste")
			(net 1 "GND")
			(pinfunction "V_{EE}(R)")
			(pintype "passive")
			(solder_mask_margin 0.102)
		)
		(pad "11" smd rect
			(at 4.1 3.4 90)
			(size 0.5 2)
			(layers "F.Cu" "F.Mask" "F.Paste")
			(net 1 "GND")
			(pinfunction "V_{EE}(R)")
			(pintype "passive")
			(solder_mask_margin 0.102)
		)
		(pad "12" smd rect
			(at 4.1 2.6 90)
			(size 0.5 2)
			(layers "F.Cu" "F.Mask" "F.Paste")
			(net 30 "/SFP/SFI_CONN_RX_N")
			(pinfunction "RD-")
			(pintype "output")
			(solder_mask_margin 0.102)
		)
		(pad "13" smd rect
			(at 4.1 1.8 90)
			(size 0.5 2)
			(layers "F.Cu" "F.Mask" "F.Paste")
			(net 27 "/SFP/SFI_CONN_RX_P")
			(pinfunction "RD+")
			(pintype "output")
			(solder_mask_margin 0.102)
		)
		(pad "14" smd rect
			(at 4.1 1 90)
			(size 0.5 2)
			(layers "F.Cu" "F.Mask" "F.Paste")
			(net 1 "GND")
			(pinfunction "V_{EE}(R)")
			(pintype "passive")
			(solder_mask_margin 0.102)
		)
		(pad "15" smd rect
			(at 4.1 0.2 90)
			(size 0.5 2)
			(layers "F.Cu" "F.Mask" "F.Paste")
			(net 2 "+3V3")
			(pinfunction "V_{CC}(R)")
			(pintype "power_in")
			(solder_mask_margin 0.102)
		)
		(pad "16" smd rect
			(at 4.1 -0.6 90)
			(size 0.5 2)
			(layers "F.Cu" "F.Mask" "F.Paste")
			(net 2 "+3V3")
			(pinfunction "V_{CC}(T)")
			(pintype "power_in")
			(solder_mask_margin 0.102)
		)
		(pad "17" smd rect
			(at 4.1 -1.4 90)
			(size 0.5 2)
			(layers "F.Cu" "F.Mask" "F.Paste")
			(net 1 "GND")
			(pinfunction "V_{EE}(T)")
			(pintype "passive")
			(solder_mask_margin 0.102)
		)
		(pad "18" smd rect
			(at 4.1 -2.2 90)
			(size 0.5 2)
			(layers "F.Cu" "F.Mask" "F.Paste")
			(net 21 "/SFP/SFI_CONN_TX_P")
			(pinfunction "TD+")
			(pintype "input")
			(solder_mask_margin 0.102)
		)
		(pad "19" smd rect
			(at 4.1 -3 90)
			(size 0.5 2)
			(layers "F.Cu" "F.Mask" "F.Paste")
			(net 22 "/SFP/SFI_CONN_TX_N")
			(pinfunction "TD-")
			(pintype "input")
			(solder_mask_margin 0.102)
		)
		(pad "20" smd rect
			(at 4.1 -3.8 90)
			(size 0.5 2)
			(layers "F.Cu" "F.Mask" "F.Paste")
			(net 1 "GND")
			(pinfunction "V_{EE}(T)")
			(pintype "passive")
			(solder_mask_margin 0.102)
		)
	)
	(footprint "antmicro-footprints:C_0402_1005Metric"
		(layer "F.Cu")
		(at 206.75 89.470856 180)
		(descr "Capacitor SMD 0402")
		(tags "capacitor SMD 0402")
		(property "Reference" "C317"
			(at -0.95 -0.429144 180)
			(layer "F.SilkS")
			(effects
				(font
					(size 0.7 0.7)
					(thickness 0.15)
				)
				(justify left bottom)
			)
		)
		(property "Value" "C_100n_0402"
			(at -1.022927 2.155213 180)
			(layer "F.Fab")
			(effects
				(font
					(size 0.7 0.7)
					(thickness 0.15)
				)
				(justify left bottom)
			)
		)
		(property "Datasheet" "https://www.murata.com/products/productdetail?partno=GRM155R61H104KE14%23"
			(at 0 0 180)
			(layer "F.Fab")
			(hide yes)
			(effects
				(font
					(size 1.27 1.27)
					(thickness 0.15)
				)
			)
		)
		(property "Description" "SMD Multilayer Ceramic Capacitor, 0.1 µF, 50 V, 0402 [1005 Metric], ± 10%, X5R, GRM Series"
			(at 0 0 180)
			(layer "F.Fab")
			(hide yes)
			(effects
				(font
					(size 1.27 1.27)
					(thickness 0.15)
				)
			)
		)
		(property "Manufacturer" "Murata"
			(at 0 0 180)
			(unlocked yes)
			(layer "F.Fab")
			(hide yes)
			(effects
				(font
					(size 1 1)
					(thickness 0.15)
				)
			)
		)
		(property "MPN" "GRM155R61H104KE14D"
			(at 0 0 180)
			(unlocked yes)
			(layer "F.Fab")
			(hide yes)
			(effects
				(font
					(size 1 1)
					(thickness 0.15)
				)
			)
		)
		(property "Val" "100n"
			(at 0 0 180)
			(unlocked yes)
			(layer "F.Fab")
			(hide yes)
			(effects
				(font
					(size 1 1)
					(thickness 0.15)
				)
			)
		)
		(property "License" "Apache-2.0"
			(at 0 0 180)
			(unlocked yes)
			(layer "F.Fab")
			(hide yes)
			(effects
				(font
					(size 1 1)
					(thickness 0.15)
				)
			)
		)
		(property "Author" "Antmicro"
			(at 0 0 180)
			(unlocked yes)
			(layer "F.Fab")
			(hide yes)
			(effects
				(font
					(size 1 1)
					(thickness 0.15)
				)
			)
		)
		(property "Voltage" "50V"
			(at 0 0 180)
			(unlocked yes)
			(layer "F.Fab")
			(hide yes)
			(effects
				(font
					(size 1 1)
					(thickness 0.15)
				)
			)
		)
		(property "Dielectric" "X5R"
			(at 0 0 180)
			(unlocked yes)
			(layer "F.Fab")
			(hide yes)
			(effects
				(font
					(size 1 1)
					(thickness 0.15)
				)
			)
		)
		(sheetname "/SoM_IO2/")
		(sheetfile "som_io2.kicad_sch")
		(attr smd)
		(fp_rect
			(start -0.925 -0.47)
			(end 0.925 0.47)
			(stroke
				(width 0.05)
				(type default)
			)
			(fill no)
			(layer "F.CrtYd")
		)
		(fp_line
			(start 0.504 0.248)
			(end -0.494 0.248)
			(stroke
				(width 0.15)
				(type solid)
			)
			(layer "F.Fab")
		)
		(fp_line
			(start 0.504 -0.25)
			(end 0.504 0.248)
			(stroke
				(width 0.15)
				(type solid)
			)
			(layer "F.Fab")
		)
		(fp_line
			(start -0.494 0.248)
			(end -0.494 -0.25)
			(stroke
				(width 0.15)
				(type solid)
			)
			(layer "F.Fab")
		)
		(fp_line
			(start -0.494 -0.25)
			(end 0.504 -0.25)
			(stroke
				(width 0.15)
				(type solid)
			)
			(layer "F.Fab")
		)
		(fp_text user "${REFERENCE}"
			(at -0.939 4.599 180)
			(layer "F.Fab")
			(effects
				(font
					(size 0.7 0.7)
					(thickness 0.15)
				)
				(justify left bottom)
			)
		)
		(fp_text user "License: Apache-2.0"
			(at -0.939 5.799 180)
			(layer "F.Fab")
			(effects
				(font
					(size 0.7 0.7)
					(thickness 0.15)
				)
				(justify left bottom)
			)
		)
		(fp_text user "Author: Antmicro"
			(at -0.939 3.399 180)
			(layer "F.Fab")
			(effects
				(font
					(size 0.7 0.7)
					(thickness 0.15)
				)
				(justify left bottom)
			)
		)
		(pad "1" smd roundrect
			(at -0.48 0 180)
			(size 0.59 0.64)
			(layers "F.Cu" "F.Mask" "F.Paste")
			(roundrect_rratio 0.25)
			(net 792 "/SoM_IO2/DP0.TX1-")
			(pintype "passive")
		)
		(pad "2" smd roundrect
			(at 0.48 0 180)
			(size 0.59 0.64)
			(layers "F.Cu" "F.Mask" "F.Paste")
			(roundrect_rratio 0.25)
			(net 597 "/SoM_IO2/DP0.TX1_C-")
			(pintype "passive")
		)
	)
	(footprint "antmicro-footprints:C_0402_1005Metric"
		(layer "F.Cu")
		(at 193.126 147.1 180)
		(descr "Capacitor SMD 0402")
		(tags "capacitor SMD 0402")
		(property "Reference" "C57"
			(at 3.1 -0.5 180)
			(layer "F.SilkS")
			(effects
				(font
					(size 0.7 0.7)
					(thickness 0.15)
				)
				(justify left bottom)
			)
		)
		(property "Value" "C_100n_0402"
			(at -1.022927 2.155213 180)
			(layer "F.Fab")
			(effects
				(font
					(size 0.7 0.7)
					(thickness 0.15)
				)
				(justify left bottom)
			)
		)
		(property "Datasheet" "https://www.murata.com/products/productdetail?partno=GRM155R61H104KE14%23"
			(at 0 0 180)
			(layer "F.Fab")
			(hide yes)
			(effects
				(font
					(size 1.27 1.27)
					(thickness 0.15)
				)
			)
		)
		(property "Description" "SMD Multilayer Ceramic Capacitor, 0.1 µF, 50 V, 0402 [1005 Metric], ± 10%, X5R, GRM Series"
			(at 0 0 180)
			(layer "F.Fab")
			(hide yes)
			(effects
				(font
					(size 1.27 1.27)
					(thickness 0.15)
				)
			)
		)
		(property "Manufacturer" "Murata"
			(at 0 0 180)
			(unlocked yes)
			(layer "F.Fab")
			(hide yes)
			(effects
				(font
					(size 1 1)
					(thickness 0.15)
				)
			)
		)
		(property "MPN" "GRM155R61H104KE14D"
			(at 0 0 180)
			(unlocked yes)
			(layer "F.Fab")
			(hide yes)
			(effects
				(font
					(size 1 1)
					(thickness 0.15)
				)
			)
		)
		(property "Val" "100n"
			(at 0 0 180)
			(unlocked yes)
			(layer "F.Fab")
			(hide yes)
			(effects
				(font
					(size 1 1)
					(thickness 0.15)
				)
			)
		)
		(property "License" "Apache-2.0"
			(at 0 0 180)
			(unlocked yes)
			(layer "F.Fab")
			(hide yes)
			(effects
				(font
					(size 1 1)
					(thickness 0.15)
				)
			)
		)
		(property "Author" "Antmicro"
			(at 0 0 180)
			(unlocked yes)
			(layer "F.Fab")
			(hide yes)
			(effects
				(font
					(size 1 1)
					(thickness 0.15)
				)
			)
		)
		(property "Voltage" "50V"
			(at 0 0 180)
			(unlocked yes)
			(layer "F.Fab")
			(hide yes)
			(effects
				(font
					(size 1 1)
					(thickness 0.15)
				)
			)
		)
		(property "Dielectric" "X5R"
			(at 0 0 180)
			(unlocked yes)
			(layer "F.Fab")
			(hide yes)
			(effects
				(font
					(size 1 1)
					(thickness 0.15)
				)
			)
		)
		(property "Public" "False"
			(at 0 0 180)
			(unlocked yes)
			(layer "F.Fab")
			(hide yes)
			(effects
				(font
					(size 1 1)
					(thickness 0.15)
				)
			)
		)
		(sheetname "/SFP/")
		(sheetfile "sfp.kicad_sch")
		(attr smd)
		(fp_rect
			(start -0.925 -0.47)
			(end 0.925 0.47)
			(stroke
				(width 0.05)
				(type default)
			)
			(fill no)
			(layer "F.CrtYd")
		)
		(fp_line
			(start 0.504 0.248)
			(end -0.494 0.248)
			(stroke
				(width 0.15)
				(type solid)
			)
			(layer "F.Fab")
		)
		(fp_line
			(start 0.504 -0.25)
			(end 0.504 0.248)
			(stroke
				(width 0.15)
				(type solid)
			)
			(layer "F.Fab")
		)
		(fp_line
			(start -0.494 0.248)
			(end -0.494 -0.25)
			(stroke
				(width 0.15)
				(type solid)
			)
			(layer "F.Fab")
		)
		(fp_line
			(start -0.494 -0.25)
			(end 0.504 -0.25)
			(stroke
				(width 0.15)
				(type solid)
			)
			(layer "F.Fab")
		)
		(fp_text user "Author: Antmicro"
			(at -0.939 3.399 180)
			(layer "F.Fab")
			(effects
				(font
					(size 0.7 0.7)
					(thickness 0.15)
				)
				(justify left bottom)
			)
		)
		(fp_text user "${REFERENCE}"
			(at -0.939 4.599 180)
			(layer "F.Fab")
			(effects
				(font
					(size 0.7 0.7)
					(thickness 0.15)
				)
				(justify left bottom)
			)
		)
		(fp_text user "License: Apache-2.0"
			(at -0.939 5.799 180)
			(layer "F.Fab")
			(effects
				(font
					(size 0.7 0.7)
					(thickness 0.15)
				)
				(justify left bottom)
			)
		)
		(pad "1" smd roundrect
			(at -0.48 0 180)
			(size 0.59 0.64)
			(layers "F.Cu" "F.Mask" "F.Paste")
			(roundrect_rratio 0.25)
			(net 21 "/SFP/SFI_CONN_TX_P")
			(pintype "passive")
		)
		(pad "2" smd roundrect
			(at 0.48 0 180)
			(size 0.59 0.64)
			(layers "F.Cu" "F.Mask" "F.Paste")
			(roundrect_rratio 0.25)
			(net 106 "/SFP/SFI.TX+")
			(pintype "passive")
		)
	)
	(footprint "antmicro-footprints:R_0402_1005Metric"
		(layer "F.Cu")
		(at 94 65.45 180)
		(descr "Resistor SMD 0402")
		(tags "resistor SMD 0402")
		(property "Reference" "R24"
			(at -9.1 -0.45 0)
			(layer "F.SilkS")
			(effects
				(font
					(size 0.7 0.7)
					(thickness 0.15)
				)
				(justify right top)
			)
		)
		(property "Value" "R_10k_0402"
			(at -1.011843 1.772046 0)
			(layer "F.Fab")
			(effects
				(font
					(size 0.7 0.7)
					(thickness 0.15)
				)
				(justify right top)
			)
		)
		(property "Datasheet" "https://www.bourns.com/docs/product-datasheets/cr.pdf"
			(at 0 0 0)
			(layer "F.Fab")
			(hide yes)
			(effects
				(font
					(size 1.27 1.27)
					(thickness 0.15)
				)
			)
		)
		(property "Description" "SMD Chip Resistor, 10 kohm, ± 1%, 62.5 mW, 0402 [1005 Metric], Thick Film, General Purpose"
			(at 0 0 0)
			(layer "F.Fab")
			(hide yes)
			(effects
				(font
					(size 1.27 1.27)
					(thickness 0.15)
				)
			)
		)
		(property "MPN" "CR0402-FX-1002GLF"
			(at 0 0 180)
			(unlocked yes)
			(layer "F.Fab")
			(hide yes)
			(effects
				(font
					(size 1 1)
					(thickness 0.15)
				)
			)
		)
		(property "Manufacturer" "Bourns"
			(at 0 0 180)
			(unlocked yes)
			(layer "F.Fab")
			(hide yes)
			(effects
				(font
					(size 1 1)
					(thickness 0.15)
				)
			)
		)
		(property "License" "Apache-2.0"
			(at 0 0 180)
			(unlocked yes)
			(layer "F.Fab")
			(hide yes)
			(effects
				(font
					(size 1 1)
					(thickness 0.15)
				)
			)
		)
		(property "Author" "Antmicro"
			(at 0 0 180)
			(unlocked yes)
			(layer "F.Fab")
			(hide yes)
			(effects
				(font
					(size 1 1)
					(thickness 0.15)
				)
			)
		)
		(property "Val" "10k"
			(at 0 0 180)
			(unlocked yes)
			(layer "F.Fab")
			(hide yes)
			(effects
				(font
					(size 1 1)
					(thickness 0.15)
				)
			)
		)
		(property "Tolerance" "1%"
			(at 0 0 180)
			(unlocked yes)
			(layer "F.Fab")
			(hide yes)
			(effects
				(font
					(size 1 1)
					(thickness 0.15)
				)
			)
		)
		(sheetname "/SoM_Power/")
		(sheetfile "som_power.kicad_sch")
		(attr smd)
		(fp_poly
			(pts
				(xy -0.925 -0.47) (xy 0.925 -0.47) (xy 0.925 0.47) (xy -0.925 0.47)
			)
			(stroke
				(width 0.05)
				(type default)
			)
			(fill no)
			(layer "F.CrtYd")
		)
		(fp_poly
			(pts
				(xy -0.5 -0.25) (xy 0.5 -0.25) (xy 0.5 0.25) (xy -0.5 0.25)
			)
			(stroke
				(width 0.15)
				(type solid)
			)
			(fill no)
			(layer "F.Fab")
		)
		(fp_text user "License: Apache-2.0"
			(at -0.949999 5.169 0)
			(layer "F.Fab")
			(effects
				(font
					(size 0.7 0.7)
					(thickness 0.15)
				)
				(justify right top)
			)
		)
		(fp_text user "Author: Antmicro"
			(at -0.95 4.169 0)
			(layer "F.Fab")
			(effects
				(font
					(size 0.7 0.7)
					(thickness 0.15)
				)
				(justify right top)
			)
		)
		(fp_text user "${REFERENCE}"
			(at -0.95 3.168 0)
			(layer "F.Fab")
			(effects
				(font
					(size 0.7 0.7)
					(thickness 0.15)
				)
				(justify right top)
			)
		)
		(pad "1" smd roundrect
			(at -0.48 0 180)
			(size 0.59 0.64)
			(layers "F.Cu" "F.Mask" "F.Paste")
			(roundrect_rratio 0.25)
			(net 1285 "/SoM_Power/VIN_PWR_ON")
			(pintype "passive")
		)
		(pad "2" smd roundrect
			(at 0.48 0 180)
			(size 0.59 0.64)
			(layers "F.Cu" "F.Mask" "F.Paste")
			(roundrect_rratio 0.25)
			(net 1304 "Net-(U74-2Y)")
			(pintype "passive")
		)
	)
	(footprint "antmicro-footprints:R_0402_1005Metric"
		(layer "F.Cu")
		(at 212.8 95.4 -90)
		(descr "Resistor SMD 0402")
		(tags "resistor SMD 0402")
		(property "Reference" "R117"
			(at -1.63 -1.62 90)
			(layer "F.SilkS")
			(effects
				(font
					(size 0.7 0.7)
					(thickness 0.15)
				)
				(justify right top)
			)
		)
		(property "Value" "R_100k_0402"
			(at -1.011843 1.772047 90)
			(layer "F.Fab")
			(effects
				(font
					(size 0.7 0.7)
					(thickness 0.15)
				)
				(justify right top)
			)
		)
		(property "Datasheet" "https://www.bourns.com/docs/product-datasheets/cr.pdf"
			(at 0 0 90)
			(layer "F.Fab")
			(hide yes)
			(effects
				(font
					(size 1.27 1.27)
					(thickness 0.15)
				)
			)
		)
		(property "Description" "SMD Chip Resistor, 100 kohm, ± 1%, 62.5 mW, 0402 [1005 Metric], Thick Film, General Purpose"
			(at 0 0 90)
			(layer "F.Fab")
			(hide yes)
			(effects
				(font
					(size 1.27 1.27)
					(thickness 0.15)
				)
			)
		)
		(property "Manufacturer" "Bourns"
			(at 0 0 270)
			(unlocked yes)
			(layer "F.Fab")
			(hide yes)
			(effects
				(font
					(size 1 1)
					(thickness 0.15)
				)
			)
		)
		(property "MPN" "CR0402-FX-1003GLF"
			(at 0 0 270)
			(unlocked yes)
			(layer "F.Fab")
			(hide yes)
			(effects
				(font
					(size 1 1)
					(thickness 0.15)
				)
			)
		)
		(property "Val" "100k"
			(at 0 0 270)
			(unlocked yes)
			(layer "F.Fab")
			(hide yes)
			(effects
				(font
					(size 1 1)
					(thickness 0.15)
				)
			)
		)
		(property "License" "Apache-2.0"
			(at 0 0 270)
			(unlocked yes)
			(layer "F.Fab")
			(hide yes)
			(effects
				(font
					(size 1 1)
					(thickness 0.15)
				)
			)
		)
		(property "Author" "Antmicro"
			(at 0 0 270)
			(unlocked yes)
			(layer "F.Fab")
			(hide yes)
			(effects
				(font
					(size 1 1)
					(thickness 0.15)
				)
			)
		)
		(property "Tolerance" "1%"
			(at 0 0 270)
			(unlocked yes)
			(layer "F.Fab")
			(hide yes)
			(effects
				(font
					(size 1 1)
					(thickness 0.15)
				)
			)
		)
		(sheetname "/USB DP Alt mode/")
		(sheetfile "usb_dp.kicad_sch")
		(attr smd)
		(fp_rect
			(start -0.925 -0.47)
			(end 0.925 0.47)
			(stroke
				(width 0.05)
				(type default)
			)
			(fill no)
			(layer "F.CrtYd")
		)
		(fp_rect
			(start -0.5 -0.25)
			(end 0.5 0.25)
			(stroke
				(width 0.15)
				(type solid)
			)
			(fill no)
			(layer "F.Fab")
		)
		(fp_text user "Author: Antmicro"
			(at -0.95 4.169 90)
			(layer "F.Fab")
			(effects
				(font
					(size 0.7 0.7)
					(thickness 0.15)
				)
				(justify right top)
			)
		)
		(fp_text user "${REFERENCE}"
			(at -0.95 3.168 90)
			(layer "F.Fab")
			(effects
				(font
					(size 0.7 0.7)
					(thickness 0.15)
				)
				(justify right top)
			)
		)
		(fp_text user "License: Apache-2.0"
			(at -0.95 5.169 90)
			(layer "F.Fab")
			(effects
				(font
					(size 0.7 0.7)
					(thickness 0.15)
				)
				(justify right top)
			)
		)
		(pad "1" smd roundrect
			(at -0.48 0 270)
			(size 0.59 0.64)
			(layers "F.Cu" "F.Mask" "F.Paste")
			(roundrect_rratio 0.25)
			(net 635 "/SoM_IO2/DP0.AUX+")
			(pintype "passive")
		)
		(pad "2" smd roundrect
			(at 0.48 0 270)
			(size 0.59 0.64)
			(layers "F.Cu" "F.Mask" "F.Paste")
			(roundrect_rratio 0.25)
			(net 1 "GND")
			(pintype "passive")
		)
	)
	(footprint "antmicro-footprints:TP_SMD_0.75mm"
		(layer "F.Cu")
		(at 73.2 127.2)
		(property "Reference" "TP112"
			(at -0.35 -4.000001 270)
			(layer "F.SilkS")
			(effects
				(font
					(size 0.7 0.7)
					(thickness 0.15)
				)
				(justify right top)
			)
		)
		(property "Value" "TP_0.75mm_SMD"
			(at 0 1.2 180)
			(layer "F.Fab")
			(effects
				(font
					(size 0.7 0.7)
					(thickness 0.15)
				)
				(justify right top)
			)
		)
		(property "Description" "SMT test point"
			(at 0 0 180)
			(layer "F.Fab")
			(hide yes)
			(effects
				(font
					(size 1.27 1.27)
					(thickness 0.15)
				)
			)
		)
		(property "MPN" ""
			(at 0 0 0)
			(unlocked yes)
			(layer "F.Fab")
			(hide yes)
			(effects
				(font
					(size 1 1)
					(thickness 0.15)
				)
			)
		)
		(property "Manufacturer" ""
			(at 0 0 0)
			(unlocked yes)
			(layer "F.Fab")
			(hide yes)
			(effects
				(font
					(size 1 1)
					(thickness 0.15)
				)
			)
		)
		(property "Author" "Antmicro"
			(at 0 0 0)
			(unlocked yes)
			(layer "F.Fab")
			(hide yes)
			(effects
				(font
					(size 1 1)
					(thickness 0.15)
				)
			)
		)
		(property "License" "Apache-2.0"
			(at 0 0 0)
			(unlocked yes)
			(layer "F.Fab")
			(hide yes)
			(effects
				(font
					(size 1 1)
					(thickness 0.15)
				)
			)
		)
		(sheetname "/Expansion connector/")
		(sheetfile "expansion_connector.kicad_sch")
		(attr exclude_from_pos_files exclude_from_bom)
		(fp_circle
			(center 0 0)
			(end 0.475 0)
			(stroke
				(width 0.05)
				(type default)
			)
			(fill no)
			(layer "F.CrtYd")
		)
		(fp_text user "${REFERENCE}"
			(at -0.4 2.7 180)
			(layer "F.Fab")
			(effects
				(font
					(size 0.7 0.7)
					(thickness 0.15)
				)
				(justify right top)
			)
		)
		(fp_text user "Author: Antmicro"
			(at -0.4 3.901 180)
			(layer "F.Fab")
			(effects
				(font
					(size 0.7 0.7)
					(thickness 0.15)
				)
				(justify right top)
			)
		)
		(fp_text user "License: Apache-2.0"
			(at -0.4 5.101 180)
			(layer "F.Fab")
			(effects
				(font
					(size 0.7 0.7)
					(thickness 0.15)
				)
				(justify right top)
			)
		)
		(pad "1" smd circle
			(at 0 0)
			(size 0.75 0.75)
			(layers "F.Cu" "F.Mask")
			(net 450 "Net-(J18-PadJ39)")
			(pinfunction "1")
			(pintype "passive")
		)
	)
	(footprint "antmicro-footprints:C_0805_2012Metric"
		(layer "F.Cu")
		(at 169.52 89.1 90)
		(descr "Capacitor SMD 0805")
		(tags "capacitor SMD 0805")
		(property "Reference" "C275"
			(at -1.67 -3.93 90)
			(layer "F.SilkS")
			(effects
				(font
					(size 0.7 0.7)
					(thickness 0.15)
				)
				(justify left bottom)
			)
		)
		(property "Value" "C_22u_25V_0805"
			(at -2.055717 1.963152 90)
			(layer "F.Fab")
			(effects
				(font
					(size 0.7 0.7)
					(thickness 0.15)
				)
				(justify left bottom)
			)
		)
		(property "Datasheet" "https://product.samsungsem.com/mlcc/CL21A226MAYNNN.do"
			(at 0 0 90)
			(layer "F.Fab")
			(hide yes)
			(effects
				(font
					(size 1.27 1.27)
					(thickness 0.15)
				)
			)
		)
		(property "Description" "SMT Multilayer Ceramic Capacitor, 22uF, +/-20%, 25V, X5R, 0805 [2012 Metric]"
			(at 0 0 90)
			(layer "F.Fab")
			(hide yes)
			(effects
				(font
					(size 1.27 1.27)
					(thickness 0.15)
				)
			)
		)
		(property "MPN" "CL21A226MAYNNNE"
			(at 0 0 90)
			(unlocked yes)
			(layer "F.Fab")
			(hide yes)
			(effects
				(font
					(size 1 1)
					(thickness 0.15)
				)
			)
		)
		(property "Manufacturer" "Samsung Electro-Mechanics"
			(at 0 0 90)
			(unlocked yes)
			(layer "F.Fab")
			(hide yes)
			(effects
				(font
					(size 1 1)
					(thickness 0.15)
				)
			)
		)
		(property "License" "Apache-2.0"
			(at 0 0 90)
			(unlocked yes)
			(layer "F.Fab")
			(hide yes)
			(effects
				(font
					(size 1 1)
					(thickness 0.15)
				)
			)
		)
		(property "Author" "Antmicro"
			(at 0 0 90)
			(unlocked yes)
			(layer "F.Fab")
			(hide yes)
			(effects
				(font
					(size 1 1)
					(thickness 0.15)
				)
			)
		)
		(property "Val" "22u"
			(at 0 0 90)
			(unlocked yes)
			(layer "F.Fab")
			(hide yes)
			(effects
				(font
					(size 1 1)
					(thickness 0.15)
				)
			)
		)
		(property "Voltage" "25V"
			(at 0 0 90)
			(unlocked yes)
			(layer "F.Fab")
			(hide yes)
			(effects
				(font
					(size 1 1)
					(thickness 0.15)
				)
			)
		)
		(property "Dielectric" "X5R"
			(at 0 0 90)
			(unlocked yes)
			(layer "F.Fab")
			(hide yes)
			(effects
				(font
					(size 1 1)
					(thickness 0.15)
				)
			)
		)
		(property "Public" "False"
			(at 0 0 90)
			(unlocked yes)
			(layer "F.Fab")
			(hide yes)
			(effects
				(font
					(size 1 1)
					(thickness 0.15)
				)
			)
		)
		(component_classes
			(class "DCDC_SOM")
		)
		(sheetname "/DCDC/")
		(sheetfile "dcdc.kicad_sch")
		(attr smd)
		(fp_line
			(start -0.3 -0.7)
			(end 0.3 -0.7)
			(stroke
				(width 0.15)
				(type solid)
			)
			(layer "F.SilkS")
		)
		(fp_line
			(start -0.3 0.7)
			(end 0.3 0.7)
			(stroke
				(width 0.15)
				(type solid)
			)
			(layer "F.SilkS")
		)
		(fp_rect
			(start 1.95 -0.9)
			(end -1.95 0.9)
			(stroke
				(width 0.05)
				(type default)
			)
			(fill no)
			(layer "F.CrtYd")
		)
		(fp_rect
			(start -0.95 -0.675)
			(end 0.95 0.675)
			(stroke
				(width 0.15)
				(type solid)
			)
			(fill no)
			(layer "F.Fab")
		)
		(fp_text user "License: Apache-2.0"
			(at -1.9 4.947 90)
			(layer "F.Fab")
			(effects
				(font
					(size 0.7 0.7)
					(thickness 0.15)
				)
				(justify left bottom)
			)
		)
		(fp_text user "${REFERENCE}"
			(at -1.9 3.947 90)
			(layer "F.Fab")
			(effects
				(font
					(size 0.7 0.7)
					(thickness 0.15)
				)
				(justify left bottom)
			)
		)
		(fp_text user "Author: Antmicro"
			(at -1.9 5.947 90)
			(layer "F.Fab")
			(effects
				(font
					(size 0.7 0.7)
					(thickness 0.15)
				)
				(justify left bottom)
			)
		)
		(pad "1" smd roundrect
			(at -1.1 0 90)
			(size 1.2 1.3)
			(layers "F.Cu" "F.Mask" "F.Paste")
			(roundrect_rratio 0.25)
			(net 1 "GND")
			(pintype "passive")
		)
		(pad "2" smd roundrect
			(at 1.1 0 90)
			(size 1.2 1.3)
			(layers "F.Cu" "F.Mask" "F.Paste")
			(roundrect_rratio 0.25)
			(net 13 "VCC")
			(pintype "passive")
		)
	)
	(footprint "antmicro-footprints:SW_KMR211NGLFS_SMD"
		(layer "F.Cu")
		(at 191 55.52 180)
		(property "Reference" "S2"
			(at 1.4 -2.08 180)
			(layer "F.SilkS")
			(hide yes)
			(effects
				(font
					(size 0.7 0.7)
					(thickness 0.15)
				)
				(justify right top)
			)
		)
		(property "Value" "SW_KMR211NGLFS_SMD"
			(at 0 2.8 0)
			(layer "F.Fab")
			(effects
				(font
					(size 0.7 0.7)
					(thickness 0.15)
				)
				(justify right top)
			)
		)
		(property "Datasheet" "http://www.farnell.com/datasheets/2631211.pdf"
			(at 0 0 0)
			(layer "F.Fab")
			(hide yes)
			(effects
				(font
					(size 1.27 1.27)
					(thickness 0.15)
				)
			)
		)
		(property "Description" "Tactile Switch, KMR 2 Series, Top Actuated, Surface Mount, Oval Button, 120 gf, 50mA at 32VDC"
			(at 0 0 0)
			(layer "F.Fab")
			(hide yes)
			(effects
				(font
					(size 1.27 1.27)
					(thickness 0.15)
				)
			)
		)
		(property "MPN" "KMR211NGLFS"
			(at 0 0 180)
			(unlocked yes)
			(layer "F.Fab")
			(hide yes)
			(effects
				(font
					(size 1 1)
					(thickness 0.15)
				)
			)
		)
		(property "Manufacturer" "C&K"
			(at 0 0 180)
			(unlocked yes)
			(layer "F.Fab")
			(hide yes)
			(effects
				(font
					(size 1 1)
					(thickness 0.15)
				)
			)
		)
		(property "Author" "Antmicro"
			(at 0 0 180)
			(unlocked yes)
			(layer "F.Fab")
			(hide yes)
			(effects
				(font
					(size 1 1)
					(thickness 0.15)
				)
			)
		)
		(property "License" "Apache-2.0"
			(at 0 0 180)
			(unlocked yes)
			(layer "F.Fab")
			(hide yes)
			(effects
				(font
					(size 1 1)
					(thickness 0.15)
				)
			)
		)
		(sheetname "/Peripherals/")
		(sheetfile "peripherals.kicad_sch")
		(attr smd)
		(fp_line
			(start 2.101 1.601)
			(end 2.101 1.48)
			(stroke
				(width 0.15)
				(type solid)
			)
			(layer "F.SilkS")
		)
		(fp_line
			(start 2.101 1.601)
			(end -2.1 1.601)
			(stroke
				(width 0.15)
				(type solid)
			)
			(layer "F.SilkS")
		)
		(fp_line
			(start 2.101 -1.58)
			(end 2.101 -1.459)
			(stroke
				(width 0.15)
				(type solid)
			)
			(layer "F.SilkS")
		)
		(fp_line
			(start 2.101 -1.6)
			(end -2.1 -1.6)
			(stroke
				(width 0.15)
				(type solid)
			)
			(layer "F.SilkS")
		)
		(fp_line
			(start -2.1 1.601)
			(end -2.1 1.48)
			(stroke
				(width 0.15)
				(type solid)
			)
			(layer "F.SilkS")
		)
		(fp_line
			(start -2.1 -1.6)
			(end -2.1 -1.499)
			(stroke
				(width 0.15)
				(type solid)
			)
			(layer "F.SilkS")
		)
		(fp_poly
			(pts
				(xy 2.751 1.75) (xy 2.751 -1.749) (xy -2.748 -1.749) (xy -2.748 1.749999)
			)
			(stroke
				(width 0.05)
				(type solid)
			)
			(fill no)
			(layer "F.CrtYd")
		)
		(fp_line
			(start 2.101 1.601)
			(end 2.101 -1.6)
			(stroke
				(width 0.15)
				(type solid)
			)
			(layer "F.Fab")
		)
		(fp_line
			(start 2.101 -1.6)
			(end -2.1 -1.6)
			(stroke
				(width 0.15)
				(type solid)
			)
			(layer "F.Fab")
		)
		(fp_line
			(start 0.25 0.802)
			(end -0.248 0.802)
			(stroke
				(width 0.15)
				(type solid)
			)
			(layer "F.Fab")
		)
		(fp_line
			(start -0.248 -0.8)
			(end 0.25 -0.8)
			(stroke
				(width 0.15)
				(type solid)
			)
			(layer "F.Fab")
		)
		(fp_line
			(start -2.1 1.601)
			(end 2.101 1.601)
			(stroke
				(width 0.15)
				(type solid)
			)
			(layer "F.Fab")
		)
		(fp_line
			(start -2.1 -1.6)
			(end -2.1 1.601)
			(stroke
				(width 0.15)
				(type solid)
			)
			(layer "F.Fab")
		)
		(fp_arc
			(start 0.25 -0.8)
			(mid 1.051001 0.001)
			(end 0.25 0.802)
			(stroke
				(width 0.15)
				(type solid)
			)
			(layer "F.Fab")
		)
		(fp_arc
			(start -0.248 0.802)
			(mid -1.050001 0.001)
			(end -0.248 -0.8)
			(stroke
				(width 0.15)
				(type solid)
			)
			(layer "F.Fab")
		)
		(fp_text user "${REFERENCE}"
			(at -3 4.25 0)
			(layer "F.Fab")
			(effects
				(font
					(size 0.7 0.7)
					(thickness 0.15)
				)
				(justify right top)
			)
		)
		(fp_text user "License: Apache-2.0"
			(at -3 6.75 0)
			(layer "F.Fab")
			(effects
				(font
					(size 0.7 0.7)
					(thickness 0.15)
				)
				(justify right top)
			)
		)
		(fp_text user "Author: Antmicro"
			(at -3 5.5 0)
			(layer "F.Fab")
			(effects
				(font
					(size 0.7 0.7)
					(thickness 0.15)
				)
				(justify right top)
			)
		)
		(pad "1" smd rect
			(at -2.048 -0.8)
			(size 0.9 1)
			(layers "F.Cu" "F.Mask" "F.Paste")
			(net 448 "/Expansion connector/GPIO.USER_BTN0")
			(pinfunction "1")
			(pintype "passive")
		)
		(pad "2" smd rect
			(at 2.049999 -0.8)
			(size 0.9 1)
			(layers "F.Cu" "F.Mask" "F.Paste")
			(net 448 "/Expansion connector/GPIO.USER_BTN0")
			(pinfunction "2")
			(pintype "passive")
		)
		(pad "3" smd rect
			(at -2.048 0.802)
			(size 0.9 1)
			(layers "F.Cu" "F.Mask" "F.Paste")
			(net 1 "GND")
			(pinfunction "3")
			(pintype "passive")
		)
		(pad "4" smd rect
			(at 2.05 0.802001)
			(size 0.9 1)
			(layers "F.Cu" "F.Mask" "F.Paste")
			(net 1 "GND")
			(pinfunction "4")
			(pintype "passive")
		)
	)
	(footprint "antmicro-footprints:C_0402_1005Metric"
		(layer "F.Cu")
		(at 197.215 125.3)
		(descr "Capacitor SMD 0402")
		(tags "capacitor SMD 0402")
		(property "Reference" "C98"
			(at -1.015 1.4 0)
			(layer "F.SilkS")
			(effects
				(font
					(size 0.7 0.7)
					(thickness 0.15)
				)
				(justify left bottom)
			)
		)
		(property "Value" "C_100n_0402"
			(at -1.022927 2.155213 0)
			(layer "F.Fab")
			(effects
				(font
					(size 0.7 0.7)
					(thickness 0.15)
				)
				(justify left bottom)
			)
		)
		(property "Datasheet" "https://www.murata.com/products/productdetail?partno=GRM155R61H104KE14%23"
			(at 0 0 0)
			(layer "F.Fab")
			(hide yes)
			(effects
				(font
					(size 1.27 1.27)
					(thickness 0.15)
				)
			)
		)
		(property "Description" "SMD Multilayer Ceramic Capacitor, 0.1 µF, 50 V, 0402 [1005 Metric], ± 10%, X5R, GRM Series"
			(at 0 0 0)
			(layer "F.Fab")
			(hide yes)
			(effects
				(font
					(size 1.27 1.27)
					(thickness 0.15)
				)
			)
		)
		(property "MPN" "GRM155R61H104KE14D"
			(at 0 0 0)
			(unlocked yes)
			(layer "F.Fab")
			(hide yes)
			(effects
				(font
					(size 1 1)
					(thickness 0.15)
				)
			)
		)
		(property "Val" "100n"
			(at 0 0 0)
			(unlocked yes)
			(layer "F.Fab")
			(hide yes)
			(effects
				(font
					(size 1 1)
					(thickness 0.15)
				)
			)
		)
		(property "Voltage" "50V"
			(at 0 0 0)
			(unlocked yes)
			(layer "F.Fab")
			(hide yes)
			(effects
				(font
					(size 1 1)
					(thickness 0.15)
				)
			)
		)
		(property "Dielectric" "X5R"
			(at 0 0 0)
			(unlocked yes)
			(layer "F.Fab")
			(hide yes)
			(effects
				(font
					(size 1 1)
					(thickness 0.15)
				)
			)
		)
		(property "Manufacturer" "Murata"
			(at 0 0 0)
			(unlocked yes)
			(layer "F.Fab")
			(hide yes)
			(effects
				(font
					(size 1 1)
					(thickness 0.15)
				)
			)
		)
		(property "License" "Apache-2.0"
			(at 0 0 0)
			(unlocked yes)
			(layer "F.Fab")
			(hide yes)
			(effects
				(font
					(size 1 1)
					(thickness 0.15)
				)
			)
		)
		(property "Author" "Antmicro"
			(at 0 0 0)
			(unlocked yes)
			(layer "F.Fab")
			(hide yes)
			(effects
				(font
					(size 1 1)
					(thickness 0.15)
				)
			)
		)
		(sheetname "/USB Hub/")
		(sheetfile "usb_hub.kicad_sch")
		(attr smd)
		(fp_rect
			(start -0.925 -0.47)
			(end 0.925 0.47)
			(stroke
				(width 0.05)
				(type default)
			)
			(fill no)
			(layer "F.CrtYd")
		)
		(fp_line
			(start -0.494 -0.25)
			(end 0.504 -0.25)
			(stroke
				(width 0.15)
				(type solid)
			)
			(layer "F.Fab")
		)
		(fp_line
			(start -0.494 0.248)
			(end -0.494 -0.25)
			(stroke
				(width 0.15)
				(type solid)
			)
			(layer "F.Fab")
		)
		(fp_line
			(start 0.504 -0.25)
			(end 0.504 0.248)
			(stroke
				(width 0.15)
				(type solid)
			)
			(layer "F.Fab")
		)
		(fp_line
			(start 0.504 0.248)
			(end -0.494 0.248)
			(stroke
				(width 0.15)
				(type solid)
			)
			(layer "F.Fab")
		)
		(fp_text user "${REFERENCE}"
			(at -0.939 4.599 0)
			(layer "F.Fab")
			(effects
				(font
					(size 0.7 0.7)
					(thickness 0.15)
				)
				(justify left bottom)
			)
		)
		(fp_text user "Author: Antmicro"
			(at -0.939 3.399 0)
			(layer "F.Fab")
			(effects
				(font
					(size 0.7 0.7)
					(thickness 0.15)
				)
				(justify left bottom)
			)
		)
		(fp_text user "License: Apache-2.0"
			(at -0.939 5.799 0)
			(layer "F.Fab")
			(effects
				(font
					(size 0.7 0.7)
					(thickness 0.15)
				)
				(justify left bottom)
			)
		)
		(pad "1" smd roundrect
			(at -0.48 0)
			(size 0.59 0.64)
			(layers "F.Cu" "F.Mask" "F.Paste")
			(roundrect_rratio 0.25)
			(net 1 "GND")
			(pintype "passive")
		)
		(pad "2" smd roundrect
			(at 0.48 0)
			(size 0.59 0.64)
			(layers "F.Cu" "F.Mask" "F.Paste")
			(roundrect_rratio 0.25)
			(net 2 "+3V3")
			(pintype "passive")
		)
	)
	(footprint "antmicro-footprints:C_0603_1608Metric_EIA"
		(layer "F.Cu")
		(at 176.35 113.59 -90)
		(descr "Capacitor SMD 0603, IPC-7351 Density Level A")
		(tags "Capacitor 0603")
		(property "Reference" "C69"
			(at -1.21 7.85 90)
			(layer "F.SilkS")
			(effects
				(font
					(size 0.7 0.7)
					(thickness 0.15)
				)
				(justify right top)
			)
		)
		(property "Value" "C_22u_16V_0603"
			(at -1.42757 1.770288 90)
			(layer "F.Fab")
			(effects
				(font
					(size 0.7 0.7)
					(thickness 0.15)
				)
				(justify right top)
			)
		)
		(property "Datasheet" "https://product.samsungsem.com/mlcc/CL10A226MO7JZN.do"
			(at 0 0 90)
			(layer "F.Fab")
			(hide yes)
			(effects
				(font
					(size 1.27 1.27)
					(thickness 0.15)
				)
			)
		)
		(property "Description" "SMD Multilayer Ceramic Capacitor"
			(at 0 0 90)
			(layer "F.Fab")
			(hide yes)
			(effects
				(font
					(size 1.27 1.27)
					(thickness 0.15)
				)
			)
		)
		(property "Manufacturer" "Samsung Electro-Mechanics"
			(at 0 0 270)
			(unlocked yes)
			(layer "F.Fab")
			(hide yes)
			(effects
				(font
					(size 1 1)
					(thickness 0.15)
				)
			)
		)
		(property "MPN" "CL10A226MO7JZNC"
			(at 0 0 270)
			(unlocked yes)
			(layer "F.Fab")
			(hide yes)
			(effects
				(font
					(size 1 1)
					(thickness 0.15)
				)
			)
		)
		(property "Val" "22u"
			(at 0 0 270)
			(unlocked yes)
			(layer "F.Fab")
			(hide yes)
			(effects
				(font
					(size 1 1)
					(thickness 0.15)
				)
			)
		)
		(property "License" "Apache-2.0"
			(at 0 0 270)
			(unlocked yes)
			(layer "F.Fab")
			(hide yes)
			(effects
				(font
					(size 1 1)
					(thickness 0.15)
				)
			)
		)
		(property "Author" "Antmicro"
			(at 0 0 270)
			(unlocked yes)
			(layer "F.Fab")
			(hide yes)
			(effects
				(font
					(size 1 1)
					(thickness 0.15)
				)
			)
		)
		(property "Voltage" "16V"
			(at 0 0 270)
			(unlocked yes)
			(layer "F.Fab")
			(hide yes)
			(effects
				(font
					(size 1 1)
					(thickness 0.15)
				)
			)
		)
		(property "Dielectric" ""
			(at 0 0 270)
			(unlocked yes)
			(layer "F.Fab")
			(hide yes)
			(effects
				(font
					(size 1 1)
					(thickness 0.15)
				)
			)
		)
		(sheetname "/DCDC/")
		(sheetfile "dcdc.kicad_sch")
		(attr smd)
		(fp_line
			(start -0.15 0.55)
			(end 0.15 0.55)
			(stroke
				(width 0.15)
				(type solid)
			)
			(layer "F.SilkS")
		)
		(fp_line
			(start -0.15 -0.55)
			(end 0.15 -0.55)
			(stroke
				(width 0.15)
				(type solid)
			)
			(layer "F.SilkS")
		)
		(fp_rect
			(start -1.25 -0.65)
			(end 1.25 0.65)
			(stroke
				(width 0.05)
				(type solid)
			)
			(fill no)
			(layer "F.CrtYd")
		)
		(fp_rect
			(start -0.8 -0.45)
			(end 0.8 0.45)
			(stroke
				(width 0.15)
				(type solid)
			)
			(fill no)
			(layer "F.Fab")
		)
		(fp_text user "License: Apache-2.0"
			(at -1.682 5.895 90)
			(layer "F.Fab")
			(effects
				(font
					(size 0.7 0.7)
					(thickness 0.15)
				)
				(justify right top)
			)
		)
		(fp_text user "${REFERENCE}"
			(at -1.682 3.895 90)
			(layer "F.Fab")
			(effects
				(font
					(size 0.7 0.7)
					(thickness 0.15)
				)
				(justify right top)
			)
		)
		(fp_text user "Author: Antmicro"
			(at -1.682 4.894 90)
			(layer "F.Fab")
			(effects
				(font
					(size 0.7 0.7)
					(thickness 0.15)
				)
				(justify right top)
			)
		)
		(pad "1" smd roundrect
			(at -0.7 0 270)
			(size 0.8 1.1)
			(layers "F.Cu" "F.Mask" "F.Paste")
			(roundrect_rratio 0.2)
			(net 1 "GND")
			(pintype "passive")
		)
		(pad "2" smd roundrect
			(at 0.7 0 270)
			(size 0.8 1.1)
			(layers "F.Cu" "F.Mask" "F.Paste")
			(roundrect_rratio 0.2)
			(net 253 "/DCDC/5V_OUT")
			(pintype "passive")
		)
	)
	(footprint "antmicro-footprints:C_0805_2012Metric"
		(layer "F.Cu")
		(at 172.67 146.32 -90)
		(descr "Capacitor SMD 0805")
		(tags "capacitor SMD 0805")
		(property "Reference" "C306"
			(at 1.86 -0.14 90)
			(layer "F.SilkS")
			(effects
				(font
					(size 0.7 0.7)
					(thickness 0.15)
				)
				(justify right top)
			)
		)
		(property "Value" "C_22u_25V_0805"
			(at -2.055717 1.963152 90)
			(layer "F.Fab")
			(effects
				(font
					(size 0.7 0.7)
					(thickness 0.15)
				)
				(justify right top)
			)
		)
		(property "Datasheet" "https://product.samsungsem.com/mlcc/CL21A226MAYNNN.do"
			(at 0 0 90)
			(layer "F.Fab")
			(hide yes)
			(effects
				(font
					(size 1.27 1.27)
					(thickness 0.15)
				)
			)
		)
		(property "Description" "SMT Multilayer Ceramic Capacitor, 22uF, +/-20%, 25V, X5R, 0805 [2012 Metric]"
			(at 0 0 90)
			(layer "F.Fab")
			(hide yes)
			(effects
				(font
					(size 1.27 1.27)
					(thickness 0.15)
				)
			)
		)
		(property "Manufacturer" "Samsung Electro-Mechanics"
			(at 0 0 270)
			(unlocked yes)
			(layer "F.Fab")
			(hide yes)
			(effects
				(font
					(size 1 1)
					(thickness 0.15)
				)
			)
		)
		(property "MPN" "CL21A226MAYNNNE"
			(at 0 0 270)
			(unlocked yes)
			(layer "F.Fab")
			(hide yes)
			(effects
				(font
					(size 1 1)
					(thickness 0.15)
				)
			)
		)
		(property "Val" "22u"
			(at 0 0 270)
			(unlocked yes)
			(layer "F.Fab")
			(hide yes)
			(effects
				(font
					(size 1 1)
					(thickness 0.15)
				)
			)
		)
		(property "License" "Apache-2.0"
			(at 0 0 270)
			(unlocked yes)
			(layer "F.Fab")
			(hide yes)
			(effects
				(font
					(size 1 1)
					(thickness 0.15)
				)
			)
		)
		(property "Author" "Antmicro"
			(at 0 0 270)
			(unlocked yes)
			(layer "F.Fab")
			(hide yes)
			(effects
				(font
					(size 1 1)
					(thickness 0.15)
				)
			)
		)
		(property "Voltage" "25V"
			(at 0 0 270)
			(unlocked yes)
			(layer "F.Fab")
			(hide yes)
			(effects
				(font
					(size 1 1)
					(thickness 0.15)
				)
			)
		)
		(property "Dielectric" "X5R"
			(at 0 0 270)
			(unlocked yes)
			(layer "F.Fab")
			(hide yes)
			(effects
				(font
					(size 1 1)
					(thickness 0.15)
				)
			)
		)
		(property "Public" "False"
			(at 0 0 270)
			(unlocked yes)
			(layer "F.Fab")
			(hide yes)
			(effects
				(font
					(size 1 1)
					(thickness 0.15)
				)
			)
		)
		(sheetname "/DCDC/")
		(sheetfile "dcdc.kicad_sch")
		(attr smd)
		(fp_line
			(start -0.3 0.7)
			(end 0.3 0.7)
			(stroke
				(width 0.15)
				(type solid)
			)
			(layer "F.SilkS")
		)
		(fp_line
			(start -0.3 -0.7)
			(end 0.3 -0.7)
			(stroke
				(width 0.15)
				(type solid)
			)
			(layer "F.SilkS")
		)
		(fp_rect
			(start 1.95 -0.9)
			(end -1.95 0.9)
			(stroke
				(width 0.05)
				(type default)
			)
			(fill no)
			(layer "F.CrtYd")
		)
		(fp_rect
			(start -0.95 -0.675)
			(end 0.95 0.675)
			(stroke
				(width 0.15)
				(type solid)
			)
			(fill no)
			(layer "F.Fab")
		)
		(fp_text user "License: Apache-2.0"
			(at -1.9 4.947 90)
			(layer "F.Fab")
			(effects
				(font
					(size 0.7 0.7)
					(thickness 0.15)
				)
				(justify right top)
			)
		)
		(fp_text user "Author: Antmicro"
			(at -1.9 5.947 90)
			(layer "F.Fab")
			(effects
				(font
					(size 0.7 0.7)
					(thickness 0.15)
				)
				(justify right top)
			)
		)
		(fp_text user "${REFERENCE}"
			(at -1.9 3.947 90)
			(layer "F.Fab")
			(effects
				(font
					(size 0.7 0.7)
					(thickness 0.15)
				)
				(justify right top)
			)
		)
		(pad "1" smd roundrect
			(at -1.1 0 270)
			(size 1.2 1.3)
			(layers "F.Cu" "F.Mask" "F.Paste")
			(roundrect_rratio 0.25)
			(net 1 "GND")
			(pintype "passive")
		)
		(pad "2" smd roundrect
			(at 1.1 0 270)
			(size 1.2 1.3)
			(layers "F.Cu" "F.Mask" "F.Paste")
			(roundrect_rratio 0.25)
			(net 880 "/DCDC/12V_OUT")
			(pintype "passive")
		)
	)
	(footprint "antmicro-footprints:R_0402_1005Metric"
		(layer "F.Cu")
		(at 214.9 98.2 -90)
		(descr "Resistor SMD 0402")
		(tags "resistor SMD 0402")
		(property "Reference" "R277"
			(at -1.1 3.4 90)
			(layer "F.SilkS")
			(effects
				(font
					(size 0.7 0.7)
					(thickness 0.15)
				)
				(justify right top)
			)
		)
		(property "Value" "R_0R_0402"
			(at -1.011843 1.772046 90)
			(layer "F.Fab")
			(effects
				(font
					(size 0.7 0.7)
					(thickness 0.15)
				)
				(justify right top)
			)
		)
		(property "Datasheet" "https://industrial.panasonic.com/cdbs/www-data/pdf/RDA0000/AOA0000C301.pdf"
			(at 0 0 90)
			(layer "F.Fab")
			(hide yes)
			(effects
				(font
					(size 1.27 1.27)
					(thickness 0.15)
				)
			)
		)
		(property "Description" "SMD Chip Resistor, Jumper, 0 ohm, 100 mW, 0402 [1005 Metric], Thick Film, General Purpose"
			(at 0 0 90)
			(layer "F.Fab")
			(hide yes)
			(effects
				(font
					(size 1.27 1.27)
					(thickness 0.15)
				)
			)
		)
		(property "Manufacturer" "Panasonic"
			(at 0 0 270)
			(unlocked yes)
			(layer "F.Fab")
			(hide yes)
			(effects
				(font
					(size 1 1)
					(thickness 0.15)
				)
			)
		)
		(property "MPN" "ERJ2GE0R00X"
			(at 0 0 270)
			(unlocked yes)
			(layer "F.Fab")
			(hide yes)
			(effects
				(font
					(size 1 1)
					(thickness 0.15)
				)
			)
		)
		(property "Val" "0R"
			(at 0 0 270)
			(unlocked yes)
			(layer "F.Fab")
			(hide yes)
			(effects
				(font
					(size 1 1)
					(thickness 0.15)
				)
			)
		)
		(property "License" "Apache-2.0"
			(at 0 0 270)
			(unlocked yes)
			(layer "F.Fab")
			(hide yes)
			(effects
				(font
					(size 1 1)
					(thickness 0.15)
				)
			)
		)
		(property "Author" "Antmicro"
			(at 0 0 270)
			(unlocked yes)
			(layer "F.Fab")
			(hide yes)
			(effects
				(font
					(size 1 1)
					(thickness 0.15)
				)
			)
		)
		(property "Tolerance" "~"
			(at 0 0 270)
			(unlocked yes)
			(layer "F.Fab")
			(hide yes)
			(effects
				(font
					(size 1 1)
					(thickness 0.15)
				)
			)
		)
		(property "Current" "1A"
			(at 0 0 270)
			(unlocked yes)
			(layer "F.Fab")
			(hide yes)
			(effects
				(font
					(size 1 1)
					(thickness 0.15)
				)
			)
		)
		(sheetname "/Recovery USB/")
		(sheetfile "recovery_usb.kicad_sch")
		(attr smd)
		(fp_poly
			(pts
				(xy -0.925 -0.47) (xy 0.925 -0.47) (xy 0.925 0.47) (xy -0.925 0.47)
			)
			(stroke
				(width 0.05)
				(type default)
			)
			(fill no)
			(layer "F.CrtYd")
		)
		(fp_poly
			(pts
				(xy -0.5 -0.25) (xy 0.5 -0.25) (xy 0.5 0.25) (xy -0.5 0.25)
			)
			(stroke
				(width 0.15)
				(type solid)
			)
			(fill no)
			(layer "F.Fab")
		)
		(fp_text user "License: Apache-2.0"
			(at -0.949999 5.169 90)
			(layer "F.Fab")
			(effects
				(font
					(size 0.7 0.7)
					(thickness 0.15)
				)
				(justify right top)
			)
		)
		(fp_text user "Author: Antmicro"
			(at -0.95 4.169 90)
			(layer "F.Fab")
			(effects
				(font
					(size 0.7 0.7)
					(thickness 0.15)
				)
				(justify right top)
			)
		)
		(fp_text user "${REFERENCE}"
			(at -0.95 3.168 90)
			(layer "F.Fab")
			(effects
				(font
					(size 0.7 0.7)
					(thickness 0.15)
				)
				(justify right top)
			)
		)
		(pad "1" smd roundrect
			(at -0.48 0 270)
			(size 0.59 0.64)
			(layers "F.Cu" "F.Mask" "F.Paste")
			(roundrect_rratio 0.25)
			(net 1 "GND")
			(pintype "passive")
		)
		(pad "2" smd roundrect
			(at 0.48 0 270)
			(size 0.59 0.64)
			(layers "F.Cu" "F.Mask" "F.Paste")
			(roundrect_rratio 0.25)
			(net 1022 "/Recovery USB/~{USBC2_EN_CC}")
			(pintype "passive")
		)
	)
	(footprint "antmicro-footprints:C_0402_1005Metric"
		(layer "F.Cu")
		(at 89.1 93.1)
		(descr "Capacitor SMD 0402")
		(tags "capacitor SMD 0402")
		(property "Reference" "C339"
			(at -3.82 0.45 0)
			(layer "F.SilkS")
			(effects
				(font
					(size 0.7 0.7)
					(thickness 0.15)
				)
				(justify left bottom)
			)
		)
		(property "Value" "C_100n_0402"
			(at -1.022927 2.155213 0)
			(layer "F.Fab")
			(effects
				(font
					(size 0.7 0.7)
					(thickness 0.15)
				)
				(justify left bottom)
			)
		)
		(property "Datasheet" "https://www.murata.com/products/productdetail?partno=GRM155R61H104KE14%23"
			(at 0 0 0)
			(layer "F.Fab")
			(hide yes)
			(effects
				(font
					(size 1.27 1.27)
					(thickness 0.15)
				)
			)
		)
		(property "Description" "SMD Multilayer Ceramic Capacitor, 0.1 µF, 50 V, 0402 [1005 Metric], ± 10%, X5R, GRM Series"
			(at 0 0 0)
			(layer "F.Fab")
			(hide yes)
			(effects
				(font
					(size 1.27 1.27)
					(thickness 0.15)
				)
			)
		)
		(property "Manufacturer" "Murata"
			(at 0 0 0)
			(unlocked yes)
			(layer "F.Fab")
			(hide yes)
			(effects
				(font
					(size 1 1)
					(thickness 0.15)
				)
			)
		)
		(property "MPN" "GRM155R61H104KE14D"
			(at 0 0 0)
			(unlocked yes)
			(layer "F.Fab")
			(hide yes)
			(effects
				(font
					(size 1 1)
					(thickness 0.15)
				)
			)
		)
		(property "Val" "100n"
			(at 0 0 0)
			(unlocked yes)
			(layer "F.Fab")
			(hide yes)
			(effects
				(font
					(size 1 1)
					(thickness 0.15)
				)
			)
		)
		(property "License" "Apache-2.0"
			(at 0 0 0)
			(unlocked yes)
			(layer "F.Fab")
			(hide yes)
			(effects
				(font
					(size 1 1)
					(thickness 0.15)
				)
			)
		)
		(property "Author" "Antmicro"
			(at 0 0 0)
			(unlocked yes)
			(layer "F.Fab")
			(hide yes)
			(effects
				(font
					(size 1 1)
					(thickness 0.15)
				)
			)
		)
		(property "Voltage" "50V"
			(at 0 0 0)
			(unlocked yes)
			(layer "F.Fab")
			(hide yes)
			(effects
				(font
					(size 1 1)
					(thickness 0.15)
				)
			)
		)
		(property "Dielectric" "X5R"
			(at 0 0 0)
			(unlocked yes)
			(layer "F.Fab")
			(hide yes)
			(effects
				(font
					(size 1 1)
					(thickness 0.15)
				)
			)
		)
		(sheetname "/SoM_IO2/")
		(sheetfile "som_io2.kicad_sch")
		(attr smd)
		(fp_rect
			(start -0.925 -0.47)
			(end 0.925 0.47)
			(stroke
				(width 0.05)
				(type default)
			)
			(fill no)
			(layer "F.CrtYd")
		)
		(fp_line
			(start -0.494 -0.25)
			(end 0.504 -0.25)
			(stroke
				(width 0.15)
				(type solid)
			)
			(layer "F.Fab")
		)
		(fp_line
			(start -0.494 0.248)
			(end -0.494 -0.25)
			(stroke
				(width 0.15)
				(type solid)
			)
			(layer "F.Fab")
		)
		(fp_line
			(start 0.504 -0.25)
			(end 0.504 0.248)
			(stroke
				(width 0.15)
				(type solid)
			)
			(layer "F.Fab")
		)
		(fp_line
			(start 0.504 0.248)
			(end -0.494 0.248)
			(stroke
				(width 0.15)
				(type solid)
			)
			(layer "F.Fab")
		)
		(fp_text user "Author: Antmicro"
			(at -0.939 3.399 0)
			(layer "F.Fab")
			(effects
				(font
					(size 0.7 0.7)
					(thickness 0.15)
				)
				(justify left bottom)
			)
		)
		(fp_text user "${REFERENCE}"
			(at -0.939 4.599 0)
			(layer "F.Fab")
			(effects
				(font
					(size 0.7 0.7)
					(thickness 0.15)
				)
				(justify left bottom)
			)
		)
		(fp_text user "License: Apache-2.0"
			(at -0.939 5.799 0)
			(layer "F.Fab")
			(effects
				(font
					(size 0.7 0.7)
					(thickness 0.15)
				)
				(justify left bottom)
			)
		)
		(pad "1" smd roundrect
			(at -0.48 0)
			(size 0.59 0.64)
			(layers "F.Cu" "F.Mask" "F.Paste")
			(roundrect_rratio 0.25)
			(net 744 "/Expansion connector/DP2.TX1-")
			(pintype "passive")
		)
		(pad "2" smd roundrect
			(at 0.48 0)
			(size 0.59 0.64)
			(layers "F.Cu" "F.Mask" "F.Paste")
			(roundrect_rratio 0.25)
			(net 1259 "/SoM_IO2/DP2.TX1_C-")
			(pintype "passive")
		)
	)
	(footprint "antmicro-footprints:TP_SMD_0.75mm"
		(layer "F.Cu")
		(at 175.25 57.175)
		(property "Reference" "TP75"
			(at -0.585 2.095 90)
			(layer "F.SilkS")
			(hide yes)
			(effects
				(font
					(size 0.7 0.7)
					(thickness 0.15)
				)
				(justify left bottom)
			)
		)
		(property "Value" "TP_0.75mm_SMD"
			(at 0 1.2 0)
			(layer "F.Fab")
			(effects
				(font
					(size 0.7 0.7)
					(thickness 0.15)
				)
				(justify left bottom)
			)
		)
		(property "Description" "SMT test point"
			(at 0 0 0)
			(layer "F.Fab")
			(hide yes)
			(effects
				(font
					(size 1.27 1.27)
					(thickness 0.15)
				)
			)
		)
		(property "MPN" ""
			(at 0 0 0)
			(unlocked yes)
			(layer "F.Fab")
			(hide yes)
			(effects
				(font
					(size 1 1)
					(thickness 0.15)
				)
			)
		)
		(property "Manufacturer" ""
			(at 0 0 0)
			(unlocked yes)
			(layer "F.Fab")
			(hide yes)
			(effects
				(font
					(size 1 1)
					(thickness 0.15)
				)
			)
		)
		(property "Author" "Antmicro"
			(at 0 0 0)
			(unlocked yes)
			(layer "F.Fab")
			(hide yes)
			(effects
				(font
					(size 1 1)
					(thickness 0.15)
				)
			)
		)
		(property "License" "Apache-2.0"
			(at 0 0 0)
			(unlocked yes)
			(layer "F.Fab")
			(hide yes)
			(effects
				(font
					(size 1 1)
					(thickness 0.15)
				)
			)
		)
		(sheetname "/Power/")
		(sheetfile "power.kicad_sch")
		(attr exclude_from_pos_files exclude_from_bom)
		(fp_circle
			(center 0 0)
			(end 0.475 0)
			(stroke
				(width 0.05)
				(type default)
			)
			(fill no)
			(layer "F.CrtYd")
		)
		(fp_text user "Author: Antmicro"
			(at -0.4 3.901 0)
			(layer "F.Fab")
			(effects
				(font
					(size 0.7 0.7)
					(thickness 0.15)
				)
				(justify left bottom)
			)
		)
		(fp_text user "${REFERENCE}"
			(at -0.4 2.7 0)
			(layer "F.Fab")
			(effects
				(font
					(size 0.7 0.7)
					(thickness 0.15)
				)
				(justify left bottom)
			)
		)
		(fp_text user "License: Apache-2.0"
			(at -0.4 5.101 0)
			(layer "F.Fab")
			(effects
				(font
					(size 0.7 0.7)
					(thickness 0.15)
				)
				(justify left bottom)
			)
		)
		(pad "1" smd circle
			(at 0 0)
			(size 0.75 0.75)
			(layers "F.Cu" "F.Mask")
			(net 213 "+5V_SOM")
			(pinfunction "1")
			(pintype "passive")
		)
	)
	(footprint "antmicro-footprints:R_0402_1005Metric"
		(layer "F.Cu")
		(at 161.729468 78.11 90)
		(descr "Resistor SMD 0402")
		(tags "resistor SMD 0402")
		(property "Reference" "R371"
			(at -1 -1.809468 90)
			(layer "F.SilkS")
			(effects
				(font
					(size 0.7 0.7)
					(thickness 0.15)
				)
				(justify left bottom)
			)
		)
		(property "Value" "R_27R_0402"
			(at -1.011843 1.772047 90)
			(layer "F.Fab")
			(effects
				(font
					(size 0.7 0.7)
					(thickness 0.15)
				)
				(justify left bottom)
			)
		)
		(property "Datasheet" "https://www.bourns.com/docs/product-datasheets/cr.pdf"
			(at 0 0 90)
			(layer "F.Fab")
			(hide yes)
			(effects
				(font
					(size 1.27 1.27)
					(thickness 0.15)
				)
			)
		)
		(property "Description" "SMD Chip Resistor, 27 ohm, ± 1%, 63 mW, 0402 [1005 Metric], Thick Film, General Purpose"
			(at 0 0 90)
			(layer "F.Fab")
			(hide yes)
			(effects
				(font
					(size 1.27 1.27)
					(thickness 0.15)
				)
			)
		)
		(property "Manufacturer" "Bourns"
			(at 0 0 90)
			(unlocked yes)
			(layer "F.Fab")
			(hide yes)
			(effects
				(font
					(size 1 1)
					(thickness 0.15)
				)
			)
		)
		(property "MPN" "CR0402-FX-27R0GLF"
			(at 0 0 90)
			(unlocked yes)
			(layer "F.Fab")
			(hide yes)
			(effects
				(font
					(size 1 1)
					(thickness 0.15)
				)
			)
		)
		(property "Val" "27R"
			(at 0 0 90)
			(unlocked yes)
			(layer "F.Fab")
			(hide yes)
			(effects
				(font
					(size 1 1)
					(thickness 0.15)
				)
			)
		)
		(property "License" "Apache-2.0"
			(at 0 0 90)
			(unlocked yes)
			(layer "F.Fab")
			(hide yes)
			(effects
				(font
					(size 1 1)
					(thickness 0.15)
				)
			)
		)
		(property "Author" "Antmicro"
			(at 0 0 90)
			(unlocked yes)
			(layer "F.Fab")
			(hide yes)
			(effects
				(font
					(size 1 1)
					(thickness 0.15)
				)
			)
		)
		(property "Tolerance" "1%"
			(at 0 0 90)
			(unlocked yes)
			(layer "F.Fab")
			(hide yes)
			(effects
				(font
					(size 1 1)
					(thickness 0.15)
				)
			)
		)
		(component_classes
			(class "DCDC_20V")
		)
		(sheetname "/DCDC/")
		(sheetfile "dcdc.kicad_sch")
		(attr smd)
		(fp_rect
			(start -0.925 -0.47)
			(end 0.925 0.47)
			(stroke
				(width 0.05)
				(type default)
			)
			(fill no)
			(layer "F.CrtYd")
		)
		(fp_rect
			(start -0.5 -0.25)
			(end 0.5 0.25)
			(stroke
				(width 0.15)
				(type solid)
			)
			(fill no)
			(layer "F.Fab")
		)
		(fp_text user "${REFERENCE}"
			(at -0.95 3.168 90)
			(layer "F.Fab")
			(effects
				(font
					(size 0.7 0.7)
					(thickness 0.15)
				)
				(justify left bottom)
			)
		)
		(fp_text user "Author: Antmicro"
			(at -0.95 4.169 90)
			(layer "F.Fab")
			(effects
				(font
					(size 0.7 0.7)
					(thickness 0.15)
				)
				(justify left bottom)
			)
		)
		(fp_text user "License: Apache-2.0"
			(at -0.95 5.169 90)
			(layer "F.Fab")
			(effects
				(font
					(size 0.7 0.7)
					(thickness 0.15)
				)
				(justify left bottom)
			)
		)
		(pad "1" smd roundrect
			(at -0.48 0 90)
			(size 0.59 0.64)
			(layers "F.Cu" "F.Mask" "F.Paste")
			(roundrect_rratio 0.25)
			(net 1221 "Net-(U66-IN-)")
			(pintype "passive")
		)
		(pad "2" smd roundrect
			(at 0.48 0 90)
			(size 0.59 0.64)
			(layers "F.Cu" "F.Mask" "F.Paste")
			(roundrect_rratio 0.25)
			(net 904 "+20V")
			(pintype "passive")
		)
	)
	(footprint "antmicro-footprints:USB-C_Receptacle_Kycon_KUSBX-SL2-CS1N24-B-TR"
		(locked yes)
		(layer "F.Cu")
		(at 236.455532 115.21 90)
		(descr "USB-C (USB TYPE-C) USB 3.2 Gen 2 (USB 3.1 Gen 2, Superspeed + (USB 3.1)) Receptacle Connector 24 Position Through Hole, Right Angle")
		(tags "CONNECTOR, USB")
		(property "Reference" "J6"
			(at 3.11 -10.685532 180)
			(layer "F.SilkS")
			(effects
				(font
					(size 0.7 0.7)
					(thickness 0.15)
				)
				(justify left bottom)
			)
		)
		(property "Value" "USB-C_Kycon_KUSBX-SL2-CS1N24-B-TR"
			(at 0 7.5 90)
			(layer "F.Fab")
			(effects
				(font
					(size 0.7 0.7)
					(thickness 0.15)
				)
				(justify right top)
			)
		)
		(property "Datasheet" "https://www.kycon.com/Pub_Eng_Draw/KUSBX-SL2-CS1N24-B-TR.pdf"
			(at 0 0 90)
			(layer "F.Fab")
			(hide yes)
			(effects
				(font
					(size 1.27 1.27)
					(thickness 0.15)
				)
			)
		)
		(property "Description" "USB-C (USB TYPE-C) USB 3.2 Gen 2 (USB 3.1 Gen 2, Superspeed + (USB 3.1)) USB PD Receptacle Connector 24 Position Surface Mount"
			(at 0 0 90)
			(layer "F.Fab")
			(hide yes)
			(effects
				(font
					(size 1.27 1.27)
					(thickness 0.15)
				)
			)
		)
		(property "MPN" "KUSBX-SL2-CS1N24-B-TR"
			(at 0 0 90)
			(unlocked yes)
			(layer "F.Fab")
			(hide yes)
			(effects
				(font
					(size 1 1)
					(thickness 0.15)
				)
			)
		)
		(property "Manufacturer" "Kycon"
			(at 0 0 90)
			(unlocked yes)
			(layer "F.Fab")
			(hide yes)
			(effects
				(font
					(size 1 1)
					(thickness 0.15)
				)
			)
		)
		(property "License" "Apache-2.0"
			(at 0 0 90)
			(unlocked yes)
			(layer "F.Fab")
			(hide yes)
			(effects
				(font
					(size 1 1)
					(thickness 0.15)
				)
			)
		)
		(property "Author" "Antmicro"
			(at 0 0 90)
			(unlocked yes)
			(layer "F.Fab")
			(hide yes)
			(effects
				(font
					(size 1 1)
					(thickness 0.15)
				)
			)
		)
		(sheetname "/USB Hub/")
		(sheetfile "usb_hub.kicad_sch")
		(attr smd)
		(fp_line
			(start 1 -8.8)
			(end 1 -8.8)
			(stroke
				(width 0.15)
				(type solid)
			)
			(layer "F.SilkS")
		)
		(fp_line
			(start 1 -8.8)
			(end -1 -8.8)
			(stroke
				(width 0.15)
				(type solid)
			)
			(layer "F.SilkS")
		)
		(fp_line
			(start -1 -8.8)
			(end 1 -8.8)
			(stroke
				(width 0.15)
				(type solid)
			)
			(layer "F.SilkS")
		)
		(fp_line
			(start -1 -8.8)
			(end -1 -8.8)
			(stroke
				(width 0.15)
				(type solid)
			)
			(layer "F.SilkS")
		)
		(fp_rect
			(start -4 -9.4)
			(end 4 5.65)
			(stroke
				(width 0.05)
				(type solid)
			)
			(fill no)
			(layer "F.CrtYd")
		)
		(fp_line
			(start 2.25 -8.8)
			(end -2.25 -8.8)
			(stroke
				(width 0.15)
				(type solid)
			)
			(layer "F.Fab")
		)
		(fp_line
			(start -2.25 -8.8)
			(end -2.25 5.5)
			(stroke
				(width 0.15)
				(type solid)
			)
			(layer "F.Fab")
		)
		(fp_line
			(start 2.25 5.5)
			(end 2.25 -8.8)
			(stroke
				(width 0.15)
				(type solid)
			)
			(layer "F.Fab")
		)
		(fp_line
			(start -2.25 5.5)
			(end 2.25 5.5)
			(stroke
				(width 0.15)
				(type solid)
			)
			(layer "F.Fab")
		)
		(fp_text user "Author: Antmicro"
			(at -5.47 9.7 90)
			(layer "F.Fab")
			(effects
				(font
					(size 0.7 0.7)
					(thickness 0.15)
				)
				(justify left bottom)
			)
		)
		(fp_text user "License: Apache-2.0"
			(at -5.47 10.9 90)
			(layer "F.Fab")
			(effects
				(font
					(size 0.7 0.7)
					(thickness 0.15)
				)
				(justify left bottom)
			)
		)
		(fp_text user "${REFERENCE}"
			(at -5.47 8.5 90)
			(layer "F.Fab")
			(effects
				(font
					(size 0.7 0.7)
					(thickness 0.15)
				)
				(justify left bottom)
			)
		)
		(pad "" np_thru_hole circle
			(at 0 -7.6 90)
			(size 1.1 1.1)
			(drill 1.1)
			(layers "*.Cu" "*.Mask")
		)
		(pad "" np_thru_hole circle
			(at 0 0 90)
			(size 1 1)
			(drill 1)
			(layers "*.Cu" "*.Mask")
		)
		(pad "A1" smd rect
			(at 1.1375 -6.525 180)
			(size 0.25 1.625)
			(layers "F.Cu" "F.Mask" "F.Paste")
			(net 1 "GND")
			(pinfunction "GND")
			(pintype "power_in")
		)
		(pad "A2" smd rect
			(at 1.1375 -6.025 180)
			(size 0.25 1.625)
			(layers "F.Cu" "F.Mask" "F.Paste")
			(net 164 "/USB Hub/USBC3_CONN_TX1_P")
			(pinfunction "TX_{1}+")
			(pintype "bidirectional")
		)
		(pad "A3" smd rect
			(at 1.1375 -5.525 180)
			(size 0.25 1.625)
			(layers "F.Cu" "F.Mask" "F.Paste")
			(net 95 "/USB Hub/USBC3_CONN_TX1_N")
			(pinfunction "TX_{1}-")
			(pintype "bidirectional")
		)
		(pad "A4" smd rect
			(at 1.1375 -5.025 180)
			(size 0.25 1.625)
			(layers "F.Cu" "F.Mask" "F.Paste")
			(net 71 "/USB Hub/USBC3_VBUS")
			(pinfunction "VBUS")
			(pintype "power_in")
		)
		(pad "A5" smd rect
			(at 1.1375 -4.525 180)
			(size 0.25 1.625)
			(layers "F.Cu" "F.Mask" "F.Paste")
			(net 510 "/USB Hub/USBC3_CC_{1}")
			(pinfunction "CC_{1}")
			(pintype "bidirectional")
		)
		(pad "A6" smd rect
			(at 1.1375 -4.025 180)
			(size 0.25 1.625)
			(layers "F.Cu" "F.Mask" "F.Paste")
			(net 506 "/USB Hub/USBC3_D+")
			(pinfunction "D_{A}+")
			(pintype "bidirectional")
		)
		(pad "A7" smd rect
			(at 1.1375 -3.525 180)
			(size 0.25 1.625)
			(layers "F.Cu" "F.Mask" "F.Paste")
			(net 508 "/USB Hub/USBC3_D-")
			(pinfunction "D_{A}-")
			(pintype "bidirectional")
		)
		(pad "A8" smd rect
			(at 1.1375 -3.025 180)
			(size 0.25 1.625)
			(layers "F.Cu" "F.Mask" "F.Paste")
			(net 179 "unconnected-(J6-SBU_{1}-PadA8)")
			(pinfunction "SBU_{1}")
			(pintype "bidirectional+no_connect")
		)
		(pad "A9" smd rect
			(at 1.1375 -2.525 180)
			(size 0.25 1.625)
			(layers "F.Cu" "F.Mask" "F.Paste")
			(net 71 "/USB Hub/USBC3_VBUS")
			(pinfunction "VBUS")
			(pintype "passive")
		)
		(pad "A10" smd rect
			(at 1.1375 -2.025 180)
			(size 0.25 1.625)
			(layers "F.Cu" "F.Mask" "F.Paste")
			(net 512 "/USB Hub/USBC3_RX_{2}+")
			(pinfunction "RX_{2}-")
			(pintype "bidirectional")
		)
		(pad "A11" smd rect
			(at 1.1375 -1.525 180)
			(size 0.25 1.625)
			(layers "F.Cu" "F.Mask" "F.Paste")
			(net 511 "/USB Hub/USBC3_RX_{2}-")
			(pinfunction "RX_{2}+")
			(pintype "bidirectional")
		)
		(pad "A12" smd rect
			(at 1.1375 -1.025 180)
			(size 0.25 1.625)
			(layers "F.Cu" "F.Mask" "F.Paste")
			(net 1 "GND")
			(pinfunction "GND")
			(pintype "passive")
		)
		(pad "B1" smd rect
			(at -1.1375 -1.025 180)
			(size 0.25 1.625)
			(layers "F.Cu" "F.Mask" "F.Paste")
			(net 1 "GND")
			(pinfunction "GND")
			(pintype "passive")
		)
		(pad "B2" smd rect
			(at -1.1375 -1.525 180)
			(size 0.25 1.625)
			(layers "F.Cu" "F.Mask" "F.Paste")
			(net 103 "/USB Hub/USBC3_CONN_TX2_N")
			(pinfunction "TX_{2}+")
			(pintype "bidirectional")
		)
		(pad "B3" smd rect
			(at -1.1375 -2.025 180)
			(size 0.25 1.625)
			(layers "F.Cu" "F.Mask" "F.Paste")
			(net 174 "/USB Hub/USBC3_CONN_TX2_P")
			(pinfunction "TX_{2}-")
			(pintype "bidirectional")
		)
		(pad "B4" smd rect
			(at -1.1375 -2.525 180)
			(size 0.25 1.625)
			(layers "F.Cu" "F.Mask" "F.Paste")
			(net 71 "/USB Hub/USBC3_VBUS")
			(pinfunction "VBUS")
			(pintype "passive")
		)
		(pad "B5" smd rect
			(at -1.1375 -3.025 180)
			(size 0.25 1.625)
			(layers "F.Cu" "F.Mask" "F.Paste")
			(net 509 "/USB Hub/USBC3_CC_{2}")
			(pinfunction "CC_{2}")
			(pintype "bidirectional")
		)
		(pad "B6" smd rect
			(at -1.1375 -3.525 180)
			(size 0.25 1.625)
			(layers "F.Cu" "F.Mask" "F.Paste")
			(net 506 "/USB Hub/USBC3_D+")
			(pinfunction "D_{B}+")
			(pintype "bidirectional")
		)
		(pad "B7" smd rect
			(at -1.1375 -4.025 180)
			(size 0.25 1.625)
			(layers "F.Cu" "F.Mask" "F.Paste")
			(net 508 "/USB Hub/USBC3_D-")
			(pinfunction "D_{B}-")
			(pintype "bidirectional")
		)
		(pad "B8" smd rect
			(at -1.1375 -4.525 180)
			(size 0.25 1.625)
			(layers "F.Cu" "F.Mask" "F.Paste")
			(net 178 "unconnected-(J6-SBU_{2}-PadB8)")
			(pinfunction "SBU_{2}")
			(pintype "bidirectional+no_connect")
		)
		(pad "B9" smd rect
			(at -1.1375 -5.025 180)
			(size 0.25 1.625)
			(layers "F.Cu" "F.Mask" "F.Paste")
			(net 71 "/USB Hub/USBC3_VBUS")
			(pinfunction "VBUS")
			(pintype "passive")
		)
		(pad "B10" smd rect
			(at -1.1375 -5.525 180)
			(size 0.25 1.625)
			(layers "F.Cu" "F.Mask" "F.Paste")
			(net 513 "/USB Hub/USBC3_RX_{1}+")
			(pinfunction "RX_{1}-")
			(pintype "bidirectional")
		)
		(pad "B11" smd rect
			(at -1.1375 -6.025 180)
			(size 0.25 1.625)
			(layers "F.Cu" "F.Mask" "F.Paste")
			(net 507 "/USB Hub/USBC3_RX_{1}-")
			(pinfunction "RX_{1}+")
			(pintype "bidirectional")
		)
		(pad "B12" smd rect
			(at -1.1375 -6.525 180)
			(size 0.25 1.625)
			(layers "F.Cu" "F.Mask" "F.Paste")
			(net 1 "GND")
			(pinfunction "GND")
			(pintype "passive")
		)
		(pad "SH" thru_hole oval
			(at -3 -7.849 90)
			(size 1 2.05)
			(drill oval 0.6 1.65)
			(layers "*.Cu" "*.Mask")
			(remove_unused_layers no)
			(net 1 "GND")
			(pinfunction "SH")
			(pintype "passive")
		)
		(pad "SH" thru_hole oval
			(at -3 0.25 90)
			(size 1 2.05)
			(drill oval 0.6 1.65)
			(layers "*.Cu" "*.Mask")
			(remove_unused_layers no)
			(net 1 "GND")
			(pinfunction "SH")
			(pintype "passive")
		)
		(pad "SH" thru_hole oval
			(at 3 -7.849 90)
			(size 1 2.05)
			(drill oval 0.6 1.65)
			(layers "*.Cu" "*.Mask")
			(remove_unused_layers no)
			(net 1 "GND")
			(pinfunction "SH")
			(pintype "passive")
		)
		(pad "SH" thru_hole oval
			(at 3 0.25 90)
			(size 1 2.05)
			(drill oval 0.6 1.65)
			(layers "*.Cu" "*.Mask")
			(remove_unused_layers no)
			(net 1 "GND")
			(pinfunction "SH")
			(pintype "passive")
		)
	)
	(footprint "antmicro-footprints:C_0402_1005Metric"
		(layer "F.Cu")
		(at 204.965 117.88 -90)
		(descr "Capacitor SMD 0402")
		(tags "capacitor SMD 0402")
		(property "Reference" "C100"
			(at -3.68 0.465 90)
			(layer "F.SilkS")
			(effects
				(font
					(size 0.7 0.7)
					(thickness 0.15)
				)
				(justify right top)
			)
		)
		(property "Value" "C_100n_0402"
			(at -1.022927 2.155213 90)
			(layer "F.Fab")
			(effects
				(font
					(size 0.7 0.7)
					(thickness 0.15)
				)
				(justify right top)
			)
		)
		(property "Datasheet" "https://www.murata.com/products/productdetail?partno=GRM155R61H104KE14%23"
			(at 0 0 90)
			(layer "F.Fab")
			(hide yes)
			(effects
				(font
					(size 1.27 1.27)
					(thickness 0.15)
				)
			)
		)
		(property "Description" "SMD Multilayer Ceramic Capacitor, 0.1 µF, 50 V, 0402 [1005 Metric], ± 10%, X5R, GRM Series"
			(at 0 0 90)
			(layer "F.Fab")
			(hide yes)
			(effects
				(font
					(size 1.27 1.27)
					(thickness 0.15)
				)
			)
		)
		(property "MPN" "GRM155R61H104KE14D"
			(at 0 0 270)
			(unlocked yes)
			(layer "F.Fab")
			(hide yes)
			(effects
				(font
					(size 1 1)
					(thickness 0.15)
				)
			)
		)
		(property "Val" "100n"
			(at 0 0 270)
			(unlocked yes)
			(layer "F.Fab")
			(hide yes)
			(effects
				(font
					(size 1 1)
					(thickness 0.15)
				)
			)
		)
		(property "Voltage" "50V"
			(at 0 0 270)
			(unlocked yes)
			(layer "F.Fab")
			(hide yes)
			(effects
				(font
					(size 1 1)
					(thickness 0.15)
				)
			)
		)
		(property "Dielectric" "X5R"
			(at 0 0 270)
			(unlocked yes)
			(layer "F.Fab")
			(hide yes)
			(effects
				(font
					(size 1 1)
					(thickness 0.15)
				)
			)
		)
		(property "Manufacturer" "Murata"
			(at 0 0 270)
			(unlocked yes)
			(layer "F.Fab")
			(hide yes)
			(effects
				(font
					(size 1 1)
					(thickness 0.15)
				)
			)
		)
		(property "License" "Apache-2.0"
			(at 0 0 270)
			(unlocked yes)
			(layer "F.Fab")
			(hide yes)
			(effects
				(font
					(size 1 1)
					(thickness 0.15)
				)
			)
		)
		(property "Author" "Antmicro"
			(at 0 0 270)
			(unlocked yes)
			(layer "F.Fab")
			(hide yes)
			(effects
				(font
					(size 1 1)
					(thickness 0.15)
				)
			)
		)
		(sheetname "/USB Hub/")
		(sheetfile "usb_hub.kicad_sch")
		(attr smd)
		(fp_poly
			(pts
				(xy -0.925 -0.47) (xy -0.925 0.47) (xy 0.925 0.47) (xy 0.925 -0.47)
			)
			(stroke
				(width 0.05)
				(type default)
			)
			(fill no)
			(layer "F.CrtYd")
		)
		(fp_line
			(start -0.494 0.248)
			(end -0.494 -0.25)
			(stroke
				(width 0.15)
				(type solid)
			)
			(layer "F.Fab")
		)
		(fp_line
			(start 0.504 0.248)
			(end -0.494 0.248)
			(stroke
				(width 0.15)
				(type solid)
			)
			(layer "F.Fab")
		)
		(fp_line
			(start -0.494 -0.25)
			(end 0.504 -0.25)
			(stroke
				(width 0.15)
				(type solid)
			)
			(layer "F.Fab")
		)
		(fp_line
			(start 0.504 -0.25)
			(end 0.504 0.248)
			(stroke
				(width 0.15)
				(type solid)
			)
			(layer "F.Fab")
		)
		(fp_text user "License: Apache-2.0"
			(at -0.939 5.799 90)
			(layer "F.Fab")
			(effects
				(font
					(size 0.7 0.7)
					(thickness 0.15)
				)
				(justify right top)
			)
		)
		(fp_text user "Author: Antmicro"
			(at -0.939 3.399 90)
			(layer "F.Fab")
			(effects
				(font
					(size 0.7 0.7)
					(thickness 0.15)
				)
				(justify right top)
			)
		)
		(fp_text user "${REFERENCE}"
			(at -0.939 4.599 90)
			(layer "F.Fab")
			(effects
				(font
					(size 0.7 0.7)
					(thickness 0.15)
				)
				(justify right top)
			)
		)
		(pad "1" smd roundrect
			(at -0.48 0 270)
			(size 0.59 0.64)
			(layers "F.Cu" "F.Mask" "F.Paste")
			(roundrect_rratio 0.25)
			(net 1 "GND")
			(pintype "passive")
		)
		(pad "2" smd roundrect
			(at 0.48 0 270)
			(size 0.59 0.64)
			(layers "F.Cu" "F.Mask" "F.Paste")
			(roundrect_rratio 0.25)
			(net 282 "+1V15")
			(pintype "passive")
		)
	)
	(footprint "antmicro-footprints:C_0402_1005Metric"
		(layer "F.Cu")
		(at 91.1 92.7)
		(descr "Capacitor SMD 0402")
		(tags "capacitor SMD 0402")
		(property "Reference" "C351"
			(at 1.1 0.5 0)
			(layer "F.SilkS")
			(effects
				(font
					(size 0.7 0.7)
					(thickness 0.15)
				)
				(justify left bottom)
			)
		)
		(property "Value" "C_100n_0402"
			(at -1.022927 2.155213 0)
			(layer "F.Fab")
			(effects
				(font
					(size 0.7 0.7)
					(thickness 0.15)
				)
				(justify left bottom)
			)
		)
		(property "Datasheet" "https://www.murata.com/products/productdetail?partno=GRM155R61H104KE14%23"
			(at 0 0 0)
			(layer "F.Fab")
			(hide yes)
			(effects
				(font
					(size 1.27 1.27)
					(thickness 0.15)
				)
			)
		)
		(property "Description" "SMD Multilayer Ceramic Capacitor, 0.1 µF, 50 V, 0402 [1005 Metric], ± 10%, X5R, GRM Series"
			(at 0 0 0)
			(layer "F.Fab")
			(hide yes)
			(effects
				(font
					(size 1.27 1.27)
					(thickness 0.15)
				)
			)
		)
		(property "Manufacturer" "Murata"
			(at 0 0 0)
			(unlocked yes)
			(layer "F.Fab")
			(hide yes)
			(effects
				(font
					(size 1 1)
					(thickness 0.15)
				)
			)
		)
		(property "MPN" "GRM155R61H104KE14D"
			(at 0 0 0)
			(unlocked yes)
			(layer "F.Fab")
			(hide yes)
			(effects
				(font
					(size 1 1)
					(thickness 0.15)
				)
			)
		)
		(property "Val" "100n"
			(at 0 0 0)
			(unlocked yes)
			(layer "F.Fab")
			(hide yes)
			(effects
				(font
					(size 1 1)
					(thickness 0.15)
				)
			)
		)
		(property "License" "Apache-2.0"
			(at 0 0 0)
			(unlocked yes)
			(layer "F.Fab")
			(hide yes)
			(effects
				(font
					(size 1 1)
					(thickness 0.15)
				)
			)
		)
		(property "Author" "Antmicro"
			(at 0 0 0)
			(unlocked yes)
			(layer "F.Fab")
			(hide yes)
			(effects
				(font
					(size 1 1)
					(thickness 0.15)
				)
			)
		)
		(property "Voltage" "50V"
			(at 0 0 0)
			(unlocked yes)
			(layer "F.Fab")
			(hide yes)
			(effects
				(font
					(size 1 1)
					(thickness 0.15)
				)
			)
		)
		(property "Dielectric" "X5R"
			(at 0 0 0)
			(unlocked yes)
			(layer "F.Fab")
			(hide yes)
			(effects
				(font
					(size 1 1)
					(thickness 0.15)
				)
			)
		)
		(sheetname "/SoM_IO2/")
		(sheetfile "som_io2.kicad_sch")
		(attr smd)
		(fp_poly
			(pts
				(xy -0.925 -0.47) (xy 0.925 -0.47) (xy 0.925 0.47) (xy -0.925 0.47)
			)
			(stroke
				(width 0.05)
				(type default)
			)
			(fill no)
			(layer "F.CrtYd")
		)
		(fp_line
			(start -0.494 -0.25)
			(end 0.504 -0.25)
			(stroke
				(width 0.15)
				(type solid)
			)
			(layer "F.Fab")
		)
		(fp_line
			(start -0.494 0.248)
			(end -0.494 -0.25)
			(stroke
				(width 0.15)
				(type solid)
			)
			(layer "F.Fab")
		)
		(fp_line
			(start 0.504 -0.25)
			(end 0.504 0.248)
			(stroke
				(width 0.15)
				(type solid)
			)
			(layer "F.Fab")
		)
		(fp_line
			(start 0.504 0.248)
			(end -0.494 0.248)
			(stroke
				(width 0.15)
				(type solid)
			)
			(layer "F.Fab")
		)
		(fp_text user "License: Apache-2.0"
			(at -0.939 5.799 0)
			(layer "F.Fab")
			(effects
				(font
					(size 0.7 0.7)
					(thickness 0.15)
				)
				(justify left bottom)
			)
		)
		(fp_text user "${REFERENCE}"
			(at -0.939 4.599 0)
			(layer "F.Fab")
			(effects
				(font
					(size 0.7 0.7)
					(thickness 0.15)
				)
				(justify left bottom)
			)
		)
		(fp_text user "Author: Antmicro"
			(at -0.939 3.399 0)
			(layer "F.Fab")
			(effects
				(font
					(size 0.7 0.7)
					(thickness 0.15)
				)
				(justify left bottom)
			)
		)
		(pad "1" smd roundrect
			(at -0.48 0)
			(size 0.59 0.64)
			(layers "F.Cu" "F.Mask" "F.Paste")
			(roundrect_rratio 0.25)
			(net 661 "/Expansion connector/DP3.TX3-")
			(pintype "passive")
		)
		(pad "2" smd roundrect
			(at 0.48 0)
			(size 0.59 0.64)
			(layers "F.Cu" "F.Mask" "F.Paste")
			(roundrect_rratio 0.25)
			(net 1271 "/SoM_IO2/DP3.TX3_C-")
			(pintype "passive")
		)
	)
	(footprint "antmicro-footprints:SOT-563"
		(layer "F.Cu")
		(at 145.604391 128.21 90)
		(property "Reference" "U7"
			(at 4.01 0.895609 0)
			(layer "F.SilkS")
			(effects
				(font
					(size 0.7 0.7)
					(thickness 0.15)
				)
				(justify right top)
			)
		)
		(property "Value" "TPS564247DRLR"
			(at 0 2 90)
			(layer "F.Fab")
			(effects
				(font
					(size 0.7 0.7)
					(thickness 0.15)
				)
				(justify left bottom)
			)
		)
		(property "Datasheet" "https://www.ti.com/lit/ds/symlink/tps564247.pdf?ts=1713526387938&ref_url=https%253A%252F%252Fwww.mouser.pl%252F"
			(at 0 0 90)
			(layer "F.Fab")
			(hide yes)
			(effects
				(font
					(size 1.27 1.27)
					(thickness 0.15)
				)
			)
		)
		(property "Description" "Switching Voltage Regulators 3-V to 16-V input voltage, 4-A FCCM mode, synchronous buck converter in SOT-563 package 6-SOT-5X3 -40 to 125"
			(at 0 0 90)
			(layer "F.Fab")
			(hide yes)
			(effects
				(font
					(size 1.27 1.27)
					(thickness 0.15)
				)
			)
		)
		(property "MPN" "TPS564247DRLR"
			(at 0 0 90)
			(unlocked yes)
			(layer "F.Fab")
			(hide yes)
			(effects
				(font
					(size 1 1)
					(thickness 0.15)
				)
			)
		)
		(property "Author" "Antmicro"
			(at 0 0 90)
			(unlocked yes)
			(layer "F.Fab")
			(hide yes)
			(effects
				(font
					(size 1 1)
					(thickness 0.15)
				)
			)
		)
		(property "License" "Apache-2.0"
			(at 0 0 90)
			(unlocked yes)
			(layer "F.Fab")
			(hide yes)
			(effects
				(font
					(size 1 1)
					(thickness 0.15)
				)
			)
		)
		(property "Manufacturer" "Texas Instruments"
			(at 0 0 90)
			(unlocked yes)
			(layer "F.Fab")
			(hide yes)
			(effects
				(font
					(size 1 1)
					(thickness 0.15)
				)
			)
		)
		(component_classes
			(class "DCDC_1V8")
		)
		(sheetname "/DCDC/")
		(sheetfile "dcdc.kicad_sch")
		(attr smd)
		(fp_line
			(start 0.776 -0.974)
			(end 0.526 -0.974)
			(stroke
				(width 0.15)
				(type solid)
			)
			(layer "F.SilkS")
		)
		(fp_line
			(start 0.776 -0.974)
			(end 0.776 -0.778)
			(stroke
				(width 0.15)
				(type solid)
			)
			(layer "F.SilkS")
		)
		(fp_line
			(start -0.499 -0.974)
			(end -0.724 -0.778)
			(stroke
				(width 0.15)
				(type solid)
			)
			(layer "F.SilkS")
		)
		(fp_line
			(start 0.776 0.776)
			(end 0.776 0.972)
			(stroke
				(width 0.15)
				(type solid)
			)
			(layer "F.SilkS")
		)
		(fp_line
			(start -0.778 0.776)
			(end -0.778 0.949)
			(stroke
				(width 0.15)
				(type solid)
			)
			(layer "F.SilkS")
		)
		(fp_line
			(start -0.778 0.949)
			(end -0.424 0.949)
			(stroke
				(width 0.15)
				(type solid)
			)
			(layer "F.SilkS")
		)
		(fp_line
			(start 0.776 0.972)
			(end 0.526 0.972)
			(stroke
				(width 0.15)
				(type solid)
			)
			(layer "F.SilkS")
		)
		(fp_circle
			(center -0.903 -0.999)
			(end -0.952 -0.95)
			(stroke
				(width 0.15)
				(type solid)
			)
			(fill yes)
			(layer "F.SilkS")
		)
		(fp_rect
			(start 1.19 -1.12)
			(end -1.2 1.1)
			(stroke
				(width 0.05)
				(type solid)
			)
			(fill no)
			(layer "F.CrtYd")
		)
		(fp_line
			(start 0.651 -0.849)
			(end 0.651 0.847)
			(stroke
				(width 0.15)
				(type solid)
			)
			(layer "F.Fab")
		)
		(fp_line
			(start -0.453 -0.849)
			(end 0.651 -0.849)
			(stroke
				(width 0.15)
				(type solid)
			)
			(layer "F.Fab")
		)
		(fp_line
			(start -0.453 -0.849)
			(end -0.653 -0.678)
			(stroke
				(width 0.15)
				(type solid)
			)
			(layer "F.Fab")
		)
		(fp_line
			(start -0.653 -0.678)
			(end -0.653 0.847)
			(stroke
				(width 0.15)
				(type solid)
			)
			(layer "F.Fab")
		)
		(fp_line
			(start 0.651 0.847)
			(end -0.653 0.847)
			(stroke
				(width 0.15)
				(type solid)
			)
			(layer "F.Fab")
		)
		(fp_text user "${REFERENCE}"
			(at -1.299 7.323 90)
			(layer "F.Fab")
			(effects
				(font
					(size 0.7 0.7)
					(thickness 0.15)
				)
				(justify left bottom)
			)
		)
		(fp_text user "License: Apache-2.0"
			(at -1.299 4.924 90)
			(layer "F.Fab")
			(effects
				(font
					(size 0.7 0.7)
					(thickness 0.15)
				)
				(justify left bottom)
			)
		)
		(fp_text user "Author: Antmicro"
			(at -1.299 6.124 90)
			(layer "F.Fab")
			(effects
				(font
					(size 0.7 0.7)
					(thickness 0.15)
				)
				(justify left bottom)
			)
		)
		(pad "1" smd roundrect
			(at -0.749 -0.499)
			(size 0.3 0.6)
			(layers "F.Cu" "F.Mask" "F.Paste")
			(roundrect_rratio 0.25)
			(net 5 "+5V")
			(pinfunction "V_{IN}")
			(pintype "power_in")
		)
		(pad "2" smd roundrect
			(at -0.749 0.001)
			(size 0.3 0.6)
			(layers "F.Cu" "F.Mask" "F.Paste")
			(roundrect_rratio 0.25)
			(net 1185 "/DCDC/1V8_SW")
			(pinfunction "SW")
			(pintype "passive")
		)
		(pad "3" smd roundrect
			(at -0.749 0.497)
			(size 0.3 0.6)
			(layers "F.Cu" "F.Mask" "F.Paste")
			(roundrect_rratio 0.25)
			(net 1 "GND")
			(pinfunction "GND")
			(pintype "power_in")
		)
		(pad "4" smd roundrect
			(at 0.747 0.497)
			(size 0.3 0.6)
			(layers "F.Cu" "F.Mask" "F.Paste")
			(roundrect_rratio 0.25)
			(net 1 "GND")
			(pinfunction "AGND")
			(pintype "power_in")
		)
		(pad "5" smd roundrect
			(at 0.747 0.001)
			(size 0.3 0.6)
			(layers "F.Cu" "F.Mask" "F.Paste")
			(roundrect_rratio 0.25)
			(net 1293 "/DCDC/CARRIER_PWR_ON")
			(pinfunction "EN")
			(pintype "passive")
		)
		(pad "6" smd roundrect
			(at 0.747 -0.499)
			(size 0.3 0.6)
			(layers "F.Cu" "F.Mask" "F.Paste")
			(roundrect_rratio 0.25)
			(net 1222 "/DCDC/1V8_FB")
			(pinfunction "FB")
			(pintype "passive")
		)
	)
	(footprint "antmicro-footprints:TP_SMD_0.75mm"
		(layer "F.Cu")
		(at 69.279 60.671 90)
		(property "Reference" "TP23"
			(at 0.45 3.17 0)
			(layer "F.SilkS")
			(effects
				(font
					(size 0.7 0.7)
					(thickness 0.15)
				)
				(justify right top)
			)
		)
		(property "Value" "TP_0.75mm_SMD"
			(at 0 1.2 90)
			(layer "F.Fab")
			(effects
				(font
					(size 0.7 0.7)
					(thickness 0.15)
				)
				(justify left bottom)
			)
		)
		(property "Description" "SMT test point"
			(at 0 0 90)
			(layer "F.Fab")
			(hide yes)
			(effects
				(font
					(size 1.27 1.27)
					(thickness 0.15)
				)
			)
		)
		(property "MPN" ""
			(at 0 0 90)
			(unlocked yes)
			(layer "F.Fab")
			(hide yes)
			(effects
				(font
					(size 1 1)
					(thickness 0.15)
				)
			)
		)
		(property "Manufacturer" ""
			(at 0 0 90)
			(unlocked yes)
			(layer "F.Fab")
			(hide yes)
			(effects
				(font
					(size 1 1)
					(thickness 0.15)
				)
			)
		)
		(property "Author" "Antmicro"
			(at 0 0 90)
			(unlocked yes)
			(layer "F.Fab")
			(hide yes)
			(effects
				(font
					(size 1 1)
					(thickness 0.15)
				)
			)
		)
		(property "License" "Apache-2.0"
			(at 0 0 90)
			(unlocked yes)
			(layer "F.Fab")
			(hide yes)
			(effects
				(font
					(size 1 1)
					(thickness 0.15)
				)
			)
		)
		(sheetname "/CSI/")
		(sheetfile "csi.kicad_sch")
		(attr exclude_from_pos_files exclude_from_bom)
		(fp_circle
			(center 0 0)
			(end 0.475 0)
			(stroke
				(width 0.05)
				(type default)
			)
			(fill no)
			(layer "F.CrtYd")
		)
		(fp_text user "License: Apache-2.0"
			(at -0.4 5.101 90)
			(layer "F.Fab")
			(effects
				(font
					(size 0.7 0.7)
					(thickness 0.15)
				)
				(justify left bottom)
			)
		)
		(fp_text user "Author: Antmicro"
			(at -0.4 3.901 90)
			(layer "F.Fab")
			(effects
				(font
					(size 0.7 0.7)
					(thickness 0.15)
				)
				(justify left bottom)
			)
		)
		(fp_text user "${REFERENCE}"
			(at -0.4 2.7 90)
			(layer "F.Fab")
			(effects
				(font
					(size 0.7 0.7)
					(thickness 0.15)
				)
				(justify left bottom)
			)
		)
		(pad "1" smd circle
			(at 0 0 90)
			(size 0.75 0.75)
			(layers "F.Cu" "F.Mask")
			(net 1047 "/CSI/MUX_I2C_5_SDA")
			(pinfunction "1")
			(pintype "passive")
		)
	)
	(footprint "antmicro-footprints:SOT-523"
		(layer "F.Cu")
		(at 140.89 133.46 -90)
		(property "Reference" "Q11"
			(at -1.16 5.69 90)
			(layer "F.SilkS")
			(effects
				(font
					(size 0.7 0.7)
					(thickness 0.15)
				)
				(justify right top)
			)
		)
		(property "Value" "DMG1012T-7"
			(at 0.1 1.824 90)
			(layer "F.Fab")
			(effects
				(font
					(size 0.7 0.7)
					(thickness 0.15)
				)
				(justify right top)
			)
		)
		(property "Datasheet" "https://www.diodes.com/assets/Datasheets/ds31783.pdf"
			(at 0 0 90)
			(layer "F.Fab")
			(hide yes)
			(effects
				(font
					(size 1.27 1.27)
					(thickness 0.15)
				)
			)
		)
		(property "Description" "Power MOSFET, N Channel, 20 V, 630 mA, 0.3 ohm, SOT-523, Surface Mount"
			(at 0 0 90)
			(layer "F.Fab")
			(hide yes)
			(effects
				(font
					(size 1.27 1.27)
					(thickness 0.15)
				)
			)
		)
		(property "MPN" "DMG1012T-7"
			(at 0 0 90)
			(unlocked yes)
			(layer "F.Fab")
			(hide yes)
			(effects
				(font
					(size 1 1)
					(thickness 0.15)
				)
			)
		)
		(property "Manufacturer" "Diodes Incorporated"
			(at 0 0 90)
			(unlocked yes)
			(layer "F.Fab")
			(hide yes)
			(effects
				(font
					(size 1 1)
					(thickness 0.15)
				)
			)
		)
		(property "Author" "Antmicro"
			(at 0 0 90)
			(unlocked yes)
			(layer "F.Fab")
			(hide yes)
			(effects
				(font
					(size 1 1)
					(thickness 0.15)
				)
			)
		)
		(property "License" "Apache-2.0"
			(at 0 0 90)
			(unlocked yes)
			(layer "F.Fab")
			(hide yes)
			(effects
				(font
					(size 1 1)
					(thickness 0.15)
				)
			)
		)
		(sheetname "/SoM_Power/")
		(sheetfile "som_power.kicad_sch")
		(attr smd)
		(fp_line
			(start -0.927 -0.051)
			(end -0.927 -0.351)
			(stroke
				(width 0.15)
				(type solid)
			)
			(layer "F.SilkS")
		)
		(fp_line
			(start -0.927 -0.351)
			(end -0.725 -0.551)
			(stroke
				(width 0.15)
				(type solid)
			)
			(layer "F.SilkS")
		)
		(fp_line
			(start -0.725 -0.551)
			(end -0.277 -0.551)
			(stroke
				(width 0.15)
				(type solid)
			)
			(layer "F.SilkS")
		)
		(fp_line
			(start -0.277 -0.551)
			(end -0.277 -0.75)
			(stroke
				(width 0.15)
				(type solid)
			)
			(layer "F.SilkS")
		)
		(fp_circle
			(center -0.9652 0.9652)
			(end -0.9152 0.9652)
			(stroke
				(width 0.15)
				(type solid)
			)
			(fill yes)
			(layer "F.SilkS")
		)
		(fp_line
			(start -1.12 1.15)
			(end 1.1 1.15)
			(stroke
				(width 0.05)
				(type solid)
			)
			(layer "F.CrtYd")
		)
		(fp_line
			(start -1.12 -1.16)
			(end -1.12 1.15)
			(stroke
				(width 0.05)
				(type solid)
			)
			(layer "F.CrtYd")
		)
		(fp_line
			(start -1.12 -1.16)
			(end 1.1 -1.16)
			(stroke
				(width 0.05)
				(type solid)
			)
			(layer "F.CrtYd")
		)
		(fp_line
			(start 1.1 -1.16)
			(end 1.1 1.15)
			(stroke
				(width 0.05)
				(type solid)
			)
			(layer "F.CrtYd")
		)
		(fp_line
			(start 0.8 0.424)
			(end -0.802 0.424)
			(stroke
				(width 0.15)
				(type solid)
			)
			(layer "F.Fab")
		)
		(fp_line
			(start -0.802 -0.276)
			(end -0.802 0.424)
			(stroke
				(width 0.15)
				(type solid)
			)
			(layer "F.Fab")
		)
		(fp_line
			(start -0.652 -0.425)
			(end -0.802 -0.276)
			(stroke
				(width 0.15)
				(type solid)
			)
			(layer "F.Fab")
		)
		(fp_line
			(start 0.8 -0.425)
			(end 0.8 0.424)
			(stroke
				(width 0.15)
				(type solid)
			)
			(layer "F.Fab")
		)
		(fp_line
			(start 0.8 -0.425)
			(end -0.652 -0.425)
			(stroke
				(width 0.15)
				(type solid)
			)
			(layer "F.Fab")
		)
		(fp_circle
			(center -0.9652 0.9652)
			(end -0.9144 0.9652)
			(stroke
				(width 0.15)
				(type solid)
			)
			(fill no)
			(layer "F.Fab")
		)
		(fp_text user "${REFERENCE}"
			(at -1.12 3.824 90)
			(layer "F.Fab")
			(effects
				(font
					(size 0.7 0.7)
					(thickness 0.15)
				)
				(justify right top)
			)
		)
		(fp_text user "Author: Antmicro"
			(at -1.12 6.224 90)
			(layer "F.Fab")
			(effects
				(font
					(size 0.7 0.7)
					(thickness 0.15)
				)
				(justify right top)
			)
		)
		(fp_text user "License: Apache-2.0"
			(at -1.12 5.024 90)
			(layer "F.Fab")
			(effects
				(font
					(size 0.7 0.7)
					(thickness 0.15)
				)
				(justify right top)
			)
		)
		(pad "1" smd rect
			(at -0.5 0.65 270)
			(size 0.4 0.51)
			(layers "F.Cu" "F.Mask" "F.Paste")
			(net 883 "Net-(Q10-G)")
			(pinfunction "G")
			(pintype "input")
		)
		(pad "2" smd rect
			(at 0.498 0.65 270)
			(size 0.4 0.51)
			(layers "F.Cu" "F.Mask" "F.Paste")
			(net 1 "GND")
			(pinfunction "S")
			(pintype "passive")
		)
		(pad "3" smd rect
			(at 0 -0.652 270)
			(size 0.4 0.51)
			(layers "F.Cu" "F.Mask" "F.Paste")
			(net 886 "Net-(Q11-D)")
			(pinfunction "D")
			(pintype "passive")
		)
	)
	(footprint "antmicro-footprints:VQFN-24-1EP_3.8x3.8x1.0mm_P0.5mm"
		(layer "F.Cu")
		(at 65.571 62.049 90)
		(property "Reference" "U43"
			(at -3.551 0.229 180)
			(layer "F.SilkS")
			(effects
				(font
					(size 0.7 0.7)
					(thickness 0.15)
				)
				(justify left bottom)
			)
		)
		(property "Value" "PI4MSD5V9548AZDEX"
			(at 0 3.6 90)
			(layer "F.Fab")
			(effects
				(font
					(size 0.7 0.7)
					(thickness 0.15)
				)
				(justify right top)
			)
		)
		(property "Datasheet" "https://www.mouser.com/datasheet/2/115/DIOD_S_A0003139195_1-2542233.pdf"
			(at 0 0 90)
			(layer "F.Fab")
			(hide yes)
			(effects
				(font
					(size 1.27 1.27)
					(thickness 0.15)
				)
			)
		)
		(property "Description" "Logic signal switch/multiplexer/decoder"
			(at 0 0 90)
			(layer "F.Fab")
			(hide yes)
			(effects
				(font
					(size 1.27 1.27)
					(thickness 0.15)
				)
			)
		)
		(property "Manufacturer" "Diodes Incorporated"
			(at 0 0 90)
			(unlocked yes)
			(layer "F.Fab")
			(hide yes)
			(effects
				(font
					(size 1 1)
					(thickness 0.15)
				)
			)
		)
		(property "MPN" "PI4MSD5V9548AZDEX"
			(at 0 0 90)
			(unlocked yes)
			(layer "F.Fab")
			(hide yes)
			(effects
				(font
					(size 1 1)
					(thickness 0.15)
				)
			)
		)
		(property "Author" "Antmicro"
			(at 0 0 90)
			(unlocked yes)
			(layer "F.Fab")
			(hide yes)
			(effects
				(font
					(size 1 1)
					(thickness 0.15)
				)
			)
		)
		(property "License" "Apache-2.0"
			(at 0 0 90)
			(unlocked yes)
			(layer "F.Fab")
			(hide yes)
			(effects
				(font
					(size 1 1)
					(thickness 0.15)
				)
			)
		)
		(sheetname "/CSI/")
		(sheetfile "csi.kicad_sch")
		(attr smd)
		(fp_line
			(start 1.904 -1.905)
			(end 1.523 -1.905)
			(stroke
				(width 0.15)
				(type solid)
			)
			(layer "F.SilkS")
		)
		(fp_line
			(start 1.904 -1.524)
			(end 1.904 -1.905)
			(stroke
				(width 0.15)
				(type solid)
			)
			(layer "F.SilkS")
		)
		(fp_line
			(start -1.905 -1.524)
			(end -1.524 -1.905)
			(stroke
				(width 0.15)
				(type solid)
			)
			(layer "F.SilkS")
		)
		(fp_line
			(start -1.905 1.523)
			(end -1.905 1.904)
			(stroke
				(width 0.15)
				(type solid)
			)
			(layer "F.SilkS")
		)
		(fp_line
			(start 1.904 1.904)
			(end 1.904 1.523)
			(stroke
				(width 0.15)
				(type solid)
			)
			(layer "F.SilkS")
		)
		(fp_line
			(start 1.523 1.904)
			(end 1.904 1.904)
			(stroke
				(width 0.15)
				(type solid)
			)
			(layer "F.SilkS")
		)
		(fp_line
			(start -1.905 1.904)
			(end -1.524 1.904)
			(stroke
				(width 0.15)
				(type solid)
			)
			(layer "F.SilkS")
		)
		(fp_circle
			(center -2.2 -2.2)
			(end -2.15 -2.2)
			(stroke
				(width 0.15)
				(type solid)
			)
			(fill yes)
			(layer "F.SilkS")
		)
		(fp_rect
			(start -2.5 -2.5)
			(end 2.5 2.5)
			(stroke
				(width 0.05)
				(type solid)
			)
			(fill no)
			(layer "F.CrtYd")
		)
		(fp_line
			(start -1.905 -1.524)
			(end -1.524 -1.905)
			(stroke
				(width 0.15)
				(type solid)
			)
			(layer "F.Fab")
		)
		(fp_rect
			(start -1.905 1.904)
			(end 1.904 -1.905)
			(stroke
				(width 0.15)
				(type solid)
			)
			(fill no)
			(layer "F.Fab")
		)
		(fp_text user "${REFERENCE}"
			(at -2.5 4.99 90)
			(layer "F.Fab")
			(effects
				(font
					(size 0.7 0.7)
					(thickness 0.15)
				)
				(justify left bottom)
			)
		)
		(fp_text user "Author: Antmicro"
			(at -2.5 6.35 90)
			(layer "F.Fab")
			(effects
				(font
					(size 0.7 0.7)
					(thickness 0.15)
				)
				(justify left bottom)
			)
		)
		(fp_text user "License: Apache-2.0"
			(at -2.5 7.53 90)
			(layer "F.Fab")
			(effects
				(font
					(size 0.7 0.7)
					(thickness 0.15)
				)
				(justify left bottom)
			)
		)
		(pad "1" smd roundrect
			(at -1.901 -1.25 180)
			(size 0.25 0.6)
			(layers "F.Cu" "F.Mask" "F.Paste")
			(roundrect_rratio 0.25)
			(net 987 "/CSI/SDA_CAM0")
			(pinfunction "SD0")
			(pintype "bidirectional")
		)
		(pad "2" smd roundrect
			(at -1.901 -0.75 180)
			(size 0.25 0.6)
			(layers "F.Cu" "F.Mask" "F.Paste")
			(roundrect_rratio 0.25)
			(net 985 "/CSI/SCL_CAM0")
			(pinfunction "SC0")
			(pintype "bidirectional")
		)
		(pad "3" smd roundrect
			(at -1.901 -0.25 180)
			(size 0.25 0.6)
			(layers "F.Cu" "F.Mask" "F.Paste")
			(roundrect_rratio 0.25)
			(net 986 "/CSI/SDA_CAM1")
			(pinfunction "SD1")
			(pintype "bidirectional")
		)
		(pad "4" smd roundrect
			(at -1.901 0.248 180)
			(size 0.25 0.6)
			(layers "F.Cu" "F.Mask" "F.Paste")
			(roundrect_rratio 0.25)
			(net 988 "/CSI/SCL_CAM1")
			(pinfunction "SC1")
			(pintype "bidirectional")
		)
		(pad "5" smd roundrect
			(at -1.901 0.748 180)
			(size 0.25 0.6)
			(layers "F.Cu" "F.Mask" "F.Paste")
			(roundrect_rratio 0.25)
			(net 993 "/CSI/SDA_CAM2")
			(pinfunction "SD2")
			(pintype "bidirectional")
		)
		(pad "6" smd roundrect
			(at -1.901 1.249 180)
			(size 0.25 0.6)
			(layers "F.Cu" "F.Mask" "F.Paste")
			(roundrect_rratio 0.25)
			(net 994 "/CSI/SCL_CAM2")
			(pinfunction "SC2")
			(pintype "bidirectional")
		)
		(pad "7" smd roundrect
			(at -1.252 1.898 270)
			(size 0.25 0.6)
			(layers "F.Cu" "F.Mask" "F.Paste")
			(roundrect_rratio 0.25)
			(net 991 "/CSI/SDA_CAM3")
			(pinfunction "SD3")
			(pintype "bidirectional")
		)
		(pad "8" smd roundrect
			(at -0.751 1.898 270)
			(size 0.25 0.6)
			(layers "F.Cu" "F.Mask" "F.Paste")
			(roundrect_rratio 0.25)
			(net 992 "/CSI/SCL_CAM3")
			(pinfunction "SC3")
			(pintype "bidirectional")
		)
		(pad "9" smd roundrect
			(at -0.25 1.898 270)
			(size 0.25 0.6)
			(layers "F.Cu" "F.Mask" "F.Paste")
			(roundrect_rratio 0.25)
			(net 1 "GND")
			(pinfunction "GND")
			(pintype "power_in")
		)
		(pad "10" smd roundrect
			(at 0.248 1.898 270)
			(size 0.25 0.6)
			(layers "F.Cu" "F.Mask" "F.Paste")
			(roundrect_rratio 0.25)
			(net 1045 "/CSI/MUX_I2C_4_SDA")
			(pinfunction "SD4")
			(pintype "bidirectional")
		)
		(pad "11" smd roundrect
			(at 0.748 1.898 270)
			(size 0.25 0.6)
			(layers "F.Cu" "F.Mask" "F.Paste")
			(roundrect_rratio 0.25)
			(net 1046 "/CSI/MUX_I2C_4_SCL")
			(pinfunction "SC4")
			(pintype "bidirectional")
		)
		(pad "12" smd roundrect
			(at 1.249 1.898 270)
			(size 0.25 0.6)
			(layers "F.Cu" "F.Mask" "F.Paste")
			(roundrect_rratio 0.25)
			(net 1047 "/CSI/MUX_I2C_5_SDA")
			(pinfunction "SD5")
			(pintype "bidirectional")
		)
		(pad "13" smd roundrect
			(at 1.898 1.249)
			(size 0.25 0.6)
			(layers "F.Cu" "F.Mask" "F.Paste")
			(roundrect_rratio 0.25)
			(net 1048 "/CSI/MUX_I2C_5_SCL")
			(pinfunction "SC5")
			(pintype "bidirectional")
		)
		(pad "14" smd roundrect
			(at 1.898 0.748)
			(size 0.25 0.6)
			(layers "F.Cu" "F.Mask" "F.Paste")
			(roundrect_rratio 0.25)
			(net 1049 "/CSI/MUX_I2C_6_SDA")
			(pinfunction "SD6")
			(pintype "bidirectional")
		)
		(pad "15" smd roundrect
			(at 1.898 0.248)
			(size 0.25 0.6)
			(layers "F.Cu" "F.Mask" "F.Paste")
			(roundrect_rratio 0.25)
			(net 1050 "/CSI/MUX_I2C_6_SCL")
			(pinfunction "SC6")
			(pintype "bidirectional")
		)
		(pad "16" smd roundrect
			(at 1.898 -0.25)
			(size 0.25 0.6)
			(layers "F.Cu" "F.Mask" "F.Paste")
			(roundrect_rratio 0.25)
			(net 1051 "/CSI/MUX_I2C_7_SDA")
			(pinfunction "SD7")
			(pintype "bidirectional")
		)
		(pad "17" smd roundrect
			(at 1.898 -0.75)
			(size 0.25 0.6)
			(layers "F.Cu" "F.Mask" "F.Paste")
			(roundrect_rratio 0.25)
			(net 1052 "/CSI/MUX_I2C_7_SCL")
			(pinfunction "SC7")
			(pintype "bidirectional")
		)
		(pad "18" smd roundrect
			(at 1.898 -1.252)
			(size 0.25 0.6)
			(layers "F.Cu" "F.Mask" "F.Paste")
			(roundrect_rratio 0.25)
			(net 1 "GND")
			(pinfunction "A2")
			(pintype "input")
		)
		(pad "19" smd roundrect
			(at 1.249 -1.901 90)
			(size 0.25 0.6)
			(layers "F.Cu" "F.Mask" "F.Paste")
			(roundrect_rratio 0.25)
			(net 984 "/CSI/I2C_MUX_SCL")
			(pinfunction "SCL")
			(pintype "bidirectional")
		)
		(pad "20" smd roundrect
			(at 0.748 -1.901 90)
			(size 0.25 0.6)
			(layers "F.Cu" "F.Mask" "F.Paste")
			(roundrect_rratio 0.25)
			(net 982 "/CSI/I2C_MUX_SDA")
			(pinfunction "SDA")
			(pintype "bidirectional")
		)
		(pad "21" smd roundrect
			(at 0.248 -1.901 90)
			(size 0.25 0.6)
			(layers "F.Cu" "F.Mask" "F.Paste")
			(roundrect_rratio 0.25)
			(net 11 "+1V8")
			(pinfunction "VCC")
			(pintype "power_in")
		)
		(pad "22" smd roundrect
			(at -0.25 -1.901 90)
			(size 0.25 0.6)
			(layers "F.Cu" "F.Mask" "F.Paste")
			(roundrect_rratio 0.25)
			(net 980 "/CSI/I2C_MUX_A0")
			(pinfunction "A0")
			(pintype "input")
		)
		(pad "23" smd roundrect
			(at -0.75 -1.901 90)
			(size 0.25 0.6)
			(layers "F.Cu" "F.Mask" "F.Paste")
			(roundrect_rratio 0.25)
			(net 1 "GND")
			(pinfunction "A1")
			(pintype "input")
		)
		(pad "24" smd roundrect
			(at -1.252 -1.901 90)
			(size 0.25 0.6)
			(layers "F.Cu" "F.Mask" "F.Paste")
			(roundrect_rratio 0.25)
			(net 989 "/CSI/I2C_MUX_RESET")
			(pinfunction "~{RESET}")
			(pintype "input")
		)
		(pad "25" smd roundrect
			(at 0 -0.001 90)
			(size 2.1 2.1)
			(layers "F.Cu" "F.Mask" "F.Paste")
			(roundrect_rratio 0.05)
			(net 1120 "unconnected-(U43-EP-Pad25)")
			(pinfunction "EP")
			(pintype "power_in+no_connect")
		)
	)
	(footprint "antmicro-footprints:USB-C_Receptacle_Kycon_KUSBX-SL2-CS1N24-B-TR"
		(locked yes)
		(layer "F.Cu")
		(at 236.455532 89.21 90)
		(descr "USB-C (USB TYPE-C) USB 3.2 Gen 2 (USB 3.1 Gen 2, Superspeed + (USB 3.1)) Receptacle Connector 24 Position Through Hole, Right Angle")
		(tags "CONNECTOR, USB")
		(property "Reference" "J9"
			(at 3.21 -10.785532 180)
			(layer "F.SilkS")
			(effects
				(font
					(size 0.7 0.7)
					(thickness 0.15)
				)
				(justify left bottom)
			)
		)
		(property "Value" "USB-C_Kycon_KUSBX-SL2-CS1N24-B-TR"
			(at 0 7.5 90)
			(layer "F.Fab")
			(effects
				(font
					(size 0.7 0.7)
					(thickness 0.15)
				)
				(justify right top)
			)
		)
		(property "Datasheet" "https://www.kycon.com/Pub_Eng_Draw/KUSBX-SL2-CS1N24-B-TR.pdf"
			(at 0 0 90)
			(layer "F.Fab")
			(hide yes)
			(effects
				(font
					(size 1.27 1.27)
					(thickness 0.15)
				)
			)
		)
		(property "Description" "USB-C (USB TYPE-C) USB 3.2 Gen 2 (USB 3.1 Gen 2, Superspeed + (USB 3.1)) USB PD Receptacle Connector 24 Position Surface Mount"
			(at 0 0 90)
			(layer "F.Fab")
			(hide yes)
			(effects
				(font
					(size 1.27 1.27)
					(thickness 0.15)
				)
			)
		)
		(property "MPN" "KUSBX-SL2-CS1N24-B-TR"
			(at 0 0 90)
			(unlocked yes)
			(layer "F.Fab")
			(hide yes)
			(effects
				(font
					(size 1 1)
					(thickness 0.15)
				)
			)
		)
		(property "Manufacturer" "Kycon"
			(at 0 0 90)
			(unlocked yes)
			(layer "F.Fab")
			(hide yes)
			(effects
				(font
					(size 1 1)
					(thickness 0.15)
				)
			)
		)
		(property "License" "Apache-2.0"
			(at 0 0 90)
			(unlocked yes)
			(layer "F.Fab")
			(hide yes)
			(effects
				(font
					(size 1 1)
					(thickness 0.15)
				)
			)
		)
		(property "Author" "Antmicro"
			(at 0 0 90)
			(unlocked yes)
			(layer "F.Fab")
			(hide yes)
			(effects
				(font
					(size 1 1)
					(thickness 0.15)
				)
			)
		)
		(sheetname "/USB DP Alt mode/")
		(sheetfile "usb_dp.kicad_sch")
		(attr smd)
		(fp_line
			(start 1 -8.8)
			(end 1 -8.8)
			(stroke
				(width 0.15)
				(type solid)
			)
			(layer "F.SilkS")
		)
		(fp_line
			(start 1 -8.8)
			(end -1 -8.8)
			(stroke
				(width 0.15)
				(type solid)
			)
			(layer "F.SilkS")
		)
		(fp_line
			(start -1 -8.8)
			(end 1 -8.8)
			(stroke
				(width 0.15)
				(type solid)
			)
			(layer "F.SilkS")
		)
		(fp_line
			(start -1 -8.8)
			(end -1 -8.8)
			(stroke
				(width 0.15)
				(type solid)
			)
			(layer "F.SilkS")
		)
		(fp_rect
			(start -4 -9.4)
			(end 4 5.65)
			(stroke
				(width 0.05)
				(type solid)
			)
			(fill no)
			(layer "F.CrtYd")
		)
		(fp_line
			(start 2.25 -8.8)
			(end -2.25 -8.8)
			(stroke
				(width 0.15)
				(type solid)
			)
			(layer "F.Fab")
		)
		(fp_line
			(start -2.25 -8.8)
			(end -2.25 5.5)
			(stroke
				(width 0.15)
				(type solid)
			)
			(layer "F.Fab")
		)
		(fp_line
			(start 2.25 5.5)
			(end 2.25 -8.8)
			(stroke
				(width 0.15)
				(type solid)
			)
			(layer "F.Fab")
		)
		(fp_line
			(start -2.25 5.5)
			(end 2.25 5.5)
			(stroke
				(width 0.15)
				(type solid)
			)
			(layer "F.Fab")
		)
		(fp_text user "License: Apache-2.0"
			(at -5.47 10.9 90)
			(layer "F.Fab")
			(effects
				(font
					(size 0.7 0.7)
					(thickness 0.15)
				)
				(justify left bottom)
			)
		)
		(fp_text user "${REFERENCE}"
			(at -5.47 8.5 90)
			(layer "F.Fab")
			(effects
				(font
					(size 0.7 0.7)
					(thickness 0.15)
				)
				(justify left bottom)
			)
		)
		(fp_text user "Author: Antmicro"
			(at -5.47 9.7 90)
			(layer "F.Fab")
			(effects
				(font
					(size 0.7 0.7)
					(thickness 0.15)
				)
				(justify left bottom)
			)
		)
		(pad "" np_thru_hole circle
			(at 0 -7.6 90)
			(size 1.1 1.1)
			(drill 1.1)
			(layers "*.Cu" "*.Mask")
		)
		(pad "" np_thru_hole circle
			(at 0 0 90)
			(size 1 1)
			(drill 1)
			(layers "*.Cu" "*.Mask")
		)
		(pad "A1" smd rect
			(at 1.1375 -6.525 180)
			(size 0.25 1.625)
			(layers "F.Cu" "F.Mask" "F.Paste")
			(net 1 "GND")
			(pinfunction "GND")
			(pintype "power_in")
		)
		(pad "A2" smd rect
			(at 1.1375 -6.025 180)
			(size 0.25 1.625)
			(layers "F.Cu" "F.Mask" "F.Paste")
			(net 345 "/USB DP Alt mode/USBC1_CONN_TX1_P")
			(pinfunction "TX_{1}+")
			(pintype "bidirectional")
		)
		(pad "A3" smd rect
			(at 1.1375 -5.525 180)
			(size 0.25 1.625)
			(layers "F.Cu" "F.Mask" "F.Paste")
			(net 361 "/USB DP Alt mode/USBC1_CONN_TX1_N")
			(pinfunction "TX_{1}-")
			(pintype "bidirectional")
		)
		(pad "A4" smd rect
			(at 1.1375 -5.025 180)
			(size 0.25 1.625)
			(layers "F.Cu" "F.Mask" "F.Paste")
			(net 376 "/USB DP Alt mode/USBC1_VBUS")
			(pinfunction "VBUS")
			(pintype "power_in")
		)
		(pad "A5" smd rect
			(at 1.1375 -4.525 180)
			(size 0.25 1.625)
			(layers "F.Cu" "F.Mask" "F.Paste")
			(net 817 "/USB DP Alt mode/USBC1_CC1")
			(pinfunction "CC_{1}")
			(pintype "bidirectional")
		)
		(pad "A6" smd rect
			(at 1.1375 -4.025 180)
			(size 0.25 1.625)
			(layers "F.Cu" "F.Mask" "F.Paste")
			(net 55 "/SoM_IO2/USB1.D+")
			(pinfunction "D_{A}+")
			(pintype "bidirectional")
		)
		(pad "A7" smd rect
			(at 1.1375 -3.525 180)
			(size 0.25 1.625)
			(layers "F.Cu" "F.Mask" "F.Paste")
			(net 140 "/SoM_IO2/USB1.D-")
			(pinfunction "D_{A}-")
			(pintype "bidirectional")
		)
		(pad "A8" smd rect
			(at 1.1375 -3.025 180)
			(size 0.25 1.625)
			(layers "F.Cu" "F.Mask" "F.Paste")
			(net 821 "/USB DP Alt mode/USBC1_SBU_N")
			(pinfunction "SBU_{1}")
			(pintype "bidirectional")
		)
		(pad "A9" smd rect
			(at 1.1375 -2.525 180)
			(size 0.25 1.625)
			(layers "F.Cu" "F.Mask" "F.Paste")
			(net 376 "/USB DP Alt mode/USBC1_VBUS")
			(pinfunction "VBUS")
			(pintype "passive")
		)
		(pad "A10" smd rect
			(at 1.1375 -2.025 180)
			(size 0.25 1.625)
			(layers "F.Cu" "F.Mask" "F.Paste")
			(net 820 "/USB DP Alt mode/USBC1_RX2_N")
			(pinfunction "RX_{2}-")
			(pintype "bidirectional")
		)
		(pad "A11" smd rect
			(at 1.1375 -1.525 180)
			(size 0.25 1.625)
			(layers "F.Cu" "F.Mask" "F.Paste")
			(net 818 "/USB DP Alt mode/USBC1_RX2_P")
			(pinfunction "RX_{2}+")
			(pintype "bidirectional")
		)
		(pad "A12" smd rect
			(at 1.1375 -1.025 180)
			(size 0.25 1.625)
			(layers "F.Cu" "F.Mask" "F.Paste")
			(net 1 "GND")
			(pinfunction "GND")
			(pintype "passive")
		)
		(pad "B1" smd rect
			(at -1.1375 -1.025 180)
			(size 0.25 1.625)
			(layers "F.Cu" "F.Mask" "F.Paste")
			(net 1 "GND")
			(pinfunction "GND")
			(pintype "passive")
		)
		(pad "B2" smd rect
			(at -1.1375 -1.525 180)
			(size 0.25 1.625)
			(layers "F.Cu" "F.Mask" "F.Paste")
			(net 347 "/USB DP Alt mode/USBC1_CONN_TX2_P")
			(pinfunction "TX_{2}+")
			(pintype "bidirectional")
		)
		(pad "B3" smd rect
			(at -1.1375 -2.025 180)
			(size 0.25 1.625)
			(layers "F.Cu" "F.Mask" "F.Paste")
			(net 374 "/USB DP Alt mode/USBC1_CONN_TX2_N")
			(pinfunction "TX_{2}-")
			(pintype "bidirectional")
		)
		(pad "B4" smd rect
			(at -1.1375 -2.525 180)
			(size 0.25 1.625)
			(layers "F.Cu" "F.Mask" "F.Paste")
			(net 376 "/USB DP Alt mode/USBC1_VBUS")
			(pinfunction "VBUS")
			(pintype "passive")
		)
		(pad "B5" smd rect
			(at -1.1375 -3.025 180)
			(size 0.25 1.625)
			(layers "F.Cu" "F.Mask" "F.Paste")
			(net 816 "/USB DP Alt mode/USBC1_CC2")
			(pinfunction "CC_{2}")
			(pintype "bidirectional")
		)
		(pad "B6" smd rect
			(at -1.1375 -3.525 180)
			(size 0.25 1.625)
			(layers "F.Cu" "F.Mask" "F.Paste")
			(net 55 "/SoM_IO2/USB1.D+")
			(pinfunction "D_{B}+")
			(pintype "bidirectional")
		)
		(pad "B7" smd rect
			(at -1.1375 -4.025 180)
			(size 0.25 1.625)
			(layers "F.Cu" "F.Mask" "F.Paste")
			(net 140 "/SoM_IO2/USB1.D-")
			(pinfunction "D_{B}-")
			(pintype "bidirectional")
		)
		(pad "B8" smd rect
			(at -1.1375 -4.525 180)
			(size 0.25 1.625)
			(layers "F.Cu" "F.Mask" "F.Paste")
			(net 815 "/USB DP Alt mode/USBC1_SBU_P")
			(pinfunction "SBU_{2}")
			(pintype "bidirectional")
		)
		(pad "B9" smd rect
			(at -1.1375 -5.025 180)
			(size 0.25 1.625)
			(layers "F.Cu" "F.Mask" "F.Paste")
			(net 376 "/USB DP Alt mode/USBC1_VBUS")
			(pinfunction "VBUS")
			(pintype "passive")
		)
		(pad "B10" smd rect
			(at -1.1375 -5.525 180)
			(size 0.25 1.625)
			(layers "F.Cu" "F.Mask" "F.Paste")
			(net 819 "/USB DP Alt mode/USBC1_RX1_N")
			(pinfunction "RX_{1}-")
			(pintype "bidirectional")
		)
		(pad "B11" smd rect
			(at -1.1375 -6.025 180)
			(size 0.25 1.625)
			(layers "F.Cu" "F.Mask" "F.Paste")
			(net 822 "/USB DP Alt mode/USBC1_RX1_P")
			(pinfunction "RX_{1}+")
			(pintype "bidirectional")
		)
		(pad "B12" smd rect
			(at -1.1375 -6.525 180)
			(size 0.25 1.625)
			(layers "F.Cu" "F.Mask" "F.Paste")
			(net 1 "GND")
			(pinfunction "GND")
			(pintype "passive")
		)
		(pad "SH" thru_hole oval
			(at -3 -7.849 90)
			(size 1 2.05)
			(drill oval 0.6 1.65)
			(layers "*.Cu" "*.Mask")
			(remove_unused_layers no)
			(net 1 "GND")
			(pinfunction "SH")
			(pintype "passive")
		)
		(pad "SH" thru_hole oval
			(at -3 0.25 90)
			(size 1 2.05)
			(drill oval 0.6 1.65)
			(layers "*.Cu" "*.Mask")
			(remove_unused_layers no)
			(net 1 "GND")
			(pinfunction "SH")
			(pintype "passive")
		)
		(pad "SH" thru_hole oval
			(at 3 -7.849 90)
			(size 1 2.05)
			(drill oval 0.6 1.65)
			(layers "*.Cu" "*.Mask")
			(remove_unused_layers no)
			(net 1 "GND")
			(pinfunction "SH")
			(pintype "passive")
		)
		(pad "SH" thru_hole oval
			(at 3 0.25 90)
			(size 1 2.05)
			(drill oval 0.6 1.65)
			(layers "*.Cu" "*.Mask")
			(remove_unused_layers no)
			(net 1 "GND")
			(pinfunction "SH")
			(pintype "passive")
		)
	)
	(footprint "antmicro-footprints:SOD-523"
		(layer "F.Cu")
		(at 171.7 113.999 90)
		(property "Reference" "D8"
			(at 0.999 -0.8 180)
			(layer "F.SilkS")
			(effects
				(font
					(size 0.7 0.7)
					(thickness 0.15)
				)
				(justify left bottom)
			)
		)
		(property "Value" "PESD5Z5.0F"
			(at 0 1.499 90)
			(layer "F.Fab")
			(effects
				(font
					(size 0.7 0.7)
					(thickness 0.15)
				)
				(justify left bottom)
			)
		)
		(property "Datasheet" "https://assets.nexperia.com/documents/data-sheet/PESD5Z5_0.pdf"
			(at 0 0 90)
			(layer "F.Fab")
			(hide yes)
			(effects
				(font
					(size 1.27 1.27)
					(thickness 0.15)
				)
			)
		)
		(property "Description" "Unidirectional TVS, 30 kV,  SOD-523, 5 V, 89 pF"
			(at 0 0 90)
			(layer "F.Fab")
			(hide yes)
			(effects
				(font
					(size 1.27 1.27)
					(thickness 0.15)
				)
			)
		)
		(property "Manufacturer" "Nexperia"
			(at 0 0 90)
			(unlocked yes)
			(layer "F.Fab")
			(hide yes)
			(effects
				(font
					(size 1 1)
					(thickness 0.15)
				)
			)
		)
		(property "MPN" "PESD5Z5.0F"
			(at 0 0 90)
			(unlocked yes)
			(layer "F.Fab")
			(hide yes)
			(effects
				(font
					(size 1 1)
					(thickness 0.15)
				)
			)
		)
		(property "Author" "Antmicro"
			(at 0 0 90)
			(unlocked yes)
			(layer "F.Fab")
			(hide yes)
			(effects
				(font
					(size 1 1)
					(thickness 0.15)
				)
			)
		)
		(property "License" "Apache-2.0"
			(at 0 0 90)
			(unlocked yes)
			(layer "F.Fab")
			(hide yes)
			(effects
				(font
					(size 1 1)
					(thickness 0.15)
				)
			)
		)
		(sheetname "/DCDC/")
		(sheetfile "dcdc.kicad_sch")
		(attr smd)
		(fp_line
			(start -0.35 -0.5)
			(end -0.35 0.5)
			(stroke
				(width 0.15)
				(type solid)
			)
			(layer "F.SilkS")
		)
		(fp_rect
			(start -1 -0.6)
			(end 1 0.6)
			(stroke
				(width 0.05)
				(type solid)
			)
			(fill no)
			(layer "F.CrtYd")
		)
		(fp_line
			(start 0.65 -0.425)
			(end 0.65 0.423)
			(stroke
				(width 0.15)
				(type solid)
			)
			(layer "F.Fab")
		)
		(fp_line
			(start -0.652 -0.425)
			(end 0.65 -0.425)
			(stroke
				(width 0.15)
				(type solid)
			)
			(layer "F.Fab")
		)
		(fp_line
			(start -0.35 -0.4)
			(end -0.35 0.4)
			(stroke
				(width 0.15)
				(type solid)
			)
			(layer "F.Fab")
		)
		(fp_line
			(start -0.652 0.423)
			(end -0.652 -0.425)
			(stroke
				(width 0.15)
				(type solid)
			)
			(layer "F.Fab")
		)
		(fp_line
			(start -0.652 0.423)
			(end 0.65 0.423)
			(stroke
				(width 0.15)
				(type solid)
			)
			(layer "F.Fab")
		)
		(fp_text user "${REFERENCE}"
			(at -1.276 3.499 90)
			(layer "F.Fab")
			(effects
				(font
					(size 0.7 0.7)
					(thickness 0.15)
				)
				(justify left bottom)
			)
		)
		(fp_text user "License: Apache-2.0"
			(at -1.276 5.9 90)
			(layer "F.Fab")
			(effects
				(font
					(size 0.7 0.7)
					(thickness 0.15)
				)
				(justify left bottom)
			)
		)
		(fp_text user "Author: Antmicro"
			(at -1.276 4.7 90)
			(layer "F.Fab")
			(effects
				(font
					(size 0.7 0.7)
					(thickness 0.15)
				)
				(justify left bottom)
			)
		)
		(pad "1" smd roundrect
			(at -0.701 0 90)
			(size 0.5 0.6)
			(layers "F.Cu" "F.Mask" "F.Paste")
			(roundrect_rratio 0.25)
			(net 5 "+5V")
			(pinfunction "C")
			(pintype "passive")
		)
		(pad "2" smd roundrect
			(at 0.699 0 90)
			(size 0.5 0.6)
			(layers "F.Cu" "F.Mask" "F.Paste")
			(roundrect_rratio 0.25)
			(net 1 "GND")
			(pinfunction "A")
			(pintype "passive")
		)
	)
	(footprint "antmicro-footprints:TSOT23-6"
		(layer "F.Cu")
		(at 62.41 89.04 90)
		(property "Reference" "U45"
			(at -0.12 2.59 90)
			(layer "F.SilkS")
			(effects
				(font
					(size 0.7 0.7)
					(thickness 0.15)
				)
				(justify left bottom)
			)
		)
		(property "Value" "AP22615A_TSOT26"
			(at 0 2.6 90)
			(layer "F.Fab")
			(effects
				(font
					(size 0.7 0.7)
					(thickness 0.15)
				)
				(justify left bottom)
			)
		)
		(property "Datasheet" "https://www.mouser.com/datasheet/2/115/DIOD_S_A0008958405_1-2543193.pdf"
			(at 0 0 90)
			(layer "F.Fab")
			(hide yes)
			(effects
				(font
					(size 1.27 1.27)
					(thickness 0.15)
				)
			)
		)
		(property "Description" "Power Load Distribution Switch, High Side, Active High, 1 Output, 5.5 V, 3.6 A, 0.04 ohm, TSOT-26-6"
			(at 0 0 90)
			(layer "F.Fab")
			(hide yes)
			(effects
				(font
					(size 1.27 1.27)
					(thickness 0.15)
				)
			)
		)
		(property "MPN" "AP22615AWU-7"
			(at 0 0 90)
			(unlocked yes)
			(layer "F.Fab")
			(hide yes)
			(effects
				(font
					(size 1 1)
					(thickness 0.15)
				)
			)
		)
		(property "Manufacturer" "Diodes Incorporated"
			(at 0 0 90)
			(unlocked yes)
			(layer "F.Fab")
			(hide yes)
			(effects
				(font
					(size 1 1)
					(thickness 0.15)
				)
			)
		)
		(property "Author" "Antmicro"
			(at 0 0 90)
			(unlocked yes)
			(layer "F.Fab")
			(hide yes)
			(effects
				(font
					(size 1 1)
					(thickness 0.15)
				)
			)
		)
		(property "License" "Apache-2.0"
			(at 0 0 90)
			(unlocked yes)
			(layer "F.Fab")
			(hide yes)
			(effects
				(font
					(size 1 1)
					(thickness 0.15)
				)
			)
		)
		(sheetname "/CSI/")
		(sheetfile "csi.kicad_sch")
		(attr smd)
		(fp_line
			(start -1 -1.5)
			(end -1 -1.375)
			(stroke
				(width 0.15)
				(type solid)
			)
			(layer "F.SilkS")
		)
		(fp_line
			(start 1 -1.497)
			(end -1 -1.5)
			(stroke
				(width 0.15)
				(type solid)
			)
			(layer "F.SilkS")
		)
		(fp_line
			(start 1 -1.497)
			(end 1 -1.375)
			(stroke
				(width 0.15)
				(type solid)
			)
			(layer "F.SilkS")
		)
		(fp_line
			(start 1 1.55)
			(end 1 1.4)
			(stroke
				(width 0.15)
				(type solid)
			)
			(layer "F.SilkS")
		)
		(fp_line
			(start 1 1.55)
			(end -1 1.55)
			(stroke
				(width 0.15)
				(type solid)
			)
			(layer "F.SilkS")
		)
		(fp_line
			(start -1 1.55)
			(end -1 1.4)
			(stroke
				(width 0.15)
				(type solid)
			)
			(layer "F.SilkS")
		)
		(fp_circle
			(center -1.44 -1.5)
			(end -1.39 -1.5)
			(stroke
				(width 0.15)
				(type solid)
			)
			(fill yes)
			(layer "F.SilkS")
		)
		(fp_rect
			(start 1.93 -1.7)
			(end -1.93 1.7)
			(stroke
				(width 0.05)
				(type solid)
			)
			(fill no)
			(layer "F.CrtYd")
		)
		(fp_line
			(start -0.45 -1.521)
			(end -0.876 -1.096)
			(stroke
				(width 0.15)
				(type solid)
			)
			(layer "F.Fab")
		)
		(fp_rect
			(start 0.875 1.528)
			(end -0.875 -1.525)
			(stroke
				(width 0.15)
				(type solid)
			)
			(fill no)
			(layer "F.Fab")
		)
		(fp_text user "Author: Antmicro"
			(at -1.93 5 90)
			(layer "F.Fab")
			(effects
				(font
					(size 0.7 0.7)
					(thickness 0.15)
				)
				(justify left bottom)
			)
		)
		(fp_text user "${REFERENCE}"
			(at -1.93 3.8 90)
			(layer "F.Fab")
			(effects
				(font
					(size 0.7 0.7)
					(thickness 0.15)
				)
				(justify left bottom)
			)
		)
		(fp_text user "License: Apache-2.0"
			(at -1.93 6.199 90)
			(layer "F.Fab")
			(effects
				(font
					(size 0.7 0.7)
					(thickness 0.15)
				)
				(justify left bottom)
			)
		)
		(pad "1" smd rect
			(at -1.301 -0.947)
			(size 0.7 1.2)
			(layers "F.Cu" "F.Mask" "F.Paste")
			(net 6 "/CSI/CSIA_3V3")
			(pinfunction "OUT")
			(pintype "power_out")
		)
		(pad "2" smd rect
			(at -1.301 0.004)
			(size 0.7 1.2)
			(layers "F.Cu" "F.Mask" "F.Paste")
			(net 1 "GND")
			(pinfunction "GND")
			(pintype "power_in")
		)
		(pad "3" smd rect
			(at -1.301 0.954)
			(size 0.7 1.2)
			(layers "F.Cu" "F.Mask" "F.Paste")
			(net 98 "/CSI/CAM_CTRL.CSIA_FLG")
			(pinfunction "FLG")
			(pintype "output")
		)
		(pad "4" smd rect
			(at 1.299 0.954)
			(size 0.7 1.2)
			(layers "F.Cu" "F.Mask" "F.Paste")
			(net 74 "/CSI/CAM_CTRL.CSIA_PEN")
			(pinfunction "EN")
			(pintype "input")
		)
		(pad "5" smd rect
			(at 1.299 0.004)
			(size 0.7 1.2)
			(layers "F.Cu" "F.Mask" "F.Paste")
			(net 996 "/CSI/CSIA_3V3_ISET")
			(pinfunction "ISET")
			(pintype "passive")
		)
		(pad "6" smd rect
			(at 1.299 -0.947)
			(size 0.7 1.2)
			(layers "F.Cu" "F.Mask" "F.Paste")
			(net 2 "+3V3")
			(pinfunction "IN")
			(pintype "power_in")
		)
	)
	(footprint "antmicro-footprints:R_0402_1005Metric"
		(layer "F.Cu")
		(at 180.889468 66.47 -90)
		(descr "Resistor SMD 0402")
		(tags "resistor SMD 0402")
		(property "Reference" "R30"
			(at -3.01 0.3 90)
			(layer "F.SilkS")
			(effects
				(font
					(size 0.7 0.7)
					(thickness 0.15)
				)
				(justify right top)
			)
		)
		(property "Value" "R_200k_0402"
			(at -1.011843 1.772047 90)
			(layer "F.Fab")
			(effects
				(font
					(size 0.7 0.7)
					(thickness 0.15)
				)
				(justify right top)
			)
		)
		(property "Datasheet" "https://www.bourns.com/docs/product-datasheets/cr.pdf"
			(at 0 0 90)
			(layer "F.Fab")
			(hide yes)
			(effects
				(font
					(size 1.27 1.27)
					(thickness 0.15)
				)
			)
		)
		(property "Description" "SMD Chip Resistor, 200 kohm, ± 1%, 62.5 mW, 0402 [1005 Metric], Thick Film, General Purpose"
			(at 0 0 90)
			(layer "F.Fab")
			(hide yes)
			(effects
				(font
					(size 1.27 1.27)
					(thickness 0.15)
				)
			)
		)
		(property "MPN" "CR0402-FX-2003GLF"
			(at 0 0 270)
			(unlocked yes)
			(layer "F.Fab")
			(hide yes)
			(effects
				(font
					(size 1 1)
					(thickness 0.15)
				)
			)
		)
		(property "Manufacturer" "Bourns"
			(at 0 0 270)
			(unlocked yes)
			(layer "F.Fab")
			(hide yes)
			(effects
				(font
					(size 1 1)
					(thickness 0.15)
				)
			)
		)
		(property "License" "Apache-2.0"
			(at 0 0 270)
			(unlocked yes)
			(layer "F.Fab")
			(hide yes)
			(effects
				(font
					(size 1 1)
					(thickness 0.15)
				)
			)
		)
		(property "Author" "Antmicro"
			(at 0 0 270)
			(unlocked yes)
			(layer "F.Fab")
			(hide yes)
			(effects
				(font
					(size 1 1)
					(thickness 0.15)
				)
			)
		)
		(property "Val" "200k"
			(at 0 0 270)
			(unlocked yes)
			(layer "F.Fab")
			(hide yes)
			(effects
				(font
					(size 1 1)
					(thickness 0.15)
				)
			)
		)
		(property "Tolerance" "1%"
			(at 0 0 270)
			(unlocked yes)
			(layer "F.Fab")
			(hide yes)
			(effects
				(font
					(size 1 1)
					(thickness 0.15)
				)
			)
		)
		(component_classes
			(class "DCDC_20V")
		)
		(sheetname "/DCDC/")
		(sheetfile "dcdc.kicad_sch")
		(attr smd)
		(fp_rect
			(start -0.925 -0.47)
			(end 0.925 0.47)
			(stroke
				(width 0.05)
				(type default)
			)
			(fill no)
			(layer "F.CrtYd")
		)
		(fp_rect
			(start -0.5 -0.25)
			(end 0.5 0.25)
			(stroke
				(width 0.15)
				(type solid)
			)
			(fill no)
			(layer "F.Fab")
		)
		(fp_text user "Author: Antmicro"
			(at -0.95 4.169 90)
			(layer "F.Fab")
			(effects
				(font
					(size 0.7 0.7)
					(thickness 0.15)
				)
				(justify right top)
			)
		)
		(fp_text user "${REFERENCE}"
			(at -0.95 3.168 90)
			(layer "F.Fab")
			(effects
				(font
					(size 0.7 0.7)
					(thickness 0.15)
				)
				(justify right top)
			)
		)
		(fp_text user "License: Apache-2.0"
			(at -0.95 5.169 90)
			(layer "F.Fab")
			(effects
				(font
					(size 0.7 0.7)
					(thickness 0.15)
				)
				(justify right top)
			)
		)
		(pad "1" smd roundrect
			(at -0.48 0 270)
			(size 0.59 0.64)
			(layers "F.Cu" "F.Mask" "F.Paste")
			(roundrect_rratio 0.25)
			(net 1 "GND")
			(pintype "passive")
		)
		(pad "2" smd roundrect
			(at 0.48 0 270)
			(size 0.59 0.64)
			(layers "F.Cu" "F.Mask" "F.Paste")
			(roundrect_rratio 0.25)
			(net 1210 "/DCDC/20V_MODE2")
			(pintype "passive")
		)
	)
	(footprint "antmicro-footprints:C_0805_2012Metric"
		(layer "F.Cu")
		(at 169.55 99.81 90)
		(descr "Capacitor SMD 0805")
		(tags "capacitor SMD 0805")
		(property "Reference" "C282"
			(at -4.595 0.345 90)
			(layer "F.SilkS")
			(effects
				(font
					(size 0.7 0.7)
					(thickness 0.15)
				)
				(justify left bottom)
			)
		)
		(property "Value" "C_22u_25V_0805"
			(at -2.055717 1.963152 90)
			(layer "F.Fab")
			(effects
				(font
					(size 0.7 0.7)
					(thickness 0.15)
				)
				(justify left bottom)
			)
		)
		(property "Datasheet" "https://product.samsungsem.com/mlcc/CL21A226MAYNNN.do"
			(at 0 0 90)
			(layer "F.Fab")
			(hide yes)
			(effects
				(font
					(size 1.27 1.27)
					(thickness 0.15)
				)
			)
		)
		(property "Description" "SMT Multilayer Ceramic Capacitor, 22uF, +/-20%, 25V, X5R, 0805 [2012 Metric]"
			(at 0 0 90)
			(layer "F.Fab")
			(hide yes)
			(effects
				(font
					(size 1.27 1.27)
					(thickness 0.15)
				)
			)
		)
		(property "MPN" "CL21A226MAYNNNE"
			(at 0 0 90)
			(unlocked yes)
			(layer "F.Fab")
			(hide yes)
			(effects
				(font
					(size 1 1)
					(thickness 0.15)
				)
			)
		)
		(property "Manufacturer" "Samsung Electro-Mechanics"
			(at 0 0 90)
			(unlocked yes)
			(layer "F.Fab")
			(hide yes)
			(effects
				(font
					(size 1 1)
					(thickness 0.15)
				)
			)
		)
		(property "License" "Apache-2.0"
			(at 0 0 90)
			(unlocked yes)
			(layer "F.Fab")
			(hide yes)
			(effects
				(font
					(size 1 1)
					(thickness 0.15)
				)
			)
		)
		(property "Author" "Antmicro"
			(at 0 0 90)
			(unlocked yes)
			(layer "F.Fab")
			(hide yes)
			(effects
				(font
					(size 1 1)
					(thickness 0.15)
				)
			)
		)
		(property "Val" "22u"
			(at 0 0 90)
			(unlocked yes)
			(layer "F.Fab")
			(hide yes)
			(effects
				(font
					(size 1 1)
					(thickness 0.15)
				)
			)
		)
		(property "Voltage" "25V"
			(at 0 0 90)
			(unlocked yes)
			(layer "F.Fab")
			(hide yes)
			(effects
				(font
					(size 1 1)
					(thickness 0.15)
				)
			)
		)
		(property "Dielectric" "X5R"
			(at 0 0 90)
			(unlocked yes)
			(layer "F.Fab")
			(hide yes)
			(effects
				(font
					(size 1 1)
					(thickness 0.15)
				)
			)
		)
		(property "Public" "False"
			(at 0 0 90)
			(unlocked yes)
			(layer "F.Fab")
			(hide yes)
			(effects
				(font
					(size 1 1)
					(thickness 0.15)
				)
			)
		)
		(component_classes
			(class "DCDC_SOM")
		)
		(sheetname "/DCDC/")
		(sheetfile "dcdc.kicad_sch")
		(attr smd)
		(fp_line
			(start -0.3 -0.7)
			(end 0.3 -0.7)
			(stroke
				(width 0.15)
				(type solid)
			)
			(layer "F.SilkS")
		)
		(fp_line
			(start -0.3 0.7)
			(end 0.3 0.7)
			(stroke
				(width 0.15)
				(type solid)
			)
			(layer "F.SilkS")
		)
		(fp_rect
			(start 1.95 -0.9)
			(end -1.95 0.9)
			(stroke
				(width 0.05)
				(type default)
			)
			(fill no)
			(layer "F.CrtYd")
		)
		(fp_rect
			(start -0.95 -0.675)
			(end 0.95 0.675)
			(stroke
				(width 0.15)
				(type solid)
			)
			(fill no)
			(layer "F.Fab")
		)
		(fp_text user "License: Apache-2.0"
			(at -1.9 4.947 90)
			(layer "F.Fab")
			(effects
				(font
					(size 0.7 0.7)
					(thickness 0.15)
				)
				(justify left bottom)
			)
		)
		(fp_text user "${REFERENCE}"
			(at -1.9 3.947 90)
			(layer "F.Fab")
			(effects
				(font
					(size 0.7 0.7)
					(thickness 0.15)
				)
				(justify left bottom)
			)
		)
		(fp_text user "Author: Antmicro"
			(at -1.9 5.947 90)
			(layer "F.Fab")
			(effects
				(font
					(size 0.7 0.7)
					(thickness 0.15)
				)
				(justify left bottom)
			)
		)
		(pad "1" smd roundrect
			(at -1.1 0 90)
			(size 1.2 1.3)
			(layers "F.Cu" "F.Mask" "F.Paste")
			(roundrect_rratio 0.25)
			(net 1 "GND")
			(pintype "passive")
		)
		(pad "2" smd roundrect
			(at 1.1 0 90)
			(size 1.2 1.3)
			(layers "F.Cu" "F.Mask" "F.Paste")
			(roundrect_rratio 0.25)
			(net 903 "/DCDC/16V_OUT")
			(pintype "passive")
		)
	)
	(footprint "antmicro-footprints:R_0402_1005Metric"
		(layer "F.Cu")
		(at 210.114132 93.627 180)
		(descr "Resistor SMD 0402")
		(tags "resistor SMD 0402")
		(property "Reference" "R122"
			(at 0.854132 -0.513 0)
			(layer "F.SilkS")
			(effects
				(font
					(size 0.7 0.7)
					(thickness 0.15)
				)
				(justify right top)
			)
		)
		(property "Value" "R_0R_0402"
			(at -1.011843 1.772047 0)
			(layer "F.Fab")
			(effects
				(font
					(size 0.7 0.7)
					(thickness 0.15)
				)
				(justify right top)
			)
		)
		(property "Datasheet" "https://industrial.panasonic.com/cdbs/www-data/pdf/RDA0000/AOA0000C301.pdf"
			(at 0 0 0)
			(layer "F.Fab")
			(hide yes)
			(effects
				(font
					(size 1.27 1.27)
					(thickness 0.15)
				)
			)
		)
		(property "Description" "SMD Chip Resistor, Jumper, 0 ohm, 100 mW, 0402 [1005 Metric], Thick Film, General Purpose"
			(at 0 0 0)
			(layer "F.Fab")
			(hide yes)
			(effects
				(font
					(size 1.27 1.27)
					(thickness 0.15)
				)
			)
		)
		(property "Manufacturer" "Panasonic"
			(at 0 0 180)
			(unlocked yes)
			(layer "F.Fab")
			(hide yes)
			(effects
				(font
					(size 1 1)
					(thickness 0.15)
				)
			)
		)
		(property "MPN" "ERJ2GE0R00X"
			(at 0 0 180)
			(unlocked yes)
			(layer "F.Fab")
			(hide yes)
			(effects
				(font
					(size 1 1)
					(thickness 0.15)
				)
			)
		)
		(property "Val" "0R"
			(at 0 0 180)
			(unlocked yes)
			(layer "F.Fab")
			(hide yes)
			(effects
				(font
					(size 1 1)
					(thickness 0.15)
				)
			)
		)
		(property "License" "Apache-2.0"
			(at 0 0 180)
			(unlocked yes)
			(layer "F.Fab")
			(hide yes)
			(effects
				(font
					(size 1 1)
					(thickness 0.15)
				)
			)
		)
		(property "Author" "Antmicro"
			(at 0 0 180)
			(unlocked yes)
			(layer "F.Fab")
			(hide yes)
			(effects
				(font
					(size 1 1)
					(thickness 0.15)
				)
			)
		)
		(property "Tolerance" "~"
			(at 0 0 180)
			(unlocked yes)
			(layer "F.Fab")
			(hide yes)
			(effects
				(font
					(size 1 1)
					(thickness 0.15)
				)
			)
		)
		(property "Current" "1A"
			(at 0 0 180)
			(unlocked yes)
			(layer "F.Fab")
			(hide yes)
			(effects
				(font
					(size 1 1)
					(thickness 0.15)
				)
			)
		)
		(sheetname "/USB DP Alt mode/")
		(sheetfile "usb_dp.kicad_sch")
		(attr smd exclude_from_pos_files exclude_from_bom dnp)
		(fp_rect
			(start -0.925 -0.47)
			(end 0.925 0.47)
			(stroke
				(width 0.05)
				(type default)
			)
			(fill no)
			(layer "F.CrtYd")
		)
		(fp_rect
			(start -0.5 -0.25)
			(end 0.5 0.25)
			(stroke
				(width 0.15)
				(type solid)
			)
			(fill no)
			(layer "F.Fab")
		)
		(fp_text user "Author: Antmicro"
			(at -0.95 4.169 0)
			(layer "F.Fab")
			(effects
				(font
					(size 0.7 0.7)
					(thickness 0.15)
				)
				(justify right top)
			)
		)
		(fp_text user "${REFERENCE}"
			(at -0.95 3.168 0)
			(layer "F.Fab")
			(effects
				(font
					(size 0.7 0.7)
					(thickness 0.15)
				)
				(justify right top)
			)
		)
		(fp_text user "License: Apache-2.0"
			(at -0.95 5.169 0)
			(layer "F.Fab")
			(effects
				(font
					(size 0.7 0.7)
					(thickness 0.15)
				)
				(justify right top)
			)
		)
		(pad "1" smd roundrect
			(at -0.48 0 180)
			(size 0.59 0.64)
			(layers "F.Cu" "F.Mask" "F.Paste")
			(roundrect_rratio 0.25)
			(net 942 "/USB DP Alt mode/USBC1_FLIP")
			(pintype "passive")
		)
		(pad "2" smd roundrect
			(at 0.48 0 180)
			(size 0.59 0.64)
			(layers "F.Cu" "F.Mask" "F.Paste")
			(roundrect_rratio 0.25)
			(net 853 "/I2C_{SYS}.SCL")
			(pintype "passive")
		)
	)
	(footprint "antmicro-footprints:R_0402_1005Metric"
		(layer "F.Cu")
		(at 214 133.8 180)
		(descr "Resistor SMD 0402")
		(tags "resistor SMD 0402")
		(property "Reference" "R67"
			(at -3.07 0.33 0)
			(layer "F.SilkS")
			(effects
				(font
					(size 0.7 0.7)
					(thickness 0.15)
				)
				(justify right top)
			)
		)
		(property "Value" "R_10k_0402"
			(at -1.011843 1.772047 0)
			(layer "F.Fab")
			(effects
				(font
					(size 0.7 0.7)
					(thickness 0.15)
				)
				(justify right top)
			)
		)
		(property "Datasheet" "https://www.bourns.com/docs/product-datasheets/cr.pdf"
			(at 0 0 0)
			(layer "F.Fab")
			(hide yes)
			(effects
				(font
					(size 1.27 1.27)
					(thickness 0.15)
				)
			)
		)
		(property "Description" "SMD Chip Resistor, 10 kohm, ± 1%, 62.5 mW, 0402 [1005 Metric], Thick Film, General Purpose"
			(at 0 0 0)
			(layer "F.Fab")
			(hide yes)
			(effects
				(font
					(size 1.27 1.27)
					(thickness 0.15)
				)
			)
		)
		(property "Manufacturer" "Bourns"
			(at 0 0 180)
			(unlocked yes)
			(layer "F.Fab")
			(hide yes)
			(effects
				(font
					(size 1 1)
					(thickness 0.15)
				)
			)
		)
		(property "MPN" "CR0402-FX-1002GLF"
			(at 0 0 180)
			(unlocked yes)
			(layer "F.Fab")
			(hide yes)
			(effects
				(font
					(size 1 1)
					(thickness 0.15)
				)
			)
		)
		(property "Val" "10k"
			(at 0 0 180)
			(unlocked yes)
			(layer "F.Fab")
			(hide yes)
			(effects
				(font
					(size 1 1)
					(thickness 0.15)
				)
			)
		)
		(property "License" "Apache-2.0"
			(at 0 0 180)
			(unlocked yes)
			(layer "F.Fab")
			(hide yes)
			(effects
				(font
					(size 1 1)
					(thickness 0.15)
				)
			)
		)
		(property "Author" "Antmicro"
			(at 0 0 180)
			(unlocked yes)
			(layer "F.Fab")
			(hide yes)
			(effects
				(font
					(size 1 1)
					(thickness 0.15)
				)
			)
		)
		(property "Tolerance" "1%"
			(at 0 0 180)
			(unlocked yes)
			(layer "F.Fab")
			(hide yes)
			(effects
				(font
					(size 1 1)
					(thickness 0.15)
				)
			)
		)
		(sheetname "/USB Hub/")
		(sheetfile "usb_hub.kicad_sch")
		(attr smd)
		(fp_rect
			(start -0.925 -0.47)
			(end 0.925 0.47)
			(stroke
				(width 0.05)
				(type default)
			)
			(fill no)
			(layer "F.CrtYd")
		)
		(fp_rect
			(start -0.5 -0.25)
			(end 0.5 0.25)
			(stroke
				(width 0.15)
				(type solid)
			)
			(fill no)
			(layer "F.Fab")
		)
		(fp_text user "${REFERENCE}"
			(at -0.95 3.168 0)
			(layer "F.Fab")
			(effects
				(font
					(size 0.7 0.7)
					(thickness 0.15)
				)
				(justify right top)
			)
		)
		(fp_text user "Author: Antmicro"
			(at -0.95 4.169 0)
			(layer "F.Fab")
			(effects
				(font
					(size 0.7 0.7)
					(thickness 0.15)
				)
				(justify right top)
			)
		)
		(fp_text user "License: Apache-2.0"
			(at -0.95 5.169 0)
			(layer "F.Fab")
			(effects
				(font
					(size 0.7 0.7)
					(thickness 0.15)
				)
				(justify right top)
			)
		)
		(pad "1" smd roundrect
			(at -0.48 0 180)
			(size 0.59 0.64)
			(layers "F.Cu" "F.Mask" "F.Paste")
			(roundrect_rratio 0.25)
			(net 2 "+3V3")
			(pintype "passive")
		)
		(pad "2" smd roundrect
			(at 0.48 0 180)
			(size 0.59 0.64)
			(layers "F.Cu" "F.Mask" "F.Paste")
			(roundrect_rratio 0.25)
			(net 527 "/USB Hub/~{RESET}")
			(pintype "passive")
		)
	)
	(footprint "antmicro-footprints:R_0402_1005Metric"
		(layer "F.Cu")
		(at 188.3 122.6 90)
		(descr "Resistor SMD 0402")
		(tags "resistor SMD 0402")
		(property "Reference" "R380"
			(at 7.1 -2.4 90)
			(layer "F.SilkS")
			(effects
				(font
					(size 0.7 0.7)
					(thickness 0.15)
				)
				(justify left bottom)
			)
		)
		(property "Value" "R_0R_0402"
			(at -1.011843 1.772047 90)
			(layer "F.Fab")
			(effects
				(font
					(size 0.7 0.7)
					(thickness 0.15)
				)
				(justify left bottom)
			)
		)
		(property "Datasheet" "https://industrial.panasonic.com/cdbs/www-data/pdf/RDA0000/AOA0000C301.pdf"
			(at 0 0 90)
			(layer "F.Fab")
			(hide yes)
			(effects
				(font
					(size 1.27 1.27)
					(thickness 0.15)
				)
			)
		)
		(property "Description" "SMD Chip Resistor, Jumper, 0 ohm, 100 mW, 0402 [1005 Metric], Thick Film, General Purpose"
			(at 0 0 90)
			(layer "F.Fab")
			(hide yes)
			(effects
				(font
					(size 1.27 1.27)
					(thickness 0.15)
				)
			)
		)
		(property "MPN" "ERJ2GE0R00X"
			(at 0 0 90)
			(unlocked yes)
			(layer "F.Fab")
			(hide yes)
			(effects
				(font
					(size 1 1)
					(thickness 0.15)
				)
			)
		)
		(property "Manufacturer" "Panasonic"
			(at 0 0 90)
			(unlocked yes)
			(layer "F.Fab")
			(hide yes)
			(effects
				(font
					(size 1 1)
					(thickness 0.15)
				)
			)
		)
		(property "License" "Apache-2.0"
			(at 0 0 90)
			(unlocked yes)
			(layer "F.Fab")
			(hide yes)
			(effects
				(font
					(size 1 1)
					(thickness 0.15)
				)
			)
		)
		(property "Author" "Antmicro"
			(at 0 0 90)
			(unlocked yes)
			(layer "F.Fab")
			(hide yes)
			(effects
				(font
					(size 1 1)
					(thickness 0.15)
				)
			)
		)
		(property "Val" "0R"
			(at 0 0 90)
			(unlocked yes)
			(layer "F.Fab")
			(hide yes)
			(effects
				(font
					(size 1 1)
					(thickness 0.15)
				)
			)
		)
		(property "Tolerance" "~"
			(at 0 0 90)
			(unlocked yes)
			(layer "F.Fab")
			(hide yes)
			(effects
				(font
					(size 1 1)
					(thickness 0.15)
				)
			)
		)
		(property "Current" "1A"
			(at 0 0 90)
			(unlocked yes)
			(layer "F.Fab")
			(hide yes)
			(effects
				(font
					(size 1 1)
					(thickness 0.15)
				)
			)
		)
		(sheetname "/USB Hub/")
		(sheetfile "usb_hub.kicad_sch")
		(attr smd exclude_from_pos_files exclude_from_bom dnp)
		(fp_rect
			(start -0.925 -0.47)
			(end 0.925 0.47)
			(stroke
				(width 0.05)
				(type default)
			)
			(fill no)
			(layer "F.CrtYd")
		)
		(fp_rect
			(start -0.5 -0.25)
			(end 0.5 0.25)
			(stroke
				(width 0.15)
				(type solid)
			)
			(fill no)
			(layer "F.Fab")
		)
		(fp_text user "License: Apache-2.0"
			(at -0.95 5.169 90)
			(layer "F.Fab")
			(effects
				(font
					(size 0.7 0.7)
					(thickness 0.15)
				)
				(justify left bottom)
			)
		)
		(fp_text user "${REFERENCE}"
			(at -0.95 3.168 90)
			(layer "F.Fab")
			(effects
				(font
					(size 0.7 0.7)
					(thickness 0.15)
				)
				(justify left bottom)
			)
		)
		(fp_text user "Author: Antmicro"
			(at -0.95 4.169 90)
			(layer "F.Fab")
			(effects
				(font
					(size 0.7 0.7)
					(thickness 0.15)
				)
				(justify left bottom)
			)
		)
		(pad "1" smd roundrect
			(at -0.48 0 90)
			(size 0.59 0.64)
			(layers "F.Cu" "F.Mask" "F.Paste")
			(roundrect_rratio 0.25)
			(net 924 "/USB Hub/HUB_SPI_D3")
			(pintype "passive")
		)
		(pad "2" smd roundrect
			(at 0.48 0 90)
			(size 0.59 0.64)
			(layers "F.Cu" "F.Mask" "F.Paste")
			(roundrect_rratio 0.25)
			(net 1165 "/USB Hub/HUB_~{HOLD}")
			(pintype "passive")
		)
	)
	(footprint "antmicro-footprints:LED_0603_1608Metric_G"
		(layer "F.Cu")
		(at 168.5 55.3 -90)
		(descr "LED SMD 0603 Green")
		(tags "LED SMD 0603 Green")
		(property "Reference" "D3"
			(at -0.18 1.49875 90)
			(layer "F.SilkS")
			(effects
				(font
					(size 0.7 0.7)
					(thickness 0.15)
				)
				(justify right top)
			)
		)
		(property "Value" "LED_G_0603_LTST-C190GKT"
			(at -0.001 1.599 90)
			(layer "F.Fab")
			(effects
				(font
					(size 0.7 0.7)
					(thickness 0.15)
				)
				(justify right top)
			)
		)
		(property "Datasheet" "https://media.digikey.com/pdf/Data%20Sheets/Lite-On%20PDFs/LTST-C190GKT.pdf"
			(at 0 0 90)
			(layer "F.Fab")
			(hide yes)
			(effects
				(font
					(size 1.27 1.27)
					(thickness 0.15)
				)
			)
		)
		(property "Description" "LED, Green, SMD, 0603, 20 mA, 2.1 V, 569 nm"
			(at 0 0 90)
			(layer "F.Fab")
			(hide yes)
			(effects
				(font
					(size 1.27 1.27)
					(thickness 0.15)
				)
			)
		)
		(property "MPN" "LTST-C190GKT"
			(at 0 0 270)
			(unlocked yes)
			(layer "F.Fab")
			(hide yes)
			(effects
				(font
					(size 1 1)
					(thickness 0.15)
				)
			)
		)
		(property "Manufacturer" "Lite-On"
			(at 0 0 270)
			(unlocked yes)
			(layer "F.Fab")
			(hide yes)
			(effects
				(font
					(size 1 1)
					(thickness 0.15)
				)
			)
		)
		(property "Author" "Antmicro"
			(at 0 0 270)
			(unlocked yes)
			(layer "F.Fab")
			(hide yes)
			(effects
				(font
					(size 1 1)
					(thickness 0.15)
				)
			)
		)
		(property "License" "Apache-2.0"
			(at 0 0 270)
			(unlocked yes)
			(layer "F.Fab")
			(hide yes)
			(effects
				(font
					(size 1 1)
					(thickness 0.15)
				)
			)
		)
		(property "Color" "Green"
			(at 0 0 270)
			(unlocked yes)
			(layer "F.Fab")
			(hide yes)
			(effects
				(font
					(size 1 1)
					(thickness 0.15)
				)
			)
		)
		(sheetname "/Power/")
		(sheetfile "power.kicad_sch")
		(attr smd)
		(fp_line
			(start 0.22 0.35)
			(end -0.22 0.35)
			(stroke
				(width 0.15)
				(type solid)
			)
			(layer "F.SilkS")
		)
		(fp_line
			(start -0.094672 0.201008)
			(end -0.094672 -0.198992)
			(stroke
				(width 0.1)
				(type solid)
			)
			(layer "F.SilkS")
		)
		(fp_line
			(start 0.105328 0.201008)
			(end -0.094672 0.001008)
			(stroke
				(width 0.1)
				(type solid)
			)
			(layer "F.SilkS")
		)
		(fp_line
			(start 0.105328 0.201008)
			(end 0.105328 -0.198992)
			(stroke
				(width 0.1)
				(type solid)
			)
			(layer "F.SilkS")
		)
		(fp_line
			(start -0.094672 0.001008)
			(end -0.24 0.001008)
			(stroke
				(width 0.1)
				(type solid)
			)
			(layer "F.SilkS")
		)
		(fp_line
			(start -0.094672 0.001008)
			(end 0.105328 -0.198992)
			(stroke
				(width 0.1)
				(type solid)
			)
			(layer "F.SilkS")
		)
		(fp_line
			(start 0.105328 0.001008)
			(end 0.24 0.001)
			(stroke
				(width 0.1)
				(type solid)
			)
			(layer "F.SilkS")
		)
		(fp_line
			(start -1.18 -0.319)
			(end -1.18 0.321)
			(stroke
				(width 0.15)
				(type solid)
			)
			(layer "F.SilkS")
		)
		(fp_line
			(start 0.22 -0.35)
			(end -0.22 -0.35)
			(stroke
				(width 0.15)
				(type solid)
			)
			(layer "F.SilkS")
		)
		(fp_rect
			(start 1.25 0.65)
			(end -1.25 -0.65)
			(stroke
				(width 0.05)
				(type solid)
			)
			(fill no)
			(layer "F.CrtYd")
		)
		(fp_line
			(start -0.199 0.2)
			(end -0.199 0.1)
			(stroke
				(width 0.15)
				(type solid)
			)
			(layer "F.Fab")
		)
		(fp_line
			(start 0.201 0.2)
			(end 0.201 0)
			(stroke
				(width 0.15)
				(type solid)
			)
			(layer "F.Fab")
		)
		(fp_line
			(start -0.199 0)
			(end -0.597 0)
			(stroke
				(width 0.15)
				(type solid)
			)
			(layer "F.Fab")
		)
		(fp_line
			(start -0.101 0)
			(end 0.201 0.2)
			(stroke
				(width 0.15)
				(type solid)
			)
			(layer "F.Fab")
		)
		(fp_line
			(start 0.201 0)
			(end 0.201 -0.202)
			(stroke
				(width 0.15)
				(type solid)
			)
			(layer "F.Fab")
		)
		(fp_line
			(start 0.599 0)
			(end 0.201 0)
			(stroke
				(width 0.15)
				(type solid)
			)
			(layer "F.Fab")
		)
		(fp_line
			(start -0.199 -0.202)
			(end -0.199 0.1)
			(stroke
				(width 0.15)
				(type solid)
			)
			(layer "F.Fab")
		)
		(fp_line
			(start 0.201 -0.202)
			(end -0.101 0)
			(stroke
				(width 0.15)
				(type solid)
			)
			(layer "F.Fab")
		)
		(fp_rect
			(start 0.848 0.4)
			(end -0.85 -0.402)
			(stroke
				(width 0.15)
				(type solid)
			)
			(fill no)
			(layer "F.Fab")
		)
		(fp_text user "Author: Antmicro"
			(at -1.4224 4.799 90)
			(layer "F.Fab")
			(effects
				(font
					(size 0.7 0.7)
					(thickness 0.15)
				)
				(justify right top)
			)
		)
		(fp_text user "License: Apache-2.0"
			(at -1.4224 3.599 90)
			(layer "F.Fab")
			(effects
				(font
					(size 0.7 0.7)
					(thickness 0.15)
				)
				(justify right top)
			)
		)
		(fp_text user "${REFERENCE}"
			(at -1.4224 5.999 90)
			(layer "F.Fab")
			(effects
				(font
					(size 0.7 0.7)
					(thickness 0.15)
				)
				(justify right top)
			)
		)
		(pad "1" smd roundrect
			(at -0.7 0 90)
			(size 0.8 1)
			(layers "F.Cu" "F.Mask" "F.Paste")
			(roundrect_rratio 0.2)
			(net 1 "GND")
			(pinfunction "C")
			(pintype "passive")
		)
		(pad "2" smd roundrect
			(at 0.7 0 90)
			(size 0.8 1)
			(layers "F.Cu" "F.Mask" "F.Paste")
			(roundrect_rratio 0.2)
			(net 526 "Net-(D3-A)")
			(pinfunction "A")
			(pintype "passive")
		)
	)
	(footprint "antmicro-footprints:LED_0603_1608Metric_G"
		(layer "B.Cu")
		(at 108.555 140.77 90)
		(descr "LED SMD 0603 Green")
		(tags "LED SMD 0603 Green")
		(property "Reference" "D34"
			(at -0.98 -1.645 90)
			(layer "B.SilkS")
			(effects
				(font
					(size 0.7 0.7)
					(thickness 0.15)
				)
				(justify right top mirror)
			)
		)
		(property "Value" "LED_G_0603_LTST-C190GKT"
			(at -0.001 -1.599 90)
			(layer "B.Fab")
			(effects
				(font
					(size 0.7 0.7)
					(thickness 0.15)
				)
				(justify right top mirror)
			)
		)
		(property "Datasheet" "https://media.digikey.com/pdf/Data%20Sheets/Lite-On%20PDFs/LTST-C190GKT.pdf"
			(at 0 0 90)
			(layer "B.Fab")
			(hide yes)
			(effects
				(font
					(size 1.27 1.27)
					(thickness 0.15)
				)
				(justify mirror)
			)
		)
		(property "Description" "LED, Green, SMD, 0603, 20 mA, 2.1 V, 569 nm"
			(at 0 0 90)
			(layer "B.Fab")
			(hide yes)
			(effects
				(font
					(size 1.27 1.27)
					(thickness 0.15)
				)
				(justify mirror)
			)
		)
		(property "MPN" "LTST-C190GKT"
			(at 0 0 270)
			(unlocked yes)
			(layer "B.Fab")
			(hide yes)
			(effects
				(font
					(size 1 1)
					(thickness 0.15)
				)
				(justify mirror)
			)
		)
		(property "Manufacturer" "Lite-On"
			(at 0 0 270)
			(unlocked yes)
			(layer "B.Fab")
			(hide yes)
			(effects
				(font
					(size 1 1)
					(thickness 0.15)
				)
				(justify mirror)
			)
		)
		(property "Author" "Antmicro"
			(at 0 0 270)
			(unlocked yes)
			(layer "B.Fab")
			(hide yes)
			(effects
				(font
					(size 1 1)
					(thickness 0.15)
				)
				(justify mirror)
			)
		)
		(property "License" "Apache-2.0"
			(at 0 0 270)
			(unlocked yes)
			(layer "B.Fab")
			(hide yes)
			(effects
				(font
					(size 1 1)
					(thickness 0.15)
				)
				(justify mirror)
			)
		)
		(property "Public" "False"
			(at 0 0 270)
			(unlocked yes)
			(layer "B.Fab")
			(hide yes)
			(effects
				(font
					(size 1 1)
					(thickness 0.15)
				)
				(justify mirror)
			)
		)
		(property "Color" "Green"
			(at 0 0 270)
			(unlocked yes)
			(layer "B.Fab")
			(hide yes)
			(effects
				(font
					(size 1 1)
					(thickness 0.15)
				)
				(justify mirror)
			)
		)
		(sheetname "/M.2/")
		(sheetfile "m2.kicad_sch")
		(attr smd)
		(fp_line
			(start 0.22 -0.35)
			(end -0.22 -0.35)
			(stroke
				(width 0.15)
				(type solid)
			)
			(layer "B.SilkS")
		)
		(fp_line
			(start 0.105328 -0.201008)
			(end -0.094672 -0.001008)
			(stroke
				(width 0.1)
				(type solid)
			)
			(layer "B.SilkS")
		)
		(fp_line
			(start 0.105328 -0.201008)
			(end 0.105328 0.198992)
			(stroke
				(width 0.1)
				(type solid)
			)
			(layer "B.SilkS")
		)
		(fp_line
			(start -0.094672 -0.201008)
			(end -0.094672 0.198992)
			(stroke
				(width 0.1)
				(type solid)
			)
			(layer "B.SilkS")
		)
		(fp_line
			(start 0.105328 -0.001008)
			(end 0.24 -0.001)
			(stroke
				(width 0.1)
				(type solid)
			)
			(layer "B.SilkS")
		)
		(fp_line
			(start -0.094672 -0.001008)
			(end -0.24 -0.001008)
			(stroke
				(width 0.1)
				(type solid)
			)
			(layer "B.SilkS")
		)
		(fp_line
			(start -0.094672 -0.001008)
			(end 0.105328 0.198992)
			(stroke
				(width 0.1)
				(type solid)
			)
			(layer "B.SilkS")
		)
		(fp_line
			(start -1.18 0.319)
			(end -1.18 -0.321)
			(stroke
				(width 0.15)
				(type solid)
			)
			(layer "B.SilkS")
		)
		(fp_line
			(start 0.22 0.35)
			(end -0.22 0.35)
			(stroke
				(width 0.15)
				(type solid)
			)
			(layer "B.SilkS")
		)
		(fp_rect
			(start 1.25 -0.65)
			(end -1.25 0.65)
			(stroke
				(width 0.05)
				(type solid)
			)
			(fill no)
			(layer "B.CrtYd")
		)
		(fp_line
			(start 0.201 -0.2)
			(end 0.201 0)
			(stroke
				(width 0.15)
				(type solid)
			)
			(layer "B.Fab")
		)
		(fp_line
			(start -0.199 -0.2)
			(end -0.199 -0.1)
			(stroke
				(width 0.15)
				(type solid)
			)
			(layer "B.Fab")
		)
		(fp_line
			(start 0.599 0)
			(end 0.201 0)
			(stroke
				(width 0.15)
				(type solid)
			)
			(layer "B.Fab")
		)
		(fp_line
			(start 0.201 0)
			(end 0.201 0.202)
			(stroke
				(width 0.15)
				(type solid)
			)
			(layer "B.Fab")
		)
		(fp_line
			(start -0.101 0)
			(end 0.201 -0.2)
			(stroke
				(width 0.15)
				(type solid)
			)
			(layer "B.Fab")
		)
		(fp_line
			(start -0.199 0)
			(end -0.597 0)
			(stroke
				(width 0.15)
				(type solid)
			)
			(layer "B.Fab")
		)
		(fp_line
			(start 0.201 0.202)
			(end -0.101 0)
			(stroke
				(width 0.15)
				(type solid)
			)
			(layer "B.Fab")
		)
		(fp_line
			(start -0.199 0.202)
			(end -0.199 -0.1)
			(stroke
				(width 0.15)
				(type solid)
			)
			(layer "B.Fab")
		)
		(fp_rect
			(start 0.848 -0.4)
			(end -0.85 0.402)
			(stroke
				(width 0.15)
				(type solid)
			)
			(fill no)
			(layer "B.Fab")
		)
		(fp_text user "License: Apache-2.0"
			(at -1.4224 -3.599 90)
			(layer "B.Fab")
			(effects
				(font
					(size 0.7 0.7)
					(thickness 0.15)
				)
				(justify right top mirror)
			)
		)
		(fp_text user "${REFERENCE}"
			(at -1.4224 -5.999 90)
			(layer "B.Fab")
			(effects
				(font
					(size 0.7 0.7)
					(thickness 0.15)
				)
				(justify right top mirror)
			)
		)
		(fp_text user "Author: Antmicro"
			(at -1.4224 -4.799 90)
			(layer "B.Fab")
			(effects
				(font
					(size 0.7 0.7)
					(thickness 0.15)
				)
				(justify right top mirror)
			)
		)
		(pad "1" smd roundrect
			(at -0.7 0 270)
			(size 0.8 1)
			(layers "B.Cu" "B.Mask" "B.Paste")
			(roundrect_rratio 0.2)
			(net 35 "/M.2/~{LED_2}")
			(pinfunction "C")
			(pintype "passive")
		)
		(pad "2" smd roundrect
			(at 0.7 0 270)
			(size 0.8 1)
			(layers "B.Cu" "B.Mask" "B.Paste")
			(roundrect_rratio 0.2)
			(net 546 "Net-(D34-A)")
			(pinfunction "A")
			(pintype "passive")
		)
	)
	(footprint "antmicro-footprints:R_0402_1005Metric"
		(layer "B.Cu")
		(at 92.87 149.209999)
		(descr "Resistor SMD 0402")
		(tags "resistor SMD 0402")
		(property "Reference" "R201"
			(at 0.85 -0.369264 0)
			(layer "B.SilkS")
			(effects
				(font
					(size 0.7 0.7)
					(thickness 0.15)
				)
				(justify right top mirror)
			)
		)
		(property "Value" "R_0R_0402"
			(at -1.011843 -1.772046 0)
			(layer "B.Fab")
			(effects
				(font
					(size 0.7 0.7)
					(thickness 0.15)
				)
				(justify right top mirror)
			)
		)
		(property "Datasheet" "https://industrial.panasonic.com/cdbs/www-data/pdf/RDA0000/AOA0000C301.pdf"
			(at 0 0 0)
			(layer "B.Fab")
			(hide yes)
			(effects
				(font
					(size 1.27 1.27)
					(thickness 0.15)
				)
				(justify mirror)
			)
		)
		(property "Description" "SMD Chip Resistor, Jumper, 0 ohm, 100 mW, 0402 [1005 Metric], Thick Film, General Purpose"
			(at 0 0 0)
			(layer "B.Fab")
			(hide yes)
			(effects
				(font
					(size 1.27 1.27)
					(thickness 0.15)
				)
				(justify mirror)
			)
		)
		(property "MPN" "ERJ2GE0R00X"
			(at 0 0 180)
			(unlocked yes)
			(layer "B.Fab")
			(hide yes)
			(effects
				(font
					(size 1 1)
					(thickness 0.15)
				)
				(justify mirror)
			)
		)
		(property "Manufacturer" "Panasonic"
			(at 0 0 180)
			(unlocked yes)
			(layer "B.Fab")
			(hide yes)
			(effects
				(font
					(size 1 1)
					(thickness 0.15)
				)
				(justify mirror)
			)
		)
		(property "License" "Apache-2.0"
			(at 0 0 180)
			(unlocked yes)
			(layer "B.Fab")
			(hide yes)
			(effects
				(font
					(size 1 1)
					(thickness 0.15)
				)
				(justify mirror)
			)
		)
		(property "Author" "Antmicro"
			(at 0 0 180)
			(unlocked yes)
			(layer "B.Fab")
			(hide yes)
			(effects
				(font
					(size 1 1)
					(thickness 0.15)
				)
				(justify mirror)
			)
		)
		(property "Val" "0R"
			(at 0 0 180)
			(unlocked yes)
			(layer "B.Fab")
			(hide yes)
			(effects
				(font
					(size 1 1)
					(thickness 0.15)
				)
				(justify mirror)
			)
		)
		(property "Tolerance" "~"
			(at 0 0 180)
			(unlocked yes)
			(layer "B.Fab")
			(hide yes)
			(effects
				(font
					(size 1 1)
					(thickness 0.15)
				)
				(justify mirror)
			)
		)
		(property "Current" "1A"
			(at 0 0 180)
			(unlocked yes)
			(layer "B.Fab")
			(hide yes)
			(effects
				(font
					(size 1 1)
					(thickness 0.15)
				)
				(justify mirror)
			)
		)
		(sheetname "/SoM_IO2/")
		(sheetfile "som_io2.kicad_sch")
		(attr smd)
		(fp_poly
			(pts
				(xy -0.925 0.47) (xy -0.925 -0.47) (xy 0.925 -0.47) (xy 0.925 0.47)
			)
			(stroke
				(width 0.05)
				(type default)
			)
			(fill no)
			(layer "B.CrtYd")
		)
		(fp_poly
			(pts
				(xy -0.5 0.25) (xy -0.5 -0.25) (xy 0.5 -0.25) (xy 0.5 0.25)
			)
			(stroke
				(width 0.15)
				(type solid)
			)
			(fill no)
			(layer "B.Fab")
		)
		(fp_text user "Author: Antmicro"
			(at -0.95 -4.169 0)
			(layer "B.Fab")
			(effects
				(font
					(size 0.7 0.7)
					(thickness 0.15)
				)
				(justify right top mirror)
			)
		)
		(fp_text user "License: Apache-2.0"
			(at -0.949999 -5.169 0)
			(layer "B.Fab")
			(effects
				(font
					(size 0.7 0.7)
					(thickness 0.15)
				)
				(justify right top mirror)
			)
		)
		(fp_text user "${REFERENCE}"
			(at -0.95 -3.168 0)
			(layer "B.Fab")
			(effects
				(font
					(size 0.7 0.7)
					(thickness 0.15)
				)
				(justify right top mirror)
			)
		)
		(pad "1" smd roundrect
			(at -0.48 0)
			(size 0.59 0.64)
			(layers "B.Cu" "B.Mask" "B.Paste")
			(roundrect_rratio 0.25)
			(net 843 "/Expansion connector/PCIe_{C2x1}.CLK+")
			(pintype "passive")
		)
		(pad "2" smd roundrect
			(at 0.48 0)
			(size 0.59 0.64)
			(layers "B.Cu" "B.Mask" "B.Paste")
			(roundrect_rratio 0.25)
			(net 720 "/SoM_IO2/PCIe_{C2x1}R_CLK+")
			(pintype "passive")
		)
	)
	(footprint "antmicro-footprints:R_0402_1005Metric"
		(layer "B.Cu")
		(at 195.6 131.65 -90)
		(descr "Resistor SMD 0402")
		(tags "resistor SMD 0402")
		(property "Reference" "R321"
			(at -1.3 0.588198 90)
			(layer "B.SilkS")
			(effects
				(font
					(size 0.7 0.7)
					(thickness 0.15)
				)
				(justify left bottom mirror)
			)
		)
		(property "Value" "R_10k_0402"
			(at -1.011843 -1.772047 90)
			(layer "B.Fab")
			(effects
				(font
					(size 0.7 0.7)
					(thickness 0.15)
				)
				(justify left bottom mirror)
			)
		)
		(property "Datasheet" "https://www.bourns.com/docs/product-datasheets/cr.pdf"
			(at 0 0 90)
			(layer "B.Fab")
			(hide yes)
			(effects
				(font
					(size 1.27 1.27)
					(thickness 0.15)
				)
				(justify mirror)
			)
		)
		(property "Description" "SMD Chip Resistor, 10 kohm, ± 1%, 62.5 mW, 0402 [1005 Metric], Thick Film, General Purpose"
			(at 0 0 90)
			(layer "B.Fab")
			(hide yes)
			(effects
				(font
					(size 1.27 1.27)
					(thickness 0.15)
				)
				(justify mirror)
			)
		)
		(property "Manufacturer" "Bourns"
			(at 0 0 90)
			(unlocked yes)
			(layer "B.Fab")
			(hide yes)
			(effects
				(font
					(size 1 1)
					(thickness 0.15)
				)
				(justify mirror)
			)
		)
		(property "MPN" "CR0402-FX-1002GLF"
			(at 0 0 90)
			(unlocked yes)
			(layer "B.Fab")
			(hide yes)
			(effects
				(font
					(size 1 1)
					(thickness 0.15)
				)
				(justify mirror)
			)
		)
		(property "Val" "10k"
			(at 0 0 90)
			(unlocked yes)
			(layer "B.Fab")
			(hide yes)
			(effects
				(font
					(size 1 1)
					(thickness 0.15)
				)
				(justify mirror)
			)
		)
		(property "License" "Apache-2.0"
			(at 0 0 90)
			(unlocked yes)
			(layer "B.Fab")
			(hide yes)
			(effects
				(font
					(size 1 1)
					(thickness 0.15)
				)
				(justify mirror)
			)
		)
		(property "Author" "Antmicro"
			(at 0 0 90)
			(unlocked yes)
			(layer "B.Fab")
			(hide yes)
			(effects
				(font
					(size 1 1)
					(thickness 0.15)
				)
				(justify mirror)
			)
		)
		(property "Tolerance" "1%"
			(at 0 0 90)
			(unlocked yes)
			(layer "B.Fab")
			(hide yes)
			(effects
				(font
					(size 1 1)
					(thickness 0.15)
				)
				(justify mirror)
			)
		)
		(sheetname "/USB Hub/")
		(sheetfile "usb_hub.kicad_sch")
		(attr smd exclude_from_pos_files exclude_from_bom dnp)
		(fp_rect
			(start -0.925 0.47)
			(end 0.925 -0.47)
			(stroke
				(width 0.05)
				(type default)
			)
			(fill no)
			(layer "B.CrtYd")
		)
		(fp_rect
			(start -0.5 0.25)
			(end 0.5 -0.25)
			(stroke
				(width 0.15)
				(type solid)
			)
			(fill no)
			(layer "B.Fab")
		)
		(fp_text user "License: Apache-2.0"
			(at -0.95 -5.169 90)
			(layer "B.Fab")
			(effects
				(font
					(size 0.7 0.7)
					(thickness 0.15)
				)
				(justify left bottom mirror)
			)
		)
		(fp_text user "${REFERENCE}"
			(at -0.95 -3.168 90)
			(layer "B.Fab")
			(effects
				(font
					(size 0.7 0.7)
					(thickness 0.15)
				)
				(justify left bottom mirror)
			)
		)
		(fp_text user "Author: Antmicro"
			(at -0.95 -4.169 90)
			(layer "B.Fab")
			(effects
				(font
					(size 0.7 0.7)
					(thickness 0.15)
				)
				(justify left bottom mirror)
			)
		)
		(pad "1" smd roundrect
			(at -0.48 0 270)
			(size 0.59 0.64)
			(layers "B.Cu" "B.Mask" "B.Paste")
			(roundrect_rratio 0.25)
			(net 930 "/USB Hub/HUB_SPI_CE_N")
			(pintype "passive")
		)
		(pad "2" smd roundrect
			(at 0.48 0 270)
			(size 0.59 0.64)
			(layers "B.Cu" "B.Mask" "B.Paste")
			(roundrect_rratio 0.25)
			(net 2 "+3V3")
			(pintype "passive")
		)
	)
	(footprint "antmicro-footprints:R_0402_1005Metric"
		(layer "B.Cu")
		(at 104.9 64.5 -90)
		(descr "Resistor SMD 0402")
		(tags "resistor SMD 0402")
		(property "Reference" "R2"
			(at -2.5 -0.48 90)
			(layer "B.SilkS")
			(effects
				(font
					(size 0.7 0.7)
					(thickness 0.15)
				)
				(justify left bottom mirror)
			)
		)
		(property "Value" "R_33R_0402"
			(at -1.011843 -1.772047 90)
			(layer "B.Fab")
			(effects
				(font
					(size 0.7 0.7)
					(thickness 0.15)
				)
				(justify left bottom mirror)
			)
		)
		(property "Datasheet" "https://www.bourns.com/docs/product-datasheets/cr.pdf"
			(at 0 0 90)
			(layer "B.Fab")
			(hide yes)
			(effects
				(font
					(size 1.27 1.27)
					(thickness 0.15)
				)
				(justify mirror)
			)
		)
		(property "Description" "SMD Chip Resistor, 33 ohm, ± 1%, 62.5 mW, 0402 [1005 Metric], Thick Film, General Purpose"
			(at 0 0 90)
			(layer "B.Fab")
			(hide yes)
			(effects
				(font
					(size 1.27 1.27)
					(thickness 0.15)
				)
				(justify mirror)
			)
		)
		(property "MPN" "CR0402-FX-33R0GLF"
			(at 0 0 90)
			(unlocked yes)
			(layer "B.Fab")
			(hide yes)
			(effects
				(font
					(size 1 1)
					(thickness 0.15)
				)
				(justify mirror)
			)
		)
		(property "Manufacturer" "Bourns"
			(at 0 0 90)
			(unlocked yes)
			(layer "B.Fab")
			(hide yes)
			(effects
				(font
					(size 1 1)
					(thickness 0.15)
				)
				(justify mirror)
			)
		)
		(property "License" "Apache-2.0"
			(at 0 0 90)
			(unlocked yes)
			(layer "B.Fab")
			(hide yes)
			(effects
				(font
					(size 1 1)
					(thickness 0.15)
				)
				(justify mirror)
			)
		)
		(property "Author" "Antmicro"
			(at 0 0 90)
			(unlocked yes)
			(layer "B.Fab")
			(hide yes)
			(effects
				(font
					(size 1 1)
					(thickness 0.15)
				)
				(justify mirror)
			)
		)
		(property "Val" "33R"
			(at 0 0 90)
			(unlocked yes)
			(layer "B.Fab")
			(hide yes)
			(effects
				(font
					(size 1 1)
					(thickness 0.15)
				)
				(justify mirror)
			)
		)
		(property "Tolerance" "1%"
			(at 0 0 90)
			(unlocked yes)
			(layer "B.Fab")
			(hide yes)
			(effects
				(font
					(size 1 1)
					(thickness 0.15)
				)
				(justify mirror)
			)
		)
		(sheetname "/SoM_IO2/")
		(sheetfile "som_io2.kicad_sch")
		(attr smd)
		(fp_rect
			(start -0.925 0.47)
			(end 0.925 -0.47)
			(stroke
				(width 0.05)
				(type default)
			)
			(fill no)
			(layer "B.CrtYd")
		)
		(fp_rect
			(start -0.5 0.25)
			(end 0.5 -0.25)
			(stroke
				(width 0.15)
				(type solid)
			)
			(fill no)
			(layer "B.Fab")
		)
		(fp_text user "${REFERENCE}"
			(at -0.95 -3.168 90)
			(layer "B.Fab")
			(effects
				(font
					(size 0.7 0.7)
					(thickness 0.15)
				)
				(justify left bottom mirror)
			)
		)
		(fp_text user "License: Apache-2.0"
			(at -0.95 -5.169 90)
			(layer "B.Fab")
			(effects
				(font
					(size 0.7 0.7)
					(thickness 0.15)
				)
				(justify left bottom mirror)
			)
		)
		(fp_text user "Author: Antmicro"
			(at -0.95 -4.169 90)
			(layer "B.Fab")
			(effects
				(font
					(size 0.7 0.7)
					(thickness 0.15)
				)
				(justify left bottom mirror)
			)
		)
		(pad "1" smd roundrect
			(at -0.48 0 270)
			(size 0.59 0.64)
			(layers "B.Cu" "B.Mask" "B.Paste")
			(roundrect_rratio 0.25)
			(net 894 "/SoM_IO2/SFI_CLK+")
			(pintype "passive")
		)
		(pad "2" smd roundrect
			(at 0.48 0 270)
			(size 0.59 0.64)
			(layers "B.Cu" "B.Mask" "B.Paste")
			(roundrect_rratio 0.25)
			(net 169 "/SoM_IO2/SFI_REFCLK+")
			(pintype "passive")
		)
	)
	(footprint "antmicro-footprints:R_0402_1005Metric"
		(layer "B.Cu")
		(at 108.555 138.43 90)
		(descr "Resistor SMD 0402")
		(tags "resistor SMD 0402")
		(property "Reference" "R222"
			(at -1.35 -2.795 90)
			(layer "B.SilkS")
			(effects
				(font
					(size 0.7 0.7)
					(thickness 0.15)
				)
				(justify right top mirror)
			)
		)
		(property "Value" "R_200R_0402"
			(at -1.011843 -1.772047 90)
			(layer "B.Fab")
			(effects
				(font
					(size 0.7 0.7)
					(thickness 0.15)
				)
				(justify right top mirror)
			)
		)
		(property "Datasheet" "https://www.bourns.com/docs/product-datasheets/cr.pdf"
			(at 0 0 90)
			(layer "B.Fab")
			(hide yes)
			(effects
				(font
					(size 1.27 1.27)
					(thickness 0.15)
				)
				(justify mirror)
			)
		)
		(property "Description" "SMD Chip Resistor, 200 ohm, ± 1%, 62.5 mW, 0402 [1005 Metric], Thick Film, General Purpose"
			(at 0 0 90)
			(layer "B.Fab")
			(hide yes)
			(effects
				(font
					(size 1.27 1.27)
					(thickness 0.15)
				)
				(justify mirror)
			)
		)
		(property "MPN" "CR0402-FX-2000GLF"
			(at 0 0 270)
			(unlocked yes)
			(layer "B.Fab")
			(hide yes)
			(effects
				(font
					(size 1 1)
					(thickness 0.15)
				)
				(justify mirror)
			)
		)
		(property "Manufacturer" "Bourns"
			(at 0 0 270)
			(unlocked yes)
			(layer "B.Fab")
			(hide yes)
			(effects
				(font
					(size 1 1)
					(thickness 0.15)
				)
				(justify mirror)
			)
		)
		(property "License" "Apache-2.0"
			(at 0 0 270)
			(unlocked yes)
			(layer "B.Fab")
			(hide yes)
			(effects
				(font
					(size 1 1)
					(thickness 0.15)
				)
				(justify mirror)
			)
		)
		(property "Author" "Antmicro"
			(at 0 0 270)
			(unlocked yes)
			(layer "B.Fab")
			(hide yes)
			(effects
				(font
					(size 1 1)
					(thickness 0.15)
				)
				(justify mirror)
			)
		)
		(property "Val" "200R"
			(at 0 0 270)
			(unlocked yes)
			(layer "B.Fab")
			(hide yes)
			(effects
				(font
					(size 1 1)
					(thickness 0.15)
				)
				(justify mirror)
			)
		)
		(property "Tolerance" "1%"
			(at 0 0 270)
			(unlocked yes)
			(layer "B.Fab")
			(hide yes)
			(effects
				(font
					(size 1 1)
					(thickness 0.15)
				)
				(justify mirror)
			)
		)
		(sheetname "/M.2/")
		(sheetfile "m2.kicad_sch")
		(attr smd)
		(fp_rect
			(start -0.925 0.47)
			(end 0.925 -0.47)
			(stroke
				(width 0.05)
				(type default)
			)
			(fill no)
			(layer "B.CrtYd")
		)
		(fp_rect
			(start -0.5 0.25)
			(end 0.5 -0.25)
			(stroke
				(width 0.15)
				(type solid)
			)
			(fill no)
			(layer "B.Fab")
		)
		(fp_text user "Author: Antmicro"
			(at -0.95 -4.169 90)
			(layer "B.Fab")
			(effects
				(font
					(size 0.7 0.7)
					(thickness 0.15)
				)
				(justify right top mirror)
			)
		)
		(fp_text user "License: Apache-2.0"
			(at -0.95 -5.169 90)
			(layer "B.Fab")
			(effects
				(font
					(size 0.7 0.7)
					(thickness 0.15)
				)
				(justify right top mirror)
			)
		)
		(fp_text user "${REFERENCE}"
			(at -0.95 -3.168 90)
			(layer "B.Fab")
			(effects
				(font
					(size 0.7 0.7)
					(thickness 0.15)
				)
				(justify right top mirror)
			)
		)
		(pad "1" smd roundrect
			(at -0.48 0 90)
			(size 0.59 0.64)
			(layers "B.Cu" "B.Mask" "B.Paste")
			(roundrect_rratio 0.25)
			(net 546 "Net-(D34-A)")
			(pintype "passive")
		)
		(pad "2" smd roundrect
			(at 0.48 0 90)
			(size 0.59 0.64)
			(layers "B.Cu" "B.Mask" "B.Paste")
			(roundrect_rratio 0.25)
			(net 2 "+3V3")
			(pintype "passive")
		)
	)
	(footprint "antmicro-footprints:TP_SMD_0.75mm"
		(layer "B.Cu")
		(at 232.3 75 180)
		(property "Reference" "TP62"
			(at 0 0.6 0)
			(layer "B.SilkS")
			(effects
				(font
					(size 0.7 0.7)
					(thickness 0.15)
				)
				(justify left bottom mirror)
			)
		)
		(property "Value" "TP_0.75mm_SMD"
			(at 0 -1.2 0)
			(layer "B.Fab")
			(effects
				(font
					(size 0.7 0.7)
					(thickness 0.15)
				)
				(justify left bottom mirror)
			)
		)
		(property "Description" "SMT test point"
			(at 0 0 0)
			(layer "B.Fab")
			(hide yes)
			(effects
				(font
					(size 1.27 1.27)
					(thickness 0.15)
				)
				(justify mirror)
			)
		)
		(property "MPN" ""
			(at 0 0 0)
			(unlocked yes)
			(layer "B.Fab")
			(hide yes)
			(effects
				(font
					(size 1 1)
					(thickness 0.15)
				)
				(justify mirror)
			)
		)
		(property "Manufacturer" ""
			(at 0 0 0)
			(unlocked yes)
			(layer "B.Fab")
			(hide yes)
			(effects
				(font
					(size 1 1)
					(thickness 0.15)
				)
				(justify mirror)
			)
		)
		(property "Author" "Antmicro"
			(at 0 0 0)
			(unlocked yes)
			(layer "B.Fab")
			(hide yes)
			(effects
				(font
					(size 1 1)
					(thickness 0.15)
				)
				(justify mirror)
			)
		)
		(property "License" "Apache-2.0"
			(at 0 0 0)
			(unlocked yes)
			(layer "B.Fab")
			(hide yes)
			(effects
				(font
					(size 1 1)
					(thickness 0.15)
				)
				(justify mirror)
			)
		)
		(sheetname "/USB Debug, PD/")
		(sheetfile "usb_debug_pd.kicad_sch")
		(attr exclude_from_pos_files exclude_from_bom)
		(fp_circle
			(center 0 0)
			(end 0.475 0)
			(stroke
				(width 0.05)
				(type default)
			)
			(fill no)
			(layer "B.CrtYd")
		)
		(fp_text user "License: Apache-2.0"
			(at -0.4 -5.101 0)
			(layer "B.Fab")
			(effects
				(font
					(size 0.7 0.7)
					(thickness 0.15)
				)
				(justify left bottom mirror)
			)
		)
		(fp_text user "Author: Antmicro"
			(at -0.4 -3.901 0)
			(layer "B.Fab")
			(effects
				(font
					(size 0.7 0.7)
					(thickness 0.15)
				)
				(justify left bottom mirror)
			)
		)
		(fp_text user "${REFERENCE}"
			(at -0.4 -2.7 0)
			(layer "B.Fab")
			(effects
				(font
					(size 0.7 0.7)
					(thickness 0.15)
				)
				(justify left bottom mirror)
			)
		)
		(pad "1" smd circle
			(at 0 0 180)
			(size 0.75 0.75)
			(layers "B.Cu" "B.Mask")
			(net 176 "/USB Debug, PD/USBC0_VBUS")
			(pinfunction "1")
			(pintype "passive")
		)
	)
	(footprint "antmicro-footprints:SOD-523"
		(layer "B.Cu")
		(at 219.13 113.56 90)
		(property "Reference" "D57"
			(at -3.24 -0.43 90)
			(layer "B.SilkS")
			(effects
				(font
					(size 0.7 0.7)
					(thickness 0.15)
				)
				(justify right top mirror)
			)
		)
		(property "Value" "RB521S30T1G"
			(at 0 -1.499 90)
			(layer "B.Fab")
			(effects
				(font
					(size 0.7 0.7)
					(thickness 0.15)
				)
				(justify right top mirror)
			)
		)
		(property "Datasheet" "https://www.onsemi.com/pdf/datasheet/rb521s30t1-d.pdf"
			(at 0 0 90)
			(layer "B.Fab")
			(hide yes)
			(effects
				(font
					(size 1.27 1.27)
					(thickness 0.15)
				)
				(justify mirror)
			)
		)
		(property "Description" "Small Signal Schottky Diode, Single, 30 V, 200 mA, 500 mV, 1 A, 125 °C"
			(at 0 0 90)
			(layer "B.Fab")
			(hide yes)
			(effects
				(font
					(size 1.27 1.27)
					(thickness 0.15)
				)
				(justify mirror)
			)
		)
		(property "MPN" "RB521S30T1G"
			(at 0 0 270)
			(unlocked yes)
			(layer "B.Fab")
			(hide yes)
			(effects
				(font
					(size 1 1)
					(thickness 0.15)
				)
				(justify mirror)
			)
		)
		(property "Manufacturer" "ON Semiconductor"
			(at 0 0 270)
			(unlocked yes)
			(layer "B.Fab")
			(hide yes)
			(effects
				(font
					(size 1 1)
					(thickness 0.15)
				)
				(justify mirror)
			)
		)
		(property "Author" "Antmicro"
			(at 0 0 270)
			(unlocked yes)
			(layer "B.Fab")
			(hide yes)
			(effects
				(font
					(size 1 1)
					(thickness 0.15)
				)
				(justify mirror)
			)
		)
		(property "License" "Apache-2.0"
			(at 0 0 270)
			(unlocked yes)
			(layer "B.Fab")
			(hide yes)
			(effects
				(font
					(size 1 1)
					(thickness 0.15)
				)
				(justify mirror)
			)
		)
		(sheetname "/USB Hub/")
		(sheetfile "usb_hub.kicad_sch")
		(attr smd)
		(fp_line
			(start -0.35 0.5)
			(end -0.35 -0.5)
			(stroke
				(width 0.15)
				(type solid)
			)
			(layer "B.SilkS")
		)
		(fp_rect
			(start -1 0.6)
			(end 1 -0.6)
			(stroke
				(width 0.05)
				(type solid)
			)
			(fill no)
			(layer "B.CrtYd")
		)
		(fp_line
			(start -0.652 -0.423)
			(end 0.65 -0.423)
			(stroke
				(width 0.15)
				(type solid)
			)
			(layer "B.Fab")
		)
		(fp_line
			(start -0.652 -0.423)
			(end -0.652 0.425)
			(stroke
				(width 0.15)
				(type solid)
			)
			(layer "B.Fab")
		)
		(fp_line
			(start -0.35 0.4)
			(end -0.35 -0.4)
			(stroke
				(width 0.15)
				(type solid)
			)
			(layer "B.Fab")
		)
		(fp_line
			(start 0.65 0.425)
			(end 0.65 -0.423)
			(stroke
				(width 0.15)
				(type solid)
			)
			(layer "B.Fab")
		)
		(fp_line
			(start -0.652 0.425)
			(end 0.65 0.425)
			(stroke
				(width 0.15)
				(type solid)
			)
			(layer "B.Fab")
		)
		(fp_text user "Author: Antmicro"
			(at -1.276 -4.7 90)
			(layer "B.Fab")
			(effects
				(font
					(size 0.7 0.7)
					(thickness 0.15)
				)
				(justify right top mirror)
			)
		)
		(fp_text user "${REFERENCE}"
			(at -1.276 -3.499 90)
			(layer "B.Fab")
			(effects
				(font
					(size 0.7 0.7)
					(thickness 0.15)
				)
				(justify right top mirror)
			)
		)
		(fp_text user "License: Apache-2.0"
			(at -1.276 -5.9 90)
			(layer "B.Fab")
			(effects
				(font
					(size 0.7 0.7)
					(thickness 0.15)
				)
				(justify right top mirror)
			)
		)
		(pad "1" smd roundrect
			(at -0.701 0 90)
			(size 0.5 0.6)
			(layers "B.Cu" "B.Mask" "B.Paste")
			(roundrect_rratio 0.25)
			(net 633 "Net-(D57-C)")
			(pinfunction "C")
			(pintype "passive")
		)
		(pad "2" smd roundrect
			(at 0.699 0 90)
			(size 0.5 0.6)
			(layers "B.Cu" "B.Mask" "B.Paste")
			(roundrect_rratio 0.25)
			(net 1019 "Net-(D57-A)")
			(pinfunction "A")
			(pintype "passive")
		)
	)
	(footprint "antmicro-footprints:R_0402_1005Metric"
		(layer "B.Cu")
		(at 135.8 65.2 90)
		(descr "Resistor SMD 0402")
		(tags "resistor SMD 0402")
		(property "Reference" "R241"
			(at -3.8 -0.5 90)
			(layer "B.SilkS")
			(effects
				(font
					(size 0.7 0.7)
					(thickness 0.15)
				)
				(justify right top mirror)
			)
		)
		(property "Value" "R_10k_0402"
			(at -1.011843 -1.772047 90)
			(layer "B.Fab")
			(effects
				(font
					(size 0.7 0.7)
					(thickness 0.15)
				)
				(justify right top mirror)
			)
		)
		(property "Datasheet" "https://www.bourns.com/docs/product-datasheets/cr.pdf"
			(at 0 0 90)
			(layer "B.Fab")
			(hide yes)
			(effects
				(font
					(size 1.27 1.27)
					(thickness 0.15)
				)
				(justify mirror)
			)
		)
		(property "Description" "SMD Chip Resistor, 10 kohm, ± 1%, 62.5 mW, 0402 [1005 Metric], Thick Film, General Purpose"
			(at 0 0 90)
			(layer "B.Fab")
			(hide yes)
			(effects
				(font
					(size 1.27 1.27)
					(thickness 0.15)
				)
				(justify mirror)
			)
		)
		(property "Manufacturer" "Bourns"
			(at 0 0 270)
			(unlocked yes)
			(layer "B.Fab")
			(hide yes)
			(effects
				(font
					(size 1 1)
					(thickness 0.15)
				)
				(justify mirror)
			)
		)
		(property "MPN" "CR0402-FX-1002GLF"
			(at 0 0 270)
			(unlocked yes)
			(layer "B.Fab")
			(hide yes)
			(effects
				(font
					(size 1 1)
					(thickness 0.15)
				)
				(justify mirror)
			)
		)
		(property "Val" "10k"
			(at 0 0 270)
			(unlocked yes)
			(layer "B.Fab")
			(hide yes)
			(effects
				(font
					(size 1 1)
					(thickness 0.15)
				)
				(justify mirror)
			)
		)
		(property "License" "Apache-2.0"
			(at 0 0 270)
			(unlocked yes)
			(layer "B.Fab")
			(hide yes)
			(effects
				(font
					(size 1 1)
					(thickness 0.15)
				)
				(justify mirror)
			)
		)
		(property "Author" "Antmicro"
			(at 0 0 270)
			(unlocked yes)
			(layer "B.Fab")
			(hide yes)
			(effects
				(font
					(size 1 1)
					(thickness 0.15)
				)
				(justify mirror)
			)
		)
		(property "Tolerance" "1%"
			(at 0 0 270)
			(unlocked yes)
			(layer "B.Fab")
			(hide yes)
			(effects
				(font
					(size 1 1)
					(thickness 0.15)
				)
				(justify mirror)
			)
		)
		(sheetname "/Peripherals/")
		(sheetfile "peripherals.kicad_sch")
		(attr smd)
		(fp_rect
			(start -0.925 0.47)
			(end 0.925 -0.47)
			(stroke
				(width 0.05)
				(type default)
			)
			(fill no)
			(layer "B.CrtYd")
		)
		(fp_rect
			(start -0.5 0.25)
			(end 0.5 -0.25)
			(stroke
				(width 0.15)
				(type solid)
			)
			(fill no)
			(layer "B.Fab")
		)
		(fp_text user "${REFERENCE}"
			(at -0.95 -3.168 90)
			(layer "B.Fab")
			(effects
				(font
					(size 0.7 0.7)
					(thickness 0.15)
				)
				(justify right top mirror)
			)
		)
		(fp_text user "License: Apache-2.0"
			(at -0.95 -5.169 90)
			(layer "B.Fab")
			(effects
				(font
					(size 0.7 0.7)
					(thickness 0.15)
				)
				(justify right top mirror)
			)
		)
		(fp_text user "Author: Antmicro"
			(at -0.95 -4.169 90)
			(layer "B.Fab")
			(effects
				(font
					(size 0.7 0.7)
					(thickness 0.15)
				)
				(justify right top mirror)
			)
		)
		(pad "1" smd roundrect
			(at -0.48 0 90)
			(size 0.59 0.64)
			(layers "B.Cu" "B.Mask" "B.Paste")
			(roundrect_rratio 0.25)
			(net 1 "GND")
			(pintype "passive")
		)
		(pad "2" smd roundrect
			(at 0.48 0 90)
			(size 0.59 0.64)
			(layers "B.Cu" "B.Mask" "B.Paste")
			(roundrect_rratio 0.25)
			(net 1009 "Net-(U53-ISET)")
			(pintype "passive")
		)
	)
	(footprint "antmicro-footprints:TP_SMD_0.75mm"
		(layer "B.Cu")
		(at 180.89 58 180)
		(property "Reference" "TP126"
			(at -0.43 4.03 90)
			(layer "B.SilkS")
			(effects
				(font
					(size 0.7 0.7)
					(thickness 0.15)
				)
				(justify left bottom mirror)
			)
		)
		(property "Value" "TP_0.75mm_SMD"
			(at 0 -1.2 0)
			(layer "B.Fab")
			(effects
				(font
					(size 0.7 0.7)
					(thickness 0.15)
				)
				(justify left bottom mirror)
			)
		)
		(property "Description" "SMT test point"
			(at 0 0 0)
			(layer "B.Fab")
			(hide yes)
			(effects
				(font
					(size 1.27 1.27)
					(thickness 0.15)
				)
				(justify mirror)
			)
		)
		(property "MPN" ""
			(at 0 0 0)
			(unlocked yes)
			(layer "B.Fab")
			(hide yes)
			(effects
				(font
					(size 1 1)
					(thickness 0.15)
				)
				(justify mirror)
			)
		)
		(property "Manufacturer" ""
			(at 0 0 0)
			(unlocked yes)
			(layer "B.Fab")
			(hide yes)
			(effects
				(font
					(size 1 1)
					(thickness 0.15)
				)
				(justify mirror)
			)
		)
		(property "Author" "Antmicro"
			(at 0 0 0)
			(unlocked yes)
			(layer "B.Fab")
			(hide yes)
			(effects
				(font
					(size 1 1)
					(thickness 0.15)
				)
				(justify mirror)
			)
		)
		(property "License" "Apache-2.0"
			(at 0 0 0)
			(unlocked yes)
			(layer "B.Fab")
			(hide yes)
			(effects
				(font
					(size 1 1)
					(thickness 0.15)
				)
				(justify mirror)
			)
		)
		(sheetname "/Power/")
		(sheetfile "power.kicad_sch")
		(attr exclude_from_pos_files exclude_from_bom)
		(fp_circle
			(center 0 0)
			(end 0.475 0)
			(stroke
				(width 0.05)
				(type default)
			)
			(fill no)
			(layer "B.CrtYd")
		)
		(fp_text user "Author: Antmicro"
			(at -0.4 -3.901 0)
			(layer "B.Fab")
			(effects
				(font
					(size 0.7 0.7)
					(thickness 0.15)
				)
				(justify left bottom mirror)
			)
		)
		(fp_text user "License: Apache-2.0"
			(at -0.4 -5.101 0)
			(layer "B.Fab")
			(effects
				(font
					(size 0.7 0.7)
					(thickness 0.15)
				)
				(justify left bottom mirror)
			)
		)
		(fp_text user "${REFERENCE}"
			(at -0.4 -2.7 0)
			(layer "B.Fab")
			(effects
				(font
					(size 0.7 0.7)
					(thickness 0.15)
				)
				(justify left bottom mirror)
			)
		)
		(pad "1" smd circle
			(at 0 0 180)
			(size 0.75 0.75)
			(layers "B.Cu" "B.Mask")
			(net 12 "SYS_VIN_HV")
			(pinfunction "1")
			(pintype "passive")
		)
	)
	(footprint "antmicro-footprints:C_0402_1005Metric"
		(layer "B.Cu")
		(at 230.07 113.8 180)
		(descr "Capacitor SMD 0402")
		(tags "capacitor SMD 0402")
		(property "Reference" "C80"
			(at 0.9 -0.4 0)
			(layer "B.SilkS")
			(effects
				(font
					(size 0.7 0.7)
					(thickness 0.15)
				)
				(justify left bottom mirror)
			)
		)
		(property "Value" "C_100n_0402"
			(at -1.022927 -2.155213 0)
			(layer "B.Fab")
			(effects
				(font
					(size 0.7 0.7)
					(thickness 0.15)
				)
				(justify left bottom mirror)
			)
		)
		(property "Datasheet" "https://www.murata.com/products/productdetail?partno=GRM155R61H104KE14%23"
			(at 0 0 0)
			(layer "B.Fab")
			(hide yes)
			(effects
				(font
					(size 1.27 1.27)
					(thickness 0.15)
				)
				(justify mirror)
			)
		)
		(property "Description" "SMD Multilayer Ceramic Capacitor, 0.1 µF, 50 V, 0402 [1005 Metric], ± 10%, X5R, GRM Series"
			(at 0 0 0)
			(layer "B.Fab")
			(hide yes)
			(effects
				(font
					(size 1.27 1.27)
					(thickness 0.15)
				)
				(justify mirror)
			)
		)
		(property "Manufacturer" "Murata"
			(at 0 0 0)
			(unlocked yes)
			(layer "B.Fab")
			(hide yes)
			(effects
				(font
					(size 1 1)
					(thickness 0.15)
				)
				(justify mirror)
			)
		)
		(property "MPN" "GRM155R61H104KE14D"
			(at 0 0 0)
			(unlocked yes)
			(layer "B.Fab")
			(hide yes)
			(effects
				(font
					(size 1 1)
					(thickness 0.15)
				)
				(justify mirror)
			)
		)
		(property "Val" "100n"
			(at 0 0 0)
			(unlocked yes)
			(layer "B.Fab")
			(hide yes)
			(effects
				(font
					(size 1 1)
					(thickness 0.15)
				)
				(justify mirror)
			)
		)
		(property "License" "Apache-2.0"
			(at 0 0 0)
			(unlocked yes)
			(layer "B.Fab")
			(hide yes)
			(effects
				(font
					(size 1 1)
					(thickness 0.15)
				)
				(justify mirror)
			)
		)
		(property "Author" "Antmicro"
			(at 0 0 0)
			(unlocked yes)
			(layer "B.Fab")
			(hide yes)
			(effects
				(font
					(size 1 1)
					(thickness 0.15)
				)
				(justify mirror)
			)
		)
		(property "Voltage" "50V"
			(at 0 0 0)
			(unlocked yes)
			(layer "B.Fab")
			(hide yes)
			(effects
				(font
					(size 1 1)
					(thickness 0.15)
				)
				(justify mirror)
			)
		)
		(property "Dielectric" "X5R"
			(at 0 0 0)
			(unlocked yes)
			(layer "B.Fab")
			(hide yes)
			(effects
				(font
					(size 1 1)
					(thickness 0.15)
				)
				(justify mirror)
			)
		)
		(sheetname "/USB Hub/")
		(sheetfile "usb_hub.kicad_sch")
		(attr smd)
		(fp_poly
			(pts
				(xy -0.925 0.47) (xy 0.925 0.47) (xy 0.925 -0.47) (xy -0.925 -0.47)
			)
			(stroke
				(width 0.05)
				(type default)
			)
			(fill no)
			(layer "B.CrtYd")
		)
		(fp_line
			(start 0.504 0.25)
			(end 0.504 -0.248)
			(stroke
				(width 0.15)
				(type solid)
			)
			(layer "B.Fab")
		)
		(fp_line
			(start 0.504 -0.248)
			(end -0.494 -0.248)
			(stroke
				(width 0.15)
				(type solid)
			)
			(layer "B.Fab")
		)
		(fp_line
			(start -0.494 0.25)
			(end 0.504 0.25)
			(stroke
				(width 0.15)
				(type solid)
			)
			(layer "B.Fab")
		)
		(fp_line
			(start -0.494 -0.248)
			(end -0.494 0.25)
			(stroke
				(width 0.15)
				(type solid)
			)
			(layer "B.Fab")
		)
		(fp_text user "License: Apache-2.0"
			(at -0.939 -5.799 0)
			(layer "B.Fab")
			(effects
				(font
					(size 0.7 0.7)
					(thickness 0.15)
				)
				(justify left bottom mirror)
			)
		)
		(fp_text user "Author: Antmicro"
			(at -0.939 -3.399 0)
			(layer "B.Fab")
			(effects
				(font
					(size 0.7 0.7)
					(thickness 0.15)
				)
				(justify left bottom mirror)
			)
		)
		(fp_text user "${REFERENCE}"
			(at -0.939 -4.599 0)
			(layer "B.Fab")
			(effects
				(font
					(size 0.7 0.7)
					(thickness 0.15)
				)
				(justify left bottom mirror)
			)
		)
		(pad "1" smd roundrect
			(at -0.48 0 180)
			(size 0.59 0.64)
			(layers "B.Cu" "B.Mask" "B.Paste")
			(roundrect_rratio 0.25)
			(net 71 "/USB Hub/USBC3_VBUS")
			(pintype "passive")
		)
		(pad "2" smd roundrect
			(at 0.48 0 180)
			(size 0.59 0.64)
			(layers "B.Cu" "B.Mask" "B.Paste")
			(roundrect_rratio 0.25)
			(net 1 "GND")
			(pintype "passive")
		)
	)
	(footprint "antmicro-footprints:R_0402_1005Metric"
		(layer "B.Cu")
		(at 124.6 107.8 180)
		(descr "Resistor SMD 0402")
		(tags "resistor SMD 0402")
		(property "Reference" "R207"
			(at -3.9 -0.36 0)
			(layer "B.SilkS")
			(effects
				(font
					(size 0.7 0.7)
					(thickness 0.15)
				)
				(justify left bottom mirror)
			)
		)
		(property "Value" "R_0R_0402"
			(at -1.011843 -1.772046 0)
			(layer "B.Fab")
			(effects
				(font
					(size 0.7 0.7)
					(thickness 0.15)
				)
				(justify left bottom mirror)
			)
		)
		(property "Datasheet" "https://industrial.panasonic.com/cdbs/www-data/pdf/RDA0000/AOA0000C301.pdf"
			(at 0 0 0)
			(layer "B.Fab")
			(hide yes)
			(effects
				(font
					(size 1.27 1.27)
					(thickness 0.15)
				)
				(justify mirror)
			)
		)
		(property "Description" "SMD Chip Resistor, Jumper, 0 ohm, 100 mW, 0402 [1005 Metric], Thick Film, General Purpose"
			(at 0 0 0)
			(layer "B.Fab")
			(hide yes)
			(effects
				(font
					(size 1.27 1.27)
					(thickness 0.15)
				)
				(justify mirror)
			)
		)
		(property "MPN" "ERJ2GE0R00X"
			(at 0 0 0)
			(unlocked yes)
			(layer "B.Fab")
			(hide yes)
			(effects
				(font
					(size 1 1)
					(thickness 0.15)
				)
				(justify mirror)
			)
		)
		(property "Manufacturer" "Panasonic"
			(at 0 0 0)
			(unlocked yes)
			(layer "B.Fab")
			(hide yes)
			(effects
				(font
					(size 1 1)
					(thickness 0.15)
				)
				(justify mirror)
			)
		)
		(property "License" "Apache-2.0"
			(at 0 0 0)
			(unlocked yes)
			(layer "B.Fab")
			(hide yes)
			(effects
				(font
					(size 1 1)
					(thickness 0.15)
				)
				(justify mirror)
			)
		)
		(property "Author" "Antmicro"
			(at 0 0 0)
			(unlocked yes)
			(layer "B.Fab")
			(hide yes)
			(effects
				(font
					(size 1 1)
					(thickness 0.15)
				)
				(justify mirror)
			)
		)
		(property "Val" "0R"
			(at 0 0 0)
			(unlocked yes)
			(layer "B.Fab")
			(hide yes)
			(effects
				(font
					(size 1 1)
					(thickness 0.15)
				)
				(justify mirror)
			)
		)
		(property "Tolerance" "~"
			(at 0 0 0)
			(unlocked yes)
			(layer "B.Fab")
			(hide yes)
			(effects
				(font
					(size 1 1)
					(thickness 0.15)
				)
				(justify mirror)
			)
		)
		(property "Current" "1A"
			(at 0 0 0)
			(unlocked yes)
			(layer "B.Fab")
			(hide yes)
			(effects
				(font
					(size 1 1)
					(thickness 0.15)
				)
				(justify mirror)
			)
		)
		(sheetname "/M.2/")
		(sheetfile "m2.kicad_sch")
		(attr smd)
		(fp_poly
			(pts
				(xy -0.925 0.47) (xy 0.925 0.47) (xy 0.925 -0.47) (xy -0.925 -0.47)
			)
			(stroke
				(width 0.05)
				(type default)
			)
			(fill no)
			(layer "B.CrtYd")
		)
		(fp_poly
			(pts
				(xy -0.5 0.25) (xy 0.5 0.25) (xy 0.5 -0.25) (xy -0.5 -0.25)
			)
			(stroke
				(width 0.15)
				(type solid)
			)
			(fill no)
			(layer "B.Fab")
		)
		(fp_text user "License: Apache-2.0"
			(at -0.949999 -5.169 0)
			(layer "B.Fab")
			(effects
				(font
					(size 0.7 0.7)
					(thickness 0.15)
				)
				(justify left bottom mirror)
			)
		)
		(fp_text user "${REFERENCE}"
			(at -0.95 -3.168 0)
			(layer "B.Fab")
			(effects
				(font
					(size 0.7 0.7)
					(thickness 0.15)
				)
				(justify left bottom mirror)
			)
		)
		(fp_text user "Author: Antmicro"
			(at -0.95 -4.169 0)
			(layer "B.Fab")
			(effects
				(font
					(size 0.7 0.7)
					(thickness 0.15)
				)
				(justify left bottom mirror)
			)
		)
		(pad "1" smd roundrect
			(at -0.48 0 180)
			(size 0.59 0.64)
			(layers "B.Cu" "B.Mask" "B.Paste")
			(roundrect_rratio 0.25)
			(net 751 "/M.2/PCIe_{C5x4}.~{CLKREQ}")
			(pintype "passive")
		)
		(pad "2" smd roundrect
			(at 0.48 0 180)
			(size 0.59 0.64)
			(layers "B.Cu" "B.Mask" "B.Paste")
			(roundrect_rratio 0.25)
			(net 825 "/M.2/~{CLKREQ_M}")
			(pintype "passive")
		)
	)
	(footprint "antmicro-footprints:SOD-523"
		(layer "B.Cu")
		(at 230.07 100.9 180)
		(property "Reference" "D50"
			(at 1 -0.4 0)
			(layer "B.SilkS")
			(effects
				(font
					(size 0.7 0.7)
					(thickness 0.15)
				)
				(justify left bottom mirror)
			)
		)
		(property "Value" "PESD5Z5.0F"
			(at 0 -1.499 0)
			(layer "B.Fab")
			(effects
				(font
					(size 0.7 0.7)
					(thickness 0.15)
				)
				(justify left bottom mirror)
			)
		)
		(property "Datasheet" "https://assets.nexperia.com/documents/data-sheet/PESD5Z5_0.pdf"
			(at 0 0 0)
			(layer "B.Fab")
			(hide yes)
			(effects
				(font
					(size 1.27 1.27)
					(thickness 0.15)
				)
				(justify mirror)
			)
		)
		(property "Description" "Unidirectional TVS, 30 kV,  SOD-523, 5 V, 89 pF"
			(at 0 0 0)
			(layer "B.Fab")
			(hide yes)
			(effects
				(font
					(size 1.27 1.27)
					(thickness 0.15)
				)
				(justify mirror)
			)
		)
		(property "Manufacturer" "Nexperia"
			(at 0 0 180)
			(unlocked yes)
			(layer "B.Fab")
			(hide yes)
			(effects
				(font
					(size 1 1)
					(thickness 0.15)
				)
				(justify mirror)
			)
		)
		(property "MPN" "PESD5Z5.0F"
			(at 0 0 180)
			(unlocked yes)
			(layer "B.Fab")
			(hide yes)
			(effects
				(font
					(size 1 1)
					(thickness 0.15)
				)
				(justify mirror)
			)
		)
		(property "Author" "Antmicro"
			(at 0 0 180)
			(unlocked yes)
			(layer "B.Fab")
			(hide yes)
			(effects
				(font
					(size 1 1)
					(thickness 0.15)
				)
				(justify mirror)
			)
		)
		(property "License" "Apache-2.0"
			(at 0 0 180)
			(unlocked yes)
			(layer "B.Fab")
			(hide yes)
			(effects
				(font
					(size 1 1)
					(thickness 0.15)
				)
				(justify mirror)
			)
		)
		(sheetname "/Recovery USB/")
		(sheetfile "recovery_usb.kicad_sch")
		(attr smd)
		(fp_line
			(start -0.35 0.5)
			(end -0.35 -0.5)
			(stroke
				(width 0.15)
				(type solid)
			)
			(layer "B.SilkS")
		)
		(fp_rect
			(start -1 0.6)
			(end 1 -0.6)
			(stroke
				(width 0.05)
				(type solid)
			)
			(fill no)
			(layer "B.CrtYd")
		)
		(fp_line
			(start 0.65 0.425)
			(end 0.65 -0.423)
			(stroke
				(width 0.15)
				(type solid)
			)
			(layer "B.Fab")
		)
		(fp_line
			(start -0.35 0.4)
			(end -0.35 -0.4)
			(stroke
				(width 0.15)
				(type solid)
			)
			(layer "B.Fab")
		)
		(fp_line
			(start -0.652 0.425)
			(end 0.65 0.425)
			(stroke
				(width 0.15)
				(type solid)
			)
			(layer "B.Fab")
		)
		(fp_line
			(start -0.652 -0.423)
			(end 0.65 -0.423)
			(stroke
				(width 0.15)
				(type solid)
			)
			(layer "B.Fab")
		)
		(fp_line
			(start -0.652 -0.423)
			(end -0.652 0.425)
			(stroke
				(width 0.15)
				(type solid)
			)
			(layer "B.Fab")
		)
		(fp_text user "Author: Antmicro"
			(at -1.276 -4.7 0)
			(layer "B.Fab")
			(effects
				(font
					(size 0.7 0.7)
					(thickness 0.15)
				)
				(justify left bottom mirror)
			)
		)
		(fp_text user "${REFERENCE}"
			(at -1.276 -3.499 0)
			(layer "B.Fab")
			(effects
				(font
					(size 0.7 0.7)
					(thickness 0.15)
				)
				(justify left bottom mirror)
			)
		)
		(fp_text user "License: Apache-2.0"
			(at -1.276 -5.9 0)
			(layer "B.Fab")
			(effects
				(font
					(size 0.7 0.7)
					(thickness 0.15)
				)
				(justify left bottom mirror)
			)
		)
		(pad "1" smd roundrect
			(at -0.701 0 180)
			(size 0.5 0.6)
			(layers "B.Cu" "B.Mask" "B.Paste")
			(roundrect_rratio 0.25)
			(net 287 "/Recovery USB/USBC2_VBUS")
			(pinfunction "C")
			(pintype "passive")
		)
		(pad "2" smd roundrect
			(at 0.699 0 180)
			(size 0.5 0.6)
			(layers "B.Cu" "B.Mask" "B.Paste")
			(roundrect_rratio 0.25)
			(net 1 "GND")
			(pinfunction "A")
			(pintype "passive")
		)
	)
	(footprint "antmicro-footprints:TP_SMD_0.75mm"
		(layer "B.Cu")
		(at 191.8 80.6815)
		(property "Reference" "TP14"
			(at 0.4 -3.2815 90)
			(layer "B.SilkS")
			(effects
				(font
					(size 0.7 0.7)
					(thickness 0.15)
				)
				(justify left bottom mirror)
			)
		)
		(property "Value" "TP_0.75mm_SMD"
			(at 0 -1.2 180)
			(layer "B.Fab")
			(effects
				(font
					(size 0.7 0.7)
					(thickness 0.15)
				)
				(justify left bottom mirror)
			)
		)
		(property "Description" "SMT test point"
			(at 0 0 180)
			(layer "B.Fab")
			(hide yes)
			(effects
				(font
					(size 1.27 1.27)
					(thickness 0.15)
				)
				(justify mirror)
			)
		)
		(property "MPN" ""
			(at 0 0 180)
			(unlocked yes)
			(layer "B.Fab")
			(hide yes)
			(effects
				(font
					(size 1 1)
					(thickness 0.15)
				)
				(justify mirror)
			)
		)
		(property "Manufacturer" ""
			(at 0 0 180)
			(unlocked yes)
			(layer "B.Fab")
			(hide yes)
			(effects
				(font
					(size 1 1)
					(thickness 0.15)
				)
				(justify mirror)
			)
		)
		(property "Author" "Antmicro"
			(at 0 0 180)
			(unlocked yes)
			(layer "B.Fab")
			(hide yes)
			(effects
				(font
					(size 1 1)
					(thickness 0.15)
				)
				(justify mirror)
			)
		)
		(property "License" "Apache-2.0"
			(at 0 0 180)
			(unlocked yes)
			(layer "B.Fab")
			(hide yes)
			(effects
				(font
					(size 1 1)
					(thickness 0.15)
				)
				(justify mirror)
			)
		)
		(sheetname "/USB Debug, PD/")
		(sheetfile "usb_debug_pd.kicad_sch")
		(attr exclude_from_pos_files exclude_from_bom)
		(fp_circle
			(center 0 0)
			(end 0.475 0)
			(stroke
				(width 0.05)
				(type default)
			)
			(fill no)
			(layer "B.CrtYd")
		)
		(fp_text user "Author: Antmicro"
			(at -0.4 -3.901 180)
			(layer "B.Fab")
			(effects
				(font
					(size 0.7 0.7)
					(thickness 0.15)
				)
				(justify left bottom mirror)
			)
		)
		(fp_text user "${REFERENCE}"
			(at -0.4 -2.7 180)
			(layer "B.Fab")
			(effects
				(font
					(size 0.7 0.7)
					(thickness 0.15)
				)
				(justify left bottom mirror)
			)
		)
		(fp_text user "License: Apache-2.0"
			(at -0.4 -5.101 180)
			(layer "B.Fab")
			(effects
				(font
					(size 0.7 0.7)
					(thickness 0.15)
				)
				(justify left bottom mirror)
			)
		)
		(pad "1" smd circle
			(at 0 0)
			(size 0.75 0.75)
			(layers "B.Cu" "B.Mask")
			(net 947 "/USB Debug, PD/PDC_I2C2_SCL")
			(pinfunction "1")
			(pintype "passive")
		)
	)
	(footprint "antmicro-footprints:C_0402_1005Metric"
		(layer "B.Cu")
		(at 110.25 100.501)
		(descr "Capacitor SMD 0402")
		(tags "capacitor SMD 0402")
		(property "Reference" "C183"
			(at -0.95 -0.301 0)
			(layer "B.SilkS")
			(effects
				(font
					(size 0.7 0.7)
					(thickness 0.15)
				)
				(justify left top mirror)
			)
		)
		(property "Value" "C_220n_0402"
			(at -1.022927 -2.155213 0)
			(layer "B.Fab")
			(effects
				(font
					(size 0.7 0.7)
					(thickness 0.15)
				)
				(justify right top mirror)
			)
		)
		(property "Datasheet" "https://www.yageo.com/en/Chart/Download/pdf/CC0402KRX5R6BB224"
			(at 0 0 0)
			(layer "B.Fab")
			(hide yes)
			(effects
				(font
					(size 1.27 1.27)
					(thickness 0.15)
				)
				(justify mirror)
			)
		)
		(property "Description" "SMD Multilayer Ceramic Capacitor, 0.22 µF, 10 V, 0402 [1005 Metric], ± 10%, X5R, CC Series"
			(at 0 0 0)
			(layer "B.Fab")
			(hide yes)
			(effects
				(font
					(size 1.27 1.27)
					(thickness 0.15)
				)
				(justify mirror)
			)
		)
		(property "MPN" "CC0402KRX5R6BB224"
			(at 0 0 0)
			(unlocked yes)
			(layer "B.Fab")
			(hide yes)
			(effects
				(font
					(size 1 1)
					(thickness 0.15)
				)
				(justify mirror)
			)
		)
		(property "Val" "220n"
			(at 0 0 0)
			(unlocked yes)
			(layer "B.Fab")
			(hide yes)
			(effects
				(font
					(size 1 1)
					(thickness 0.15)
				)
				(justify mirror)
			)
		)
		(property "Voltage" "25V"
			(at 0 0 0)
			(unlocked yes)
			(layer "B.Fab")
			(hide yes)
			(effects
				(font
					(size 1 1)
					(thickness 0.15)
				)
				(justify mirror)
			)
		)
		(property "Dielectric" "X7R"
			(at 0 0 0)
			(unlocked yes)
			(layer "B.Fab")
			(hide yes)
			(effects
				(font
					(size 1 1)
					(thickness 0.15)
				)
				(justify mirror)
			)
		)
		(property "Manufacturer" "YAGEO"
			(at 0 0 0)
			(unlocked yes)
			(layer "B.Fab")
			(hide yes)
			(effects
				(font
					(size 1 1)
					(thickness 0.15)
				)
				(justify mirror)
			)
		)
		(property "License" "Apache-2.0"
			(at 0 0 0)
			(unlocked yes)
			(layer "B.Fab")
			(hide yes)
			(effects
				(font
					(size 1 1)
					(thickness 0.15)
				)
				(justify mirror)
			)
		)
		(property "Author" "Antmicro"
			(at 0 0 0)
			(unlocked yes)
			(layer "B.Fab")
			(hide yes)
			(effects
				(font
					(size 1 1)
					(thickness 0.15)
				)
				(justify mirror)
			)
		)
		(property "Public" "False"
			(at 0 0 0)
			(unlocked yes)
			(layer "B.Fab")
			(hide yes)
			(effects
				(font
					(size 1 1)
					(thickness 0.15)
				)
				(justify mirror)
			)
		)
		(sheetname "/M.2/")
		(sheetfile "m2.kicad_sch")
		(attr smd)
		(fp_poly
			(pts
				(xy -0.925 0.47) (xy -0.925 -0.47) (xy 0.925 -0.47) (xy 0.925 0.47)
			)
			(stroke
				(width 0.05)
				(type default)
			)
			(fill no)
			(layer "B.CrtYd")
		)
		(fp_line
			(start -0.494 -0.248)
			(end -0.494 0.25)
			(stroke
				(width 0.15)
				(type solid)
			)
			(layer "B.Fab")
		)
		(fp_line
			(start -0.494 0.25)
			(end 0.504 0.25)
			(stroke
				(width 0.15)
				(type solid)
			)
			(layer "B.Fab")
		)
		(fp_line
			(start 0.504 -0.248)
			(end -0.494 -0.248)
			(stroke
				(width 0.15)
				(type solid)
			)
			(layer "B.Fab")
		)
		(fp_line
			(start 0.504 0.25)
			(end 0.504 -0.248)
			(stroke
				(width 0.15)
				(type solid)
			)
			(layer "B.Fab")
		)
		(fp_text user "Author: Antmicro"
			(at -0.939 -3.399 0)
			(layer "B.Fab")
			(effects
				(font
					(size 0.7 0.7)
					(thickness 0.15)
				)
				(justify right top mirror)
			)
		)
		(fp_text user "${REFERENCE}"
			(at -0.939 -4.599 0)
			(layer "B.Fab")
			(effects
				(font
					(size 0.7 0.7)
					(thickness 0.15)
				)
				(justify right top mirror)
			)
		)
		(fp_text user "License: Apache-2.0"
			(at -0.939 -5.799 0)
			(layer "B.Fab")
			(effects
				(font
					(size 0.7 0.7)
					(thickness 0.15)
				)
				(justify right top mirror)
			)
		)
		(pad "1" smd roundrect
			(at -0.48 0)
			(size 0.59 0.64)
			(layers "B.Cu" "B.Mask" "B.Paste")
			(roundrect_rratio 0.25)
			(net 400 "/M.2/PCIe_{C5x4}.TX2+")
			(pintype "passive")
		)
		(pad "2" smd roundrect
			(at 0.48 0)
			(size 0.59 0.64)
			(layers "B.Cu" "B.Mask" "B.Paste")
			(roundrect_rratio 0.25)
			(net 399 "/M.2/M2_M_PET2_P")
			(pintype "passive")
		)
	)
	(footprint "antmicro-footprints:C_0402_1005Metric"
		(layer "B.Cu")
		(at 96.68 105.51 90)
		(descr "Capacitor SMD 0402")
		(tags "capacitor SMD 0402")
		(property "Reference" "C332"
			(at -3.69 -0.28 90)
			(layer "B.SilkS")
			(effects
				(font
					(size 0.7 0.7)
					(thickness 0.15)
				)
				(justify right top mirror)
			)
		)
		(property "Value" "C_100n_0402"
			(at -1.022927 -2.155213 90)
			(layer "B.Fab")
			(effects
				(font
					(size 0.7 0.7)
					(thickness 0.15)
				)
				(justify right top mirror)
			)
		)
		(property "Datasheet" "https://www.murata.com/products/productdetail?partno=GRM155R61H104KE14%23"
			(at 0 0 90)
			(layer "B.Fab")
			(hide yes)
			(effects
				(font
					(size 1.27 1.27)
					(thickness 0.15)
				)
				(justify mirror)
			)
		)
		(property "Description" "SMD Multilayer Ceramic Capacitor, 0.1 µF, 50 V, 0402 [1005 Metric], ± 10%, X5R, GRM Series"
			(at 0 0 90)
			(layer "B.Fab")
			(hide yes)
			(effects
				(font
					(size 1.27 1.27)
					(thickness 0.15)
				)
				(justify mirror)
			)
		)
		(property "Manufacturer" "Murata"
			(at 0 0 270)
			(unlocked yes)
			(layer "B.Fab")
			(hide yes)
			(effects
				(font
					(size 1 1)
					(thickness 0.15)
				)
				(justify mirror)
			)
		)
		(property "MPN" "GRM155R61H104KE14D"
			(at 0 0 270)
			(unlocked yes)
			(layer "B.Fab")
			(hide yes)
			(effects
				(font
					(size 1 1)
					(thickness 0.15)
				)
				(justify mirror)
			)
		)
		(property "Val" "100n"
			(at 0 0 270)
			(unlocked yes)
			(layer "B.Fab")
			(hide yes)
			(effects
				(font
					(size 1 1)
					(thickness 0.15)
				)
				(justify mirror)
			)
		)
		(property "License" "Apache-2.0"
			(at 0 0 270)
			(unlocked yes)
			(layer "B.Fab")
			(hide yes)
			(effects
				(font
					(size 1 1)
					(thickness 0.15)
				)
				(justify mirror)
			)
		)
		(property "Author" "Antmicro"
			(at 0 0 270)
			(unlocked yes)
			(layer "B.Fab")
			(hide yes)
			(effects
				(font
					(size 1 1)
					(thickness 0.15)
				)
				(justify mirror)
			)
		)
		(property "Voltage" "50V"
			(at 0 0 270)
			(unlocked yes)
			(layer "B.Fab")
			(hide yes)
			(effects
				(font
					(size 1 1)
					(thickness 0.15)
				)
				(justify mirror)
			)
		)
		(property "Dielectric" "X5R"
			(at 0 0 270)
			(unlocked yes)
			(layer "B.Fab")
			(hide yes)
			(effects
				(font
					(size 1 1)
					(thickness 0.15)
				)
				(justify mirror)
			)
		)
		(sheetname "/SoM_IO2/")
		(sheetfile "som_io2.kicad_sch")
		(attr smd)
		(fp_poly
			(pts
				(xy -0.925 0.47) (xy 0.925 0.47) (xy 0.925 -0.47) (xy -0.925 -0.47)
			)
			(stroke
				(width 0.05)
				(type default)
			)
			(fill no)
			(layer "B.CrtYd")
		)
		(fp_line
			(start 0.504 -0.248)
			(end -0.494 -0.248)
			(stroke
				(width 0.15)
				(type solid)
			)
			(layer "B.Fab")
		)
		(fp_line
			(start -0.494 -0.248)
			(end -0.494 0.25)
			(stroke
				(width 0.15)
				(type solid)
			)
			(layer "B.Fab")
		)
		(fp_line
			(start 0.504 0.25)
			(end 0.504 -0.248)
			(stroke
				(width 0.15)
				(type solid)
			)
			(layer "B.Fab")
		)
		(fp_line
			(start -0.494 0.25)
			(end 0.504 0.25)
			(stroke
				(width 0.15)
				(type solid)
			)
			(layer "B.Fab")
		)
		(fp_text user "Author: Antmicro"
			(at -0.939 -3.399 90)
			(layer "B.Fab")
			(effects
				(font
					(size 0.7 0.7)
					(thickness 0.15)
				)
				(justify right top mirror)
			)
		)
		(fp_text user "${REFERENCE}"
			(at -0.939 -4.599 90)
			(layer "B.Fab")
			(effects
				(font
					(size 0.7 0.7)
					(thickness 0.15)
				)
				(justify right top mirror)
			)
		)
		(fp_text user "License: Apache-2.0"
			(at -0.939 -5.799 90)
			(layer "B.Fab")
			(effects
				(font
					(size 0.7 0.7)
					(thickness 0.15)
				)
				(justify right top mirror)
			)
		)
		(pad "1" smd roundrect
			(at -0.48 0 90)
			(size 0.59 0.64)
			(layers "B.Cu" "B.Mask" "B.Paste")
			(roundrect_rratio 0.25)
			(net 1252 "/SoM_IO2/DP1.AUX_C+")
			(pintype "passive")
		)
		(pad "2" smd roundrect
			(at 0.48 0 90)
			(size 0.59 0.64)
			(layers "B.Cu" "B.Mask" "B.Paste")
			(roundrect_rratio 0.25)
			(net 729 "/Expansion connector/DP1.AUX+")
			(pintype "passive")
		)
	)
	(footprint "antmicro-footprints:R_0402_1005Metric"
		(layer "B.Cu")
		(at 207 65.98)
		(descr "Resistor SMD 0402")
		(tags "resistor SMD 0402")
		(property "Reference" "R179"
			(at -3.909 -0.476 0)
			(layer "B.SilkS")
			(effects
				(font
					(size 0.7 0.7)
					(thickness 0.15)
				)
				(justify right top mirror)
			)
		)
		(property "Value" "R_4k7_0402"
			(at -1.011843 -1.772046 0)
			(layer "B.Fab")
			(effects
				(font
					(size 0.7 0.7)
					(thickness 0.15)
				)
				(justify right top mirror)
			)
		)
		(property "Datasheet" "https://www.bourns.com/docs/product-datasheets/cr.pdf"
			(at 0 0 0)
			(layer "B.Fab")
			(hide yes)
			(effects
				(font
					(size 1.27 1.27)
					(thickness 0.15)
				)
				(justify mirror)
			)
		)
		(property "Description" "SMD Chip Resistor, 4.7 kohm, ± 1%, 62.5 mW, 0402 [1005 Metric], Thick Film, General Purpose"
			(at 0 0 0)
			(layer "B.Fab")
			(hide yes)
			(effects
				(font
					(size 1.27 1.27)
					(thickness 0.15)
				)
				(justify mirror)
			)
		)
		(property "Manufacturer" "Bourns"
			(at 0 0 180)
			(unlocked yes)
			(layer "B.Fab")
			(hide yes)
			(effects
				(font
					(size 1 1)
					(thickness 0.15)
				)
				(justify mirror)
			)
		)
		(property "MPN" "CR0402-FX-4701GLF"
			(at 0 0 180)
			(unlocked yes)
			(layer "B.Fab")
			(hide yes)
			(effects
				(font
					(size 1 1)
					(thickness 0.15)
				)
				(justify mirror)
			)
		)
		(property "Val" "4k7"
			(at 0 0 180)
			(unlocked yes)
			(layer "B.Fab")
			(hide yes)
			(effects
				(font
					(size 1 1)
					(thickness 0.15)
				)
				(justify mirror)
			)
		)
		(property "License" "Apache-2.0"
			(at 0 0 180)
			(unlocked yes)
			(layer "B.Fab")
			(hide yes)
			(effects
				(font
					(size 1 1)
					(thickness 0.15)
				)
				(justify mirror)
			)
		)
		(property "Author" "Antmicro"
			(at 0 0 180)
			(unlocked yes)
			(layer "B.Fab")
			(hide yes)
			(effects
				(font
					(size 1 1)
					(thickness 0.15)
				)
				(justify mirror)
			)
		)
		(property "Tolerance" "1%"
			(at 0 0 180)
			(unlocked yes)
			(layer "B.Fab")
			(hide yes)
			(effects
				(font
					(size 1 1)
					(thickness 0.15)
				)
				(justify mirror)
			)
		)
		(sheetname "/CSI/")
		(sheetfile "csi.kicad_sch")
		(attr smd)
		(fp_poly
			(pts
				(xy -0.925 0.47) (xy -0.925 -0.47) (xy 0.925 -0.47) (xy 0.925 0.47)
			)
			(stroke
				(width 0.05)
				(type default)
			)
			(fill no)
			(layer "B.CrtYd")
		)
		(fp_poly
			(pts
				(xy -0.5 0.25) (xy -0.5 -0.25) (xy 0.5 -0.25) (xy 0.5 0.25)
			)
			(stroke
				(width 0.15)
				(type solid)
			)
			(fill no)
			(layer "B.Fab")
		)
		(fp_text user "${REFERENCE}"
			(at -0.95 -3.168 0)
			(layer "B.Fab")
			(effects
				(font
					(size 0.7 0.7)
					(thickness 0.15)
				)
				(justify right top mirror)
			)
		)
		(fp_text user "Author: Antmicro"
			(at -0.95 -4.169 0)
			(layer "B.Fab")
			(effects
				(font
					(size 0.7 0.7)
					(thickness 0.15)
				)
				(justify right top mirror)
			)
		)
		(fp_text user "License: Apache-2.0"
			(at -0.949999 -5.169 0)
			(layer "B.Fab")
			(effects
				(font
					(size 0.7 0.7)
					(thickness 0.15)
				)
				(justify right top mirror)
			)
		)
		(pad "1" smd roundrect
			(at -0.48 0)
			(size 0.59 0.64)
			(layers "B.Cu" "B.Mask" "B.Paste")
			(roundrect_rratio 0.25)
			(net 1 "GND")
			(pintype "passive")
		)
		(pad "2" smd roundrect
			(at 0.48 0)
			(size 0.59 0.64)
			(layers "B.Cu" "B.Mask" "B.Paste")
			(roundrect_rratio 0.25)
			(net 997 "/CSI/CSIB_5V_ISET")
			(pintype "passive")
		)
	)
	(footprint "antmicro-footprints:SOT-523"
		(layer "B.Cu")
		(at 220.532132 97.092 -90)
		(property "Reference" "Q34"
			(at 2.008 -1.067868 0)
			(layer "B.SilkS")
			(effects
				(font
					(size 0.7 0.7)
					(thickness 0.15)
				)
				(justify left bottom mirror)
			)
		)
		(property "Value" "DMG1012T-7"
			(at 0.1 -1.824 90)
			(layer "B.Fab")
			(effects
				(font
					(size 0.7 0.7)
					(thickness 0.15)
				)
				(justify left bottom mirror)
			)
		)
		(property "Datasheet" "https://www.diodes.com/assets/Datasheets/ds31783.pdf"
			(at 0 0 90)
			(layer "B.Fab")
			(hide yes)
			(effects
				(font
					(size 1.27 1.27)
					(thickness 0.15)
				)
				(justify mirror)
			)
		)
		(property "Description" "Power MOSFET, N Channel, 20 V, 630 mA, 0.3 ohm, SOT-523, Surface Mount"
			(at 0 0 90)
			(layer "B.Fab")
			(hide yes)
			(effects
				(font
					(size 1.27 1.27)
					(thickness 0.15)
				)
				(justify mirror)
			)
		)
		(property "MPN" "DMG1012T-7"
			(at 0 0 90)
			(unlocked yes)
			(layer "B.Fab")
			(hide yes)
			(effects
				(font
					(size 1 1)
					(thickness 0.15)
				)
				(justify mirror)
			)
		)
		(property "Manufacturer" "Diodes Incorporated"
			(at 0 0 90)
			(unlocked yes)
			(layer "B.Fab")
			(hide yes)
			(effects
				(font
					(size 1 1)
					(thickness 0.15)
				)
				(justify mirror)
			)
		)
		(property "Author" "Antmicro"
			(at 0 0 90)
			(unlocked yes)
			(layer "B.Fab")
			(hide yes)
			(effects
				(font
					(size 1 1)
					(thickness 0.15)
				)
				(justify mirror)
			)
		)
		(property "License" "Apache-2.0"
			(at 0 0 90)
			(unlocked yes)
			(layer "B.Fab")
			(hide yes)
			(effects
				(font
					(size 1 1)
					(thickness 0.15)
				)
				(justify mirror)
			)
		)
		(sheetname "/USB DP Alt mode/")
		(sheetfile "usb_dp.kicad_sch")
		(attr smd)
		(fp_line
			(start -0.725 0.551)
			(end -0.277 0.551)
			(stroke
				(width 0.15)
				(type solid)
			)
			(layer "B.SilkS")
		)
		(fp_line
			(start -0.277 0.551)
			(end -0.277 0.75)
			(stroke
				(width 0.15)
				(type solid)
			)
			(layer "B.SilkS")
		)
		(fp_line
			(start -0.927 0.351)
			(end -0.725 0.551)
			(stroke
				(width 0.15)
				(type solid)
			)
			(layer "B.SilkS")
		)
		(fp_line
			(start -0.927 0.051)
			(end -0.927 0.351)
			(stroke
				(width 0.15)
				(type solid)
			)
			(layer "B.SilkS")
		)
		(fp_circle
			(center -0.9652 -0.9652)
			(end -0.9152 -0.9652)
			(stroke
				(width 0.15)
				(type solid)
			)
			(fill yes)
			(layer "B.SilkS")
		)
		(fp_line
			(start -1.12 1.16)
			(end 1.1 1.16)
			(stroke
				(width 0.05)
				(type solid)
			)
			(layer "B.CrtYd")
		)
		(fp_line
			(start -1.12 1.16)
			(end -1.12 -1.15)
			(stroke
				(width 0.05)
				(type solid)
			)
			(layer "B.CrtYd")
		)
		(fp_line
			(start 1.1 1.16)
			(end 1.1 -1.15)
			(stroke
				(width 0.05)
				(type solid)
			)
			(layer "B.CrtYd")
		)
		(fp_line
			(start -1.12 -1.15)
			(end 1.1 -1.15)
			(stroke
				(width 0.05)
				(type solid)
			)
			(layer "B.CrtYd")
		)
		(fp_line
			(start -0.652 0.425)
			(end -0.802 0.276)
			(stroke
				(width 0.15)
				(type solid)
			)
			(layer "B.Fab")
		)
		(fp_line
			(start 0.8 0.425)
			(end -0.652 0.425)
			(stroke
				(width 0.15)
				(type solid)
			)
			(layer "B.Fab")
		)
		(fp_line
			(start 0.8 0.425)
			(end 0.8 -0.424)
			(stroke
				(width 0.15)
				(type solid)
			)
			(layer "B.Fab")
		)
		(fp_line
			(start -0.802 0.276)
			(end -0.802 -0.424)
			(stroke
				(width 0.15)
				(type solid)
			)
			(layer "B.Fab")
		)
		(fp_line
			(start 0.8 -0.424)
			(end -0.802 -0.424)
			(stroke
				(width 0.15)
				(type solid)
			)
			(layer "B.Fab")
		)
		(fp_circle
			(center -0.9652 -0.9652)
			(end -0.9144 -0.9652)
			(stroke
				(width 0.15)
				(type solid)
			)
			(fill no)
			(layer "B.Fab")
		)
		(fp_text user "${REFERENCE}"
			(at -1.12 -3.824 90)
			(layer "B.Fab")
			(effects
				(font
					(size 0.7 0.7)
					(thickness 0.15)
				)
				(justify left bottom mirror)
			)
		)
		(fp_text user "Author: Antmicro"
			(at -1.12 -6.224 90)
			(layer "B.Fab")
			(effects
				(font
					(size 0.7 0.7)
					(thickness 0.15)
				)
				(justify left bottom mirror)
			)
		)
		(fp_text user "License: Apache-2.0"
			(at -1.12 -5.024 90)
			(layer "B.Fab")
			(effects
				(font
					(size 0.7 0.7)
					(thickness 0.15)
				)
				(justify left bottom mirror)
			)
		)
		(pad "1" smd rect
			(at -0.5 -0.65 270)
			(size 0.4 0.51)
			(layers "B.Cu" "B.Mask" "B.Paste")
			(net 957 "/USB DP Alt mode/HPDIN")
			(pinfunction "G")
			(pintype "input")
		)
		(pad "2" smd rect
			(at 0.498 -0.65 270)
			(size 0.4 0.51)
			(layers "B.Cu" "B.Mask" "B.Paste")
			(net 1 "GND")
			(pinfunction "S")
			(pintype "passive")
		)
		(pad "3" smd rect
			(at 0 0.652 270)
			(size 0.4 0.51)
			(layers "B.Cu" "B.Mask" "B.Paste")
			(net 1300 "Net-(Q34-D)")
			(pinfunction "D")
			(pintype "passive")
		)
	)
	(footprint "antmicro-footprints:R_0402_1005Metric"
		(layer "B.Cu")
		(at 219.88 119.9)
		(descr "Resistor SMD 0402")
		(tags "resistor SMD 0402")
		(property "Reference" "R333"
			(at -1.66 -1.5 0)
			(layer "B.SilkS")
			(effects
				(font
					(size 0.7 0.7)
					(thickness 0.15)
				)
				(justify right top mirror)
			)
		)
		(property "Value" "R_10k_0402"
			(at -1.011843 -1.772047 0)
			(layer "B.Fab")
			(effects
				(font
					(size 0.7 0.7)
					(thickness 0.15)
				)
				(justify right top mirror)
			)
		)
		(property "Datasheet" "https://www.bourns.com/docs/product-datasheets/cr.pdf"
			(at 0 0 0)
			(layer "B.Fab")
			(hide yes)
			(effects
				(font
					(size 1.27 1.27)
					(thickness 0.15)
				)
				(justify mirror)
			)
		)
		(property "Description" "SMD Chip Resistor, 10 kohm, ± 1%, 62.5 mW, 0402 [1005 Metric], Thick Film, General Purpose"
			(at 0 0 0)
			(layer "B.Fab")
			(hide yes)
			(effects
				(font
					(size 1.27 1.27)
					(thickness 0.15)
				)
				(justify mirror)
			)
		)
		(property "MPN" "CR0402-FX-1002GLF"
			(at 0 0 180)
			(unlocked yes)
			(layer "B.Fab")
			(hide yes)
			(effects
				(font
					(size 1 1)
					(thickness 0.15)
				)
				(justify mirror)
			)
		)
		(property "Manufacturer" "Bourns"
			(at 0 0 180)
			(unlocked yes)
			(layer "B.Fab")
			(hide yes)
			(effects
				(font
					(size 1 1)
					(thickness 0.15)
				)
				(justify mirror)
			)
		)
		(property "License" "Apache-2.0"
			(at 0 0 180)
			(unlocked yes)
			(layer "B.Fab")
			(hide yes)
			(effects
				(font
					(size 1 1)
					(thickness 0.15)
				)
				(justify mirror)
			)
		)
		(property "Author" "Antmicro"
			(at 0 0 180)
			(unlocked yes)
			(layer "B.Fab")
			(hide yes)
			(effects
				(font
					(size 1 1)
					(thickness 0.15)
				)
				(justify mirror)
			)
		)
		(property "Val" "10k"
			(at 0 0 180)
			(unlocked yes)
			(layer "B.Fab")
			(hide yes)
			(effects
				(font
					(size 1 1)
					(thickness 0.15)
				)
				(justify mirror)
			)
		)
		(property "Tolerance" "1%"
			(at 0 0 180)
			(unlocked yes)
			(layer "B.Fab")
			(hide yes)
			(effects
				(font
					(size 1 1)
					(thickness 0.15)
				)
				(justify mirror)
			)
		)
		(sheetname "/USB Hub/")
		(sheetfile "usb_hub.kicad_sch")
		(attr smd)
		(fp_rect
			(start -0.925 0.47)
			(end 0.925 -0.47)
			(stroke
				(width 0.05)
				(type default)
			)
			(fill no)
			(layer "B.CrtYd")
		)
		(fp_rect
			(start -0.5 0.25)
			(end 0.5 -0.25)
			(stroke
				(width 0.15)
				(type solid)
			)
			(fill no)
			(layer "B.Fab")
		)
		(fp_text user "License: Apache-2.0"
			(at -0.95 -5.169 0)
			(layer "B.Fab")
			(effects
				(font
					(size 0.7 0.7)
					(thickness 0.15)
				)
				(justify right top mirror)
			)
		)
		(fp_text user "Author: Antmicro"
			(at -0.95 -4.169 0)
			(layer "B.Fab")
			(effects
				(font
					(size 0.7 0.7)
					(thickness 0.15)
				)
				(justify right top mirror)
			)
		)
		(fp_text user "${REFERENCE}"
			(at -0.95 -3.168 0)
			(layer "B.Fab")
			(effects
				(font
					(size 0.7 0.7)
					(thickness 0.15)
				)
				(justify right top mirror)
			)
		)
		(pad "1" smd roundrect
			(at -0.48 0)
			(size 0.59 0.64)
			(layers "B.Cu" "B.Mask" "B.Paste")
			(roundrect_rratio 0.25)
			(net 5 "+5V")
			(pintype "passive")
		)
		(pad "2" smd roundrect
			(at 0.48 0)
			(size 0.59 0.64)
			(layers "B.Cu" "B.Mask" "B.Paste")
			(roundrect_rratio 0.25)
			(net 1333 "Net-(Q29-D1)")
			(pintype "passive")
		)
	)
	(footprint "antmicro-footprints:SOT-523"
		(layer "B.Cu")
		(at 97.75 62.92 -90)
		(property "Reference" "Q7"
			(at -0.92 2.5 270)
			(layer "B.SilkS")
			(effects
				(font
					(size 0.7 0.7)
					(thickness 0.15)
				)
				(justify left bottom mirror)
			)
		)
		(property "Value" "DMG1012T-7"
			(at 0.1 -1.824 90)
			(layer "B.Fab")
			(effects
				(font
					(size 0.7 0.7)
					(thickness 0.15)
				)
				(justify left bottom mirror)
			)
		)
		(property "Datasheet" "https://www.diodes.com/assets/Datasheets/ds31783.pdf"
			(at 0 0 90)
			(layer "B.Fab")
			(hide yes)
			(effects
				(font
					(size 1.27 1.27)
					(thickness 0.15)
				)
				(justify mirror)
			)
		)
		(property "Description" "Power MOSFET, N Channel, 20 V, 630 mA, 0.3 ohm, SOT-523, Surface Mount"
			(at 0 0 90)
			(layer "B.Fab")
			(hide yes)
			(effects
				(font
					(size 1.27 1.27)
					(thickness 0.15)
				)
				(justify mirror)
			)
		)
		(property "MPN" "DMG1012T-7"
			(at 0 0 90)
			(unlocked yes)
			(layer "B.Fab")
			(hide yes)
			(effects
				(font
					(size 1 1)
					(thickness 0.15)
				)
				(justify mirror)
			)
		)
		(property "Manufacturer" "Diodes Incorporated"
			(at 0 0 90)
			(unlocked yes)
			(layer "B.Fab")
			(hide yes)
			(effects
				(font
					(size 1 1)
					(thickness 0.15)
				)
				(justify mirror)
			)
		)
		(property "Author" "Antmicro"
			(at 0 0 90)
			(unlocked yes)
			(layer "B.Fab")
			(hide yes)
			(effects
				(font
					(size 1 1)
					(thickness 0.15)
				)
				(justify mirror)
			)
		)
		(property "License" "Apache-2.0"
			(at 0 0 90)
			(unlocked yes)
			(layer "B.Fab")
			(hide yes)
			(effects
				(font
					(size 1 1)
					(thickness 0.15)
				)
				(justify mirror)
			)
		)
		(sheetname "/SoM_Power/")
		(sheetfile "som_power.kicad_sch")
		(attr smd)
		(fp_line
			(start -0.725 0.551)
			(end -0.277 0.551)
			(stroke
				(width 0.15)
				(type solid)
			)
			(layer "B.SilkS")
		)
		(fp_line
			(start -0.277 0.551)
			(end -0.277 0.75)
			(stroke
				(width 0.15)
				(type solid)
			)
			(layer "B.SilkS")
		)
		(fp_line
			(start -0.927 0.351)
			(end -0.725 0.551)
			(stroke
				(width 0.15)
				(type solid)
			)
			(layer "B.SilkS")
		)
		(fp_line
			(start -0.927 0.051)
			(end -0.927 0.351)
			(stroke
				(width 0.15)
				(type solid)
			)
			(layer "B.SilkS")
		)
		(fp_circle
			(center -0.9652 -0.9652)
			(end -0.9152 -0.9652)
			(stroke
				(width 0.15)
				(type solid)
			)
			(fill yes)
			(layer "B.SilkS")
		)
		(fp_line
			(start -1.12 1.16)
			(end 1.1 1.16)
			(stroke
				(width 0.05)
				(type solid)
			)
			(layer "B.CrtYd")
		)
		(fp_line
			(start -1.12 1.16)
			(end -1.12 -1.15)
			(stroke
				(width 0.05)
				(type solid)
			)
			(layer "B.CrtYd")
		)
		(fp_line
			(start 1.1 1.16)
			(end 1.1 -1.15)
			(stroke
				(width 0.05)
				(type solid)
			)
			(layer "B.CrtYd")
		)
		(fp_line
			(start -1.12 -1.15)
			(end 1.1 -1.15)
			(stroke
				(width 0.05)
				(type solid)
			)
			(layer "B.CrtYd")
		)
		(fp_line
			(start -0.652 0.425)
			(end -0.802 0.276)
			(stroke
				(width 0.15)
				(type solid)
			)
			(layer "B.Fab")
		)
		(fp_line
			(start 0.8 0.425)
			(end -0.652 0.425)
			(stroke
				(width 0.15)
				(type solid)
			)
			(layer "B.Fab")
		)
		(fp_line
			(start 0.8 0.425)
			(end 0.8 -0.424)
			(stroke
				(width 0.15)
				(type solid)
			)
			(layer "B.Fab")
		)
		(fp_line
			(start -0.802 0.276)
			(end -0.802 -0.424)
			(stroke
				(width 0.15)
				(type solid)
			)
			(layer "B.Fab")
		)
		(fp_line
			(start 0.8 -0.424)
			(end -0.802 -0.424)
			(stroke
				(width 0.15)
				(type solid)
			)
			(layer "B.Fab")
		)
		(fp_circle
			(center -0.9652 -0.9652)
			(end -0.9144 -0.9652)
			(stroke
				(width 0.15)
				(type solid)
			)
			(fill no)
			(layer "B.Fab")
		)
		(fp_text user "License: Apache-2.0"
			(at -1.12 -5.024 90)
			(layer "B.Fab")
			(effects
				(font
					(size 0.7 0.7)
					(thickness 0.15)
				)
				(justify left bottom mirror)
			)
		)
		(fp_text user "${REFERENCE}"
			(at -1.12 -3.824 90)
			(layer "B.Fab")
			(effects
				(font
					(size 0.7 0.7)
					(thickness 0.15)
				)
				(justify left bottom mirror)
			)
		)
		(fp_text user "Author: Antmicro"
			(at -1.12 -6.224 90)
			(layer "B.Fab")
			(effects
				(font
					(size 0.7 0.7)
					(thickness 0.15)
				)
				(justify left bottom mirror)
			)
		)
		(pad "1" smd rect
			(at -0.5 -0.65 270)
			(size 0.4 0.51)
			(layers "B.Cu" "B.Mask" "B.Paste")
			(net 1285 "/SoM_Power/VIN_PWR_ON")
			(pinfunction "G")
			(pintype "input")
		)
		(pad "2" smd rect
			(at 0.498 -0.65 270)
			(size 0.4 0.51)
			(layers "B.Cu" "B.Mask" "B.Paste")
			(net 1 "GND")
			(pinfunction "S")
			(pintype "passive")
		)
		(pad "3" smd rect
			(at 0 0.652 270)
			(size 0.4 0.51)
			(layers "B.Cu" "B.Mask" "B.Paste")
			(net 1298 "Net-(Q37-G)")
			(pinfunction "D")
			(pintype "passive")
		)
	)
	(footprint "antmicro-footprints:R_0402_1005Metric"
		(layer "B.Cu")
		(at 92.87 148.17)
		(descr "Resistor SMD 0402")
		(tags "resistor SMD 0402")
		(property "Reference" "R202"
			(at 0.85 -0.369264 0)
			(layer "B.SilkS")
			(effects
				(font
					(size 0.7 0.7)
					(thickness 0.15)
				)
				(justify right top mirror)
			)
		)
		(property "Value" "R_0R_0402"
			(at -1.011843 -1.772046 0)
			(layer "B.Fab")
			(effects
				(font
					(size 0.7 0.7)
					(thickness 0.15)
				)
				(justify right top mirror)
			)
		)
		(property "Datasheet" "https://industrial.panasonic.com/cdbs/www-data/pdf/RDA0000/AOA0000C301.pdf"
			(at 0 0 0)
			(layer "B.Fab")
			(hide yes)
			(effects
				(font
					(size 1.27 1.27)
					(thickness 0.15)
				)
				(justify mirror)
			)
		)
		(property "Description" "SMD Chip Resistor, Jumper, 0 ohm, 100 mW, 0402 [1005 Metric], Thick Film, General Purpose"
			(at 0 0 0)
			(layer "B.Fab")
			(hide yes)
			(effects
				(font
					(size 1.27 1.27)
					(thickness 0.15)
				)
				(justify mirror)
			)
		)
		(property "MPN" "ERJ2GE0R00X"
			(at 0 0 180)
			(unlocked yes)
			(layer "B.Fab")
			(hide yes)
			(effects
				(font
					(size 1 1)
					(thickness 0.15)
				)
				(justify mirror)
			)
		)
		(property "Manufacturer" "Panasonic"
			(at 0 0 180)
			(unlocked yes)
			(layer "B.Fab")
			(hide yes)
			(effects
				(font
					(size 1 1)
					(thickness 0.15)
				)
				(justify mirror)
			)
		)
		(property "License" "Apache-2.0"
			(at 0 0 180)
			(unlocked yes)
			(layer "B.Fab")
			(hide yes)
			(effects
				(font
					(size 1 1)
					(thickness 0.15)
				)
				(justify mirror)
			)
		)
		(property "Author" "Antmicro"
			(at 0 0 180)
			(unlocked yes)
			(layer "B.Fab")
			(hide yes)
			(effects
				(font
					(size 1 1)
					(thickness 0.15)
				)
				(justify mirror)
			)
		)
		(property "Val" "0R"
			(at 0 0 180)
			(unlocked yes)
			(layer "B.Fab")
			(hide yes)
			(effects
				(font
					(size 1 1)
					(thickness 0.15)
				)
				(justify mirror)
			)
		)
		(property "Tolerance" "~"
			(at 0 0 180)
			(unlocked yes)
			(layer "B.Fab")
			(hide yes)
			(effects
				(font
					(size 1 1)
					(thickness 0.15)
				)
				(justify mirror)
			)
		)
		(property "Current" "1A"
			(at 0 0 180)
			(unlocked yes)
			(layer "B.Fab")
			(hide yes)
			(effects
				(font
					(size 1 1)
					(thickness 0.15)
				)
				(justify mirror)
			)
		)
		(sheetname "/SoM_IO2/")
		(sheetfile "som_io2.kicad_sch")
		(attr smd)
		(fp_poly
			(pts
				(xy -0.925 0.47) (xy -0.925 -0.47) (xy 0.925 -0.47) (xy 0.925 0.47)
			)
			(stroke
				(width 0.05)
				(type default)
			)
			(fill no)
			(layer "B.CrtYd")
		)
		(fp_poly
			(pts
				(xy -0.5 0.25) (xy -0.5 -0.25) (xy 0.5 -0.25) (xy 0.5 0.25)
			)
			(stroke
				(width 0.15)
				(type solid)
			)
			(fill no)
			(layer "B.Fab")
		)
		(fp_text user "Author: Antmicro"
			(at -0.95 -4.169 0)
			(layer "B.Fab")
			(effects
				(font
					(size 0.7 0.7)
					(thickness 0.15)
				)
				(justify right top mirror)
			)
		)
		(fp_text user "License: Apache-2.0"
			(at -0.949999 -5.169 0)
			(layer "B.Fab")
			(effects
				(font
					(size 0.7 0.7)
					(thickness 0.15)
				)
				(justify right top mirror)
			)
		)
		(fp_text user "${REFERENCE}"
			(at -0.95 -3.168 0)
			(layer "B.Fab")
			(effects
				(font
					(size 0.7 0.7)
					(thickness 0.15)
				)
				(justify right top mirror)
			)
		)
		(pad "1" smd roundrect
			(at -0.48 0)
			(size 0.59 0.64)
			(layers "B.Cu" "B.Mask" "B.Paste")
			(roundrect_rratio 0.25)
			(net 851 "/Expansion connector/PCIe_{C2x1}.CLK-")
			(pintype "passive")
		)
		(pad "2" smd roundrect
			(at 0.48 0)
			(size 0.59 0.64)
			(layers "B.Cu" "B.Mask" "B.Paste")
			(roundrect_rratio 0.25)
			(net 668 "/SoM_IO2/PCIe_{C2x1}R_CLK-")
			(pintype "passive")
		)
	)
	(footprint "antmicro-footprints:C_0402_1005Metric"
		(layer "B.Cu")
		(at 94 120.8 180)
		(descr "Capacitor SMD 0402")
		(tags "capacitor SMD 0402")
		(property "Reference" "C213"
			(at -3.9 -0.725 0)
			(layer "B.SilkS")
			(effects
				(font
					(size 0.7 0.7)
					(thickness 0.15)
				)
				(justify left bottom mirror)
			)
		)
		(property "Value" "C_220n_0402"
			(at -1.022927 -2.155213 0)
			(layer "B.Fab")
			(effects
				(font
					(size 0.7 0.7)
					(thickness 0.15)
				)
				(justify left bottom mirror)
			)
		)
		(property "Datasheet" "https://www.yageo.com/en/Chart/Download/pdf/CC0402KRX5R6BB224"
			(at 0 0 0)
			(layer "B.Fab")
			(hide yes)
			(effects
				(font
					(size 1.27 1.27)
					(thickness 0.15)
				)
				(justify mirror)
			)
		)
		(property "Description" "SMD Multilayer Ceramic Capacitor, 0.22 µF, 10 V, 0402 [1005 Metric], ± 10%, X5R, CC Series"
			(at 0 0 0)
			(layer "B.Fab")
			(hide yes)
			(effects
				(font
					(size 1.27 1.27)
					(thickness 0.15)
				)
				(justify mirror)
			)
		)
		(property "MPN" "CC0402KRX5R6BB224"
			(at 0 0 180)
			(unlocked yes)
			(layer "B.Fab")
			(hide yes)
			(effects
				(font
					(size 1 1)
					(thickness 0.15)
				)
				(justify mirror)
			)
		)
		(property "Val" "220n"
			(at 0 0 180)
			(unlocked yes)
			(layer "B.Fab")
			(hide yes)
			(effects
				(font
					(size 1 1)
					(thickness 0.15)
				)
				(justify mirror)
			)
		)
		(property "Voltage" "25V"
			(at 0 0 180)
			(unlocked yes)
			(layer "B.Fab")
			(hide yes)
			(effects
				(font
					(size 1 1)
					(thickness 0.15)
				)
				(justify mirror)
			)
		)
		(property "Dielectric" "X7R"
			(at 0 0 180)
			(unlocked yes)
			(layer "B.Fab")
			(hide yes)
			(effects
				(font
					(size 1 1)
					(thickness 0.15)
				)
				(justify mirror)
			)
		)
		(property "Manufacturer" "YAGEO"
			(at 0 0 180)
			(unlocked yes)
			(layer "B.Fab")
			(hide yes)
			(effects
				(font
					(size 1 1)
					(thickness 0.15)
				)
				(justify mirror)
			)
		)
		(property "License" "Apache-2.0"
			(at 0 0 180)
			(unlocked yes)
			(layer "B.Fab")
			(hide yes)
			(effects
				(font
					(size 1 1)
					(thickness 0.15)
				)
				(justify mirror)
			)
		)
		(property "Author" "Antmicro"
			(at 0 0 180)
			(unlocked yes)
			(layer "B.Fab")
			(hide yes)
			(effects
				(font
					(size 1 1)
					(thickness 0.15)
				)
				(justify mirror)
			)
		)
		(property "Public" "False"
			(at 0 0 180)
			(unlocked yes)
			(layer "B.Fab")
			(hide yes)
			(effects
				(font
					(size 1 1)
					(thickness 0.15)
				)
				(justify mirror)
			)
		)
		(sheetname "/Expansion connector/")
		(sheetfile "expansion_connector.kicad_sch")
		(attr smd)
		(fp_rect
			(start -0.925 0.47)
			(end 0.925 -0.47)
			(stroke
				(width 0.05)
				(type default)
			)
			(fill no)
			(layer "B.CrtYd")
		)
		(fp_line
			(start 0.504 0.25)
			(end 0.504 -0.248)
			(stroke
				(width 0.15)
				(type solid)
			)
			(layer "B.Fab")
		)
		(fp_line
			(start 0.504 -0.248)
			(end -0.494 -0.248)
			(stroke
				(width 0.15)
				(type solid)
			)
			(layer "B.Fab")
		)
		(fp_line
			(start -0.494 0.25)
			(end 0.504 0.25)
			(stroke
				(width 0.15)
				(type solid)
			)
			(layer "B.Fab")
		)
		(fp_line
			(start -0.494 -0.248)
			(end -0.494 0.25)
			(stroke
				(width 0.15)
				(type solid)
			)
			(layer "B.Fab")
		)
		(fp_text user "Author: Antmicro"
			(at -0.939 -3.399 0)
			(layer "B.Fab")
			(effects
				(font
					(size 0.7 0.7)
					(thickness 0.15)
				)
				(justify left bottom mirror)
			)
		)
		(fp_text user "${REFERENCE}"
			(at -0.939 -4.599 0)
			(layer "B.Fab")
			(effects
				(font
					(size 0.7 0.7)
					(thickness 0.15)
				)
				(justify left bottom mirror)
			)
		)
		(fp_text user "License: Apache-2.0"
			(at -0.939 -5.799 0)
			(layer "B.Fab")
			(effects
				(font
					(size 0.7 0.7)
					(thickness 0.15)
				)
				(justify left bottom mirror)
			)
		)
		(pad "1" smd roundrect
			(at -0.48 0 180)
			(size 0.59 0.64)
			(layers "B.Cu" "B.Mask" "B.Paste")
			(roundrect_rratio 0.25)
			(net 478 "/Expansion connector/PCIe_{C2x1}.TX0+")
			(pintype "passive")
		)
		(pad "2" smd roundrect
			(at 0.48 0 180)
			(size 0.59 0.64)
			(layers "B.Cu" "B.Mask" "B.Paste")
			(roundrect_rratio 0.25)
			(net 476 "/Expansion connector/PET0_C2_P")
			(pintype "passive")
		)
	)
	(footprint "antmicro-footprints:R_0402_1005Metric"
		(layer "B.Cu")
		(at 202.626 144.012)
		(descr "Resistor SMD 0402")
		(tags "resistor SMD 0402")
		(property "Reference" "R187"
			(at -1.4 -1.412 0)
			(layer "B.SilkS")
			(effects
				(font
					(size 0.7 0.7)
					(thickness 0.15)
				)
				(justify right top mirror)
			)
		)
		(property "Value" "R_0R_0402"
			(at -1.011843 -1.772047 0)
			(layer "B.Fab")
			(effects
				(font
					(size 0.7 0.7)
					(thickness 0.15)
				)
				(justify right top mirror)
			)
		)
		(property "Datasheet" "https://industrial.panasonic.com/cdbs/www-data/pdf/RDA0000/AOA0000C301.pdf"
			(at 0 0 0)
			(layer "B.Fab")
			(hide yes)
			(effects
				(font
					(size 1.27 1.27)
					(thickness 0.15)
				)
				(justify mirror)
			)
		)
		(property "Description" "SMD Chip Resistor, Jumper, 0 ohm, 100 mW, 0402 [1005 Metric], Thick Film, General Purpose"
			(at 0 0 0)
			(layer "B.Fab")
			(hide yes)
			(effects
				(font
					(size 1.27 1.27)
					(thickness 0.15)
				)
				(justify mirror)
			)
		)
		(property "MPN" "ERJ2GE0R00X"
			(at 0 0 180)
			(unlocked yes)
			(layer "B.Fab")
			(hide yes)
			(effects
				(font
					(size 1 1)
					(thickness 0.15)
				)
				(justify mirror)
			)
		)
		(property "Manufacturer" "Panasonic"
			(at 0 0 180)
			(unlocked yes)
			(layer "B.Fab")
			(hide yes)
			(effects
				(font
					(size 1 1)
					(thickness 0.15)
				)
				(justify mirror)
			)
		)
		(property "License" "Apache-2.0"
			(at 0 0 180)
			(unlocked yes)
			(layer "B.Fab")
			(hide yes)
			(effects
				(font
					(size 1 1)
					(thickness 0.15)
				)
				(justify mirror)
			)
		)
		(property "Author" "Antmicro"
			(at 0 0 180)
			(unlocked yes)
			(layer "B.Fab")
			(hide yes)
			(effects
				(font
					(size 1 1)
					(thickness 0.15)
				)
				(justify mirror)
			)
		)
		(property "Val" "0R"
			(at 0 0 180)
			(unlocked yes)
			(layer "B.Fab")
			(hide yes)
			(effects
				(font
					(size 1 1)
					(thickness 0.15)
				)
				(justify mirror)
			)
		)
		(property "Tolerance" "~"
			(at 0 0 180)
			(unlocked yes)
			(layer "B.Fab")
			(hide yes)
			(effects
				(font
					(size 1 1)
					(thickness 0.15)
				)
				(justify mirror)
			)
		)
		(property "Current" "1A"
			(at 0 0 180)
			(unlocked yes)
			(layer "B.Fab")
			(hide yes)
			(effects
				(font
					(size 1 1)
					(thickness 0.15)
				)
				(justify mirror)
			)
		)
		(sheetname "/SFP/")
		(sheetfile "sfp.kicad_sch")
		(attr smd)
		(fp_rect
			(start -0.925 0.47)
			(end 0.925 -0.47)
			(stroke
				(width 0.05)
				(type default)
			)
			(fill no)
			(layer "B.CrtYd")
		)
		(fp_rect
			(start -0.5 0.25)
			(end 0.5 -0.25)
			(stroke
				(width 0.15)
				(type solid)
			)
			(fill no)
			(layer "B.Fab")
		)
		(fp_text user "Author: Antmicro"
			(at -0.95 -4.169 0)
			(layer "B.Fab")
			(effects
				(font
					(size 0.7 0.7)
					(thickness 0.15)
				)
				(justify right top mirror)
			)
		)
		(fp_text user "License: Apache-2.0"
			(at -0.95 -5.169 0)
			(layer "B.Fab")
			(effects
				(font
					(size 0.7 0.7)
					(thickness 0.15)
				)
				(justify right top mirror)
			)
		)
		(fp_text user "${REFERENCE}"
			(at -0.95 -3.168 0)
			(layer "B.Fab")
			(effects
				(font
					(size 0.7 0.7)
					(thickness 0.15)
				)
				(justify right top mirror)
			)
		)
		(pad "1" smd roundrect
			(at -0.48 0)
			(size 0.59 0.64)
			(layers "B.Cu" "B.Mask" "B.Paste")
			(roundrect_rratio 0.25)
			(net 57 "/SFP/MOD_ABS")
			(pintype "passive")
		)
		(pad "2" smd roundrect
			(at 0.48 0)
			(size 0.59 0.64)
			(layers "B.Cu" "B.Mask" "B.Paste")
			(roundrect_rratio 0.25)
			(net 1296 "/SFP/SFP_MOD_ABS")
			(pintype "passive")
		)
	)
	(footprint "antmicro-footprints:XSON-8_1x1.95mm_P0.5mm"
		(layer "B.Cu")
		(at 199.4 66.4 90)
		(property "Reference" "U49"
			(at -1.21 -2.14 90)
			(layer "B.SilkS")
			(effects
				(font
					(size 0.7 0.7)
					(thickness 0.15)
				)
				(justify right top mirror)
			)
		)
		(property "Value" "NTS0102_XSON"
			(at 0 -2.2 90)
			(layer "B.Fab")
			(effects
				(font
					(size 0.7 0.7)
					(thickness 0.15)
				)
				(justify right top mirror)
			)
		)
		(property "Datasheet" "http://www.farnell.com/datasheets/1760723.pdf"
			(at 0 0 90)
			(layer "B.Fab")
			(hide yes)
			(effects
				(font
					(size 1.27 1.27)
					(thickness 0.15)
				)
				(justify mirror)
			)
		)
		(property "Description" "Transceiver, 1.65 V to 3.6 V, XSON-8"
			(at 0 0 90)
			(layer "B.Fab")
			(hide yes)
			(effects
				(font
					(size 1.27 1.27)
					(thickness 0.15)
				)
				(justify mirror)
			)
		)
		(property "MPN" "NTS0102GT"
			(at 0 0 270)
			(unlocked yes)
			(layer "B.Fab")
			(hide yes)
			(effects
				(font
					(size 1 1)
					(thickness 0.15)
				)
				(justify mirror)
			)
		)
		(property "Manufacturer" "NXP"
			(at 0 0 270)
			(unlocked yes)
			(layer "B.Fab")
			(hide yes)
			(effects
				(font
					(size 1 1)
					(thickness 0.15)
				)
				(justify mirror)
			)
		)
		(property "Author" "Antmicro"
			(at 0 0 270)
			(unlocked yes)
			(layer "B.Fab")
			(hide yes)
			(effects
				(font
					(size 1 1)
					(thickness 0.15)
				)
				(justify mirror)
			)
		)
		(property "License" "Apache-2.0"
			(at 0 0 270)
			(unlocked yes)
			(layer "B.Fab")
			(hide yes)
			(effects
				(font
					(size 1 1)
					(thickness 0.15)
				)
				(justify mirror)
			)
		)
		(sheetname "/CSI/")
		(sheetfile "csi.kicad_sch")
		(attr smd)
		(fp_line
			(start 0.5 -1.1)
			(end -0.5 -1.1)
			(stroke
				(width 0.15)
				(type solid)
			)
			(layer "B.SilkS")
		)
		(fp_line
			(start -0.5 1.1)
			(end 0.5 1.1)
			(stroke
				(width 0.15)
				(type solid)
			)
			(layer "B.SilkS")
		)
		(fp_circle
			(center -0.750001 1.1)
			(end -0.700999 1.1)
			(stroke
				(width 0.15)
				(type solid)
			)
			(fill no)
			(layer "B.SilkS")
		)
		(fp_poly
			(pts
				(xy -0.8 1.200001) (xy 0.8 1.200001) (xy 0.8 -1.200001) (xy -0.8 -1.200001)
			)
			(stroke
				(width 0.05)
				(type solid)
			)
			(fill no)
			(layer "B.CrtYd")
		)
		(fp_line
			(start 0.5305 -1)
			(end -0.5305 -1)
			(stroke
				(width 0.15)
				(type solid)
			)
			(layer "B.Fab")
		)
		(fp_line
			(start -0.5305 -1)
			(end -0.5305 1.001)
			(stroke
				(width 0.15)
				(type solid)
			)
			(layer "B.Fab")
		)
		(fp_line
			(start 0.5305 1.001)
			(end 0.5305 -1)
			(stroke
				(width 0.15)
				(type solid)
			)
			(layer "B.Fab")
		)
		(fp_line
			(start -0.5305 1.001)
			(end 0.5305 1.001)
			(stroke
				(width 0.15)
				(type solid)
			)
			(layer "B.Fab")
		)
		(fp_text user "Author: Antmicro"
			(at -0.527 -7.105 90)
			(layer "B.Fab")
			(effects
				(font
					(size 0.7 0.7)
					(thickness 0.15)
				)
				(justify right top mirror)
			)
		)
		(fp_text user "License: Apache-2.0"
			(at -0.527 -8.306 90)
			(layer "B.Fab")
			(effects
				(font
					(size 0.7 0.7)
					(thickness 0.15)
				)
				(justify right top mirror)
			)
		)
		(fp_text user "${REFERENCE}"
			(at -0.527 -5.905 90)
			(layer "B.Fab")
			(effects
				(font
					(size 0.7 0.7)
					(thickness 0.15)
				)
				(justify right top mirror)
			)
		)
		(pad "1" smd roundrect
			(at -0.45 0.75 270)
			(size 0.6 0.3)
			(layers "B.Cu" "B.Mask" "B.Paste")
			(roundrect_rratio 0.25)
			(net 210 "/CSI/VSYNC_CAM3_3V3")
			(pinfunction "B_{2}")
			(pintype "bidirectional")
		)
		(pad "2" smd roundrect
			(at -0.45 0.25 270)
			(size 0.6 0.25)
			(layers "B.Cu" "B.Mask" "B.Paste")
			(roundrect_rratio 0.25)
			(net 1 "GND")
			(pinfunction "GND")
			(pintype "power_in")
		)
		(pad "3" smd roundrect
			(at -0.45 -0.25 270)
			(size 0.6 0.25)
			(layers "B.Cu" "B.Mask" "B.Paste")
			(roundrect_rratio 0.25)
			(net 11 "+1V8")
			(pinfunction "VCC_{A}")
			(pintype "power_in")
		)
		(pad "4" smd roundrect
			(at -0.45 -0.75 270)
			(size 0.6 0.3)
			(layers "B.Cu" "B.Mask" "B.Paste")
			(roundrect_rratio 0.25)
			(net 47 "/CSI/CAM_CTRL.VSYNC_CAM3")
			(pinfunction "A_{2}")
			(pintype "bidirectional")
		)
		(pad "5" smd roundrect
			(at 0.45 -0.75 270)
			(size 0.6 0.3)
			(layers "B.Cu" "B.Mask" "B.Paste")
			(roundrect_rratio 0.25)
			(net 67 "/CSI/CAM_CTRL.VSYNC_CAM2")
			(pinfunction "A_{1}")
			(pintype "bidirectional")
		)
		(pad "6" smd roundrect
			(at 0.45 -0.25 270)
			(size 0.6 0.25)
			(layers "B.Cu" "B.Mask" "B.Paste")
			(roundrect_rratio 0.25)
			(net 11 "+1V8")
			(pinfunction "OE")
			(pintype "input")
		)
		(pad "7" smd roundrect
			(at 0.45 0.25 270)
			(size 0.6 0.25)
			(layers "B.Cu" "B.Mask" "B.Paste")
			(roundrect_rratio 0.25)
			(net 2 "+3V3")
			(pinfunction "VCC_{B}")
			(pintype "power_in")
		)
		(pad "8" smd roundrect
			(at 0.45 0.75 270)
			(size 0.6 0.3)
			(layers "B.Cu" "B.Mask" "B.Paste")
			(roundrect_rratio 0.25)
			(net 201 "/CSI/VSYNC_CAM2_3V3")
			(pinfunction "B_{1}")
			(pintype "bidirectional")
		)
	)
	(footprint "antmicro-footprints:R_0402_1005Metric"
		(layer "B.Cu")
		(at 175.568 62.37 90)
		(descr "Resistor SMD 0402")
		(tags "resistor SMD 0402")
		(property "Reference" "R233"
			(at -2.167516 0.699303 90)
			(layer "B.SilkS")
			(effects
				(font
					(size 0.7 0.7)
					(thickness 0.15)
				)
				(justify right top mirror)
			)
		)
		(property "Value" "R_100k_0402"
			(at -1.011843 -1.772047 90)
			(layer "B.Fab")
			(effects
				(font
					(size 0.7 0.7)
					(thickness 0.15)
				)
				(justify right top mirror)
			)
		)
		(property "Datasheet" "https://www.bourns.com/docs/product-datasheets/cr.pdf"
			(at 0 0 90)
			(layer "B.Fab")
			(hide yes)
			(effects
				(font
					(size 1.27 1.27)
					(thickness 0.15)
				)
				(justify mirror)
			)
		)
		(property "Description" "SMD Chip Resistor, 100 kohm, ± 1%, 62.5 mW, 0402 [1005 Metric], Thick Film, General Purpose"
			(at 0 0 90)
			(layer "B.Fab")
			(hide yes)
			(effects
				(font
					(size 1.27 1.27)
					(thickness 0.15)
				)
				(justify mirror)
			)
		)
		(property "Manufacturer" "Bourns"
			(at 0 0 270)
			(unlocked yes)
			(layer "B.Fab")
			(hide yes)
			(effects
				(font
					(size 1 1)
					(thickness 0.15)
				)
				(justify mirror)
			)
		)
		(property "MPN" "CR0402-FX-1003GLF"
			(at 0 0 270)
			(unlocked yes)
			(layer "B.Fab")
			(hide yes)
			(effects
				(font
					(size 1 1)
					(thickness 0.15)
				)
				(justify mirror)
			)
		)
		(property "Val" "100k"
			(at 0 0 270)
			(unlocked yes)
			(layer "B.Fab")
			(hide yes)
			(effects
				(font
					(size 1 1)
					(thickness 0.15)
				)
				(justify mirror)
			)
		)
		(property "License" "Apache-2.0"
			(at 0 0 270)
			(unlocked yes)
			(layer "B.Fab")
			(hide yes)
			(effects
				(font
					(size 1 1)
					(thickness 0.15)
				)
				(justify mirror)
			)
		)
		(property "Author" "Antmicro"
			(at 0 0 270)
			(unlocked yes)
			(layer "B.Fab")
			(hide yes)
			(effects
				(font
					(size 1 1)
					(thickness 0.15)
				)
				(justify mirror)
			)
		)
		(property "Tolerance" "1%"
			(at 0 0 270)
			(unlocked yes)
			(layer "B.Fab")
			(hide yes)
			(effects
				(font
					(size 1 1)
					(thickness 0.15)
				)
				(justify mirror)
			)
		)
		(sheetname "/Peripherals/")
		(sheetfile "peripherals.kicad_sch")
		(attr smd)
		(fp_rect
			(start -0.925 0.47)
			(end 0.925 -0.47)
			(stroke
				(width 0.05)
				(type default)
			)
			(fill no)
			(layer "B.CrtYd")
		)
		(fp_rect
			(start -0.5 0.25)
			(end 0.5 -0.25)
			(stroke
				(width 0.15)
				(type solid)
			)
			(fill no)
			(layer "B.Fab")
		)
		(fp_text user "Author: Antmicro"
			(at -0.95 -4.169 90)
			(layer "B.Fab")
			(effects
				(font
					(size 0.7 0.7)
					(thickness 0.15)
				)
				(justify right top mirror)
			)
		)
		(fp_text user "${REFERENCE}"
			(at -0.95 -3.168 90)
			(layer "B.Fab")
			(effects
				(font
					(size 0.7 0.7)
					(thickness 0.15)
				)
				(justify right top mirror)
			)
		)
		(fp_text user "License: Apache-2.0"
			(at -0.95 -5.169 90)
			(layer "B.Fab")
			(effects
				(font
					(size 0.7 0.7)
					(thickness 0.15)
				)
				(justify right top mirror)
			)
		)
		(pad "1" smd roundrect
			(at -0.48 0 90)
			(size 0.59 0.64)
			(layers "B.Cu" "B.Mask" "B.Paste")
			(roundrect_rratio 0.25)
			(net 1 "GND")
			(pintype "passive")
		)
		(pad "2" smd roundrect
			(at 0.48 0 90)
			(size 0.59 0.64)
			(layers "B.Cu" "B.Mask" "B.Paste")
			(roundrect_rratio 0.25)
			(net 371 "/Expansion connector/GPIO.USER_LED1")
			(pintype "passive")
		)
	)
	(footprint "antmicro-footprints:C_0402_1005Metric"
		(layer "B.Cu")
		(at 89.8 105.5 -90)
		(descr "Capacitor SMD 0402")
		(tags "capacitor SMD 0402")
		(property "Reference" "C329"
			(at 1 -0.5 90)
			(layer "B.SilkS")
			(effects
				(font
					(size 0.7 0.7)
					(thickness 0.15)
				)
				(justify left bottom mirror)
			)
		)
		(property "Value" "C_100n_0402"
			(at -1.022927 -2.155213 90)
			(layer "B.Fab")
			(effects
				(font
					(size 0.7 0.7)
					(thickness 0.15)
				)
				(justify left bottom mirror)
			)
		)
		(property "Datasheet" "https://www.murata.com/products/productdetail?partno=GRM155R61H104KE14%23"
			(at 0 0 90)
			(layer "B.Fab")
			(hide yes)
			(effects
				(font
					(size 1.27 1.27)
					(thickness 0.15)
				)
				(justify mirror)
			)
		)
		(property "Description" "SMD Multilayer Ceramic Capacitor, 0.1 µF, 50 V, 0402 [1005 Metric], ± 10%, X5R, GRM Series"
			(at 0 0 90)
			(layer "B.Fab")
			(hide yes)
			(effects
				(font
					(size 1.27 1.27)
					(thickness 0.15)
				)
				(justify mirror)
			)
		)
		(property "Manufacturer" "Murata"
			(at 0 0 90)
			(unlocked yes)
			(layer "B.Fab")
			(hide yes)
			(effects
				(font
					(size 1 1)
					(thickness 0.15)
				)
				(justify mirror)
			)
		)
		(property "MPN" "GRM155R61H104KE14D"
			(at 0 0 90)
			(unlocked yes)
			(layer "B.Fab")
			(hide yes)
			(effects
				(font
					(size 1 1)
					(thickness 0.15)
				)
				(justify mirror)
			)
		)
		(property "Val" "100n"
			(at 0 0 90)
			(unlocked yes)
			(layer "B.Fab")
			(hide yes)
			(effects
				(font
					(size 1 1)
					(thickness 0.15)
				)
				(justify mirror)
			)
		)
		(property "License" "Apache-2.0"
			(at 0 0 90)
			(unlocked yes)
			(layer "B.Fab")
			(hide yes)
			(effects
				(font
					(size 1 1)
					(thickness 0.15)
				)
				(justify mirror)
			)
		)
		(property "Author" "Antmicro"
			(at 0 0 90)
			(unlocked yes)
			(layer "B.Fab")
			(hide yes)
			(effects
				(font
					(size 1 1)
					(thickness 0.15)
				)
				(justify mirror)
			)
		)
		(property "Voltage" "50V"
			(at 0 0 90)
			(unlocked yes)
			(layer "B.Fab")
			(hide yes)
			(effects
				(font
					(size 1 1)
					(thickness 0.15)
				)
				(justify mirror)
			)
		)
		(property "Dielectric" "X5R"
			(at 0 0 90)
			(unlocked yes)
			(layer "B.Fab")
			(hide yes)
			(effects
				(font
					(size 1 1)
					(thickness 0.15)
				)
				(justify mirror)
			)
		)
		(sheetname "/SoM_IO2/")
		(sheetfile "som_io2.kicad_sch")
		(attr smd)
		(fp_poly
			(pts
				(xy -0.925 0.47) (xy 0.925 0.47) (xy 0.925 -0.47) (xy -0.925 -0.47)
			)
			(stroke
				(width 0.05)
				(type default)
			)
			(fill no)
			(layer "B.CrtYd")
		)
		(fp_line
			(start -0.494 0.25)
			(end 0.504 0.25)
			(stroke
				(width 0.15)
				(type solid)
			)
			(layer "B.Fab")
		)
		(fp_line
			(start 0.504 0.25)
			(end 0.504 -0.248)
			(stroke
				(width 0.15)
				(type solid)
			)
			(layer "B.Fab")
		)
		(fp_line
			(start -0.494 -0.248)
			(end -0.494 0.25)
			(stroke
				(width 0.15)
				(type solid)
			)
			(layer "B.Fab")
		)
		(fp_line
			(start 0.504 -0.248)
			(end -0.494 -0.248)
			(stroke
				(width 0.15)
				(type solid)
			)
			(layer "B.Fab")
		)
		(fp_text user "Author: Antmicro"
			(at -0.939 -3.399 90)
			(layer "B.Fab")
			(effects
				(font
					(size 0.7 0.7)
					(thickness 0.15)
				)
				(justify left bottom mirror)
			)
		)
		(fp_text user "License: Apache-2.0"
			(at -0.939 -5.799 90)
			(layer "B.Fab")
			(effects
				(font
					(size 0.7 0.7)
					(thickness 0.15)
				)
				(justify left bottom mirror)
			)
		)
		(fp_text user "${REFERENCE}"
			(at -0.939 -4.599 90)
			(layer "B.Fab")
			(effects
				(font
					(size 0.7 0.7)
					(thickness 0.15)
				)
				(justify left bottom mirror)
			)
		)
		(pad "1" smd roundrect
			(at -0.48 0 270)
			(size 0.59 0.64)
			(layers "B.Cu" "B.Mask" "B.Paste")
			(roundrect_rratio 0.25)
			(net 713 "/Expansion connector/DP1.TX1-")
			(pintype "passive")
		)
		(pad "2" smd roundrect
			(at 0.48 0 270)
			(size 0.59 0.64)
			(layers "B.Cu" "B.Mask" "B.Paste")
			(roundrect_rratio 0.25)
			(net 1249 "/SoM_IO2/DP1.TX1_C-")
			(pintype "passive")
		)
	)
	(footprint "antmicro-footprints:R_0402_1005Metric"
		(layer "B.Cu")
		(at 196.6 70.6 -90)
		(descr "Resistor SMD 0402")
		(tags "resistor SMD 0402")
		(property "Reference" "R112"
			(at -1.5 1.5 90)
			(layer "B.SilkS")
			(effects
				(font
					(size 0.7 0.7)
					(thickness 0.15)
				)
				(justify left bottom mirror)
			)
		)
		(property "Value" "R_0R_0402"
			(at -1.011843 -1.772046 90)
			(layer "B.Fab")
			(effects
				(font
					(size 0.7 0.7)
					(thickness 0.15)
				)
				(justify left bottom mirror)
			)
		)
		(property "Datasheet" "https://industrial.panasonic.com/cdbs/www-data/pdf/RDA0000/AOA0000C301.pdf"
			(at 0 0 90)
			(layer "B.Fab")
			(hide yes)
			(effects
				(font
					(size 1.27 1.27)
					(thickness 0.15)
				)
				(justify mirror)
			)
		)
		(property "Description" "SMD Chip Resistor, Jumper, 0 ohm, 100 mW, 0402 [1005 Metric], Thick Film, General Purpose"
			(at 0 0 90)
			(layer "B.Fab")
			(hide yes)
			(effects
				(font
					(size 1.27 1.27)
					(thickness 0.15)
				)
				(justify mirror)
			)
		)
		(property "Manufacturer" "Panasonic"
			(at 0 0 90)
			(unlocked yes)
			(layer "B.Fab")
			(hide yes)
			(effects
				(font
					(size 1 1)
					(thickness 0.15)
				)
				(justify mirror)
			)
		)
		(property "MPN" "ERJ2GE0R00X"
			(at 0 0 90)
			(unlocked yes)
			(layer "B.Fab")
			(hide yes)
			(effects
				(font
					(size 1 1)
					(thickness 0.15)
				)
				(justify mirror)
			)
		)
		(property "Val" "0R"
			(at 0 0 90)
			(unlocked yes)
			(layer "B.Fab")
			(hide yes)
			(effects
				(font
					(size 1 1)
					(thickness 0.15)
				)
				(justify mirror)
			)
		)
		(property "License" "Apache-2.0"
			(at 0 0 90)
			(unlocked yes)
			(layer "B.Fab")
			(hide yes)
			(effects
				(font
					(size 1 1)
					(thickness 0.15)
				)
				(justify mirror)
			)
		)
		(property "Author" "Antmicro"
			(at 0 0 90)
			(unlocked yes)
			(layer "B.Fab")
			(hide yes)
			(effects
				(font
					(size 1 1)
					(thickness 0.15)
				)
				(justify mirror)
			)
		)
		(property "Tolerance" "~"
			(at 0 0 90)
			(unlocked yes)
			(layer "B.Fab")
			(hide yes)
			(effects
				(font
					(size 1 1)
					(thickness 0.15)
				)
				(justify mirror)
			)
		)
		(property "Current" "1A"
			(at 0 0 90)
			(unlocked yes)
			(layer "B.Fab")
			(hide yes)
			(effects
				(font
					(size 1 1)
					(thickness 0.15)
				)
				(justify mirror)
			)
		)
		(sheetname "/USB Debug, PD/")
		(sheetfile "usb_debug_pd.kicad_sch")
		(attr smd)
		(fp_poly
			(pts
				(xy -0.925 0.47) (xy 0.925 0.47) (xy 0.925 -0.47) (xy -0.925 -0.47)
			)
			(stroke
				(width 0.05)
				(type default)
			)
			(fill no)
			(layer "B.CrtYd")
		)
		(fp_poly
			(pts
				(xy -0.5 0.25) (xy 0.5 0.25) (xy 0.5 -0.25) (xy -0.5 -0.25)
			)
			(stroke
				(width 0.15)
				(type solid)
			)
			(fill no)
			(layer "B.Fab")
		)
		(fp_text user "License: Apache-2.0"
			(at -0.949999 -5.169 90)
			(layer "B.Fab")
			(effects
				(font
					(size 0.7 0.7)
					(thickness 0.15)
				)
				(justify left bottom mirror)
			)
		)
		(fp_text user "${REFERENCE}"
			(at -0.95 -3.168 90)
			(layer "B.Fab")
			(effects
				(font
					(size 0.7 0.7)
					(thickness 0.15)
				)
				(justify left bottom mirror)
			)
		)
		(fp_text user "Author: Antmicro"
			(at -0.95 -4.169 90)
			(layer "B.Fab")
			(effects
				(font
					(size 0.7 0.7)
					(thickness 0.15)
				)
				(justify left bottom mirror)
			)
		)
		(pad "1" smd roundrect
			(at -0.48 0 270)
			(size 0.59 0.64)
			(layers "B.Cu" "B.Mask" "B.Paste")
			(roundrect_rratio 0.25)
			(net 850 "/I2C_{SYS}.SDA")
			(pintype "passive")
		)
		(pad "2" smd roundrect
			(at 0.48 0 270)
			(size 0.59 0.64)
			(layers "B.Cu" "B.Mask" "B.Paste")
			(roundrect_rratio 0.25)
			(net 946 "/USB Debug, PD/DEBUG_SDA")
			(pintype "passive")
		)
	)
	(footprint "antmicro-footprints:C_0402_1005Metric"
		(layer "B.Cu")
		(at 110.25 97.5)
		(descr "Capacitor SMD 0402")
		(tags "capacitor SMD 0402")
		(property "Reference" "C188"
			(at -0.95 -0.4 0)
			(layer "B.SilkS")
			(effects
				(font
					(size 0.7 0.7)
					(thickness 0.15)
				)
				(justify left top mirror)
			)
		)
		(property "Value" "C_220n_0402"
			(at -1.022927 -2.155213 0)
			(layer "B.Fab")
			(effects
				(font
					(size 0.7 0.7)
					(thickness 0.15)
				)
				(justify right top mirror)
			)
		)
		(property "Datasheet" "https://www.yageo.com/en/Chart/Download/pdf/CC0402KRX5R6BB224"
			(at 0 0 0)
			(layer "B.Fab")
			(hide yes)
			(effects
				(font
					(size 1.27 1.27)
					(thickness 0.15)
				)
				(justify mirror)
			)
		)
		(property "Description" "SMD Multilayer Ceramic Capacitor, 0.22 µF, 10 V, 0402 [1005 Metric], ± 10%, X5R, CC Series"
			(at 0 0 0)
			(layer "B.Fab")
			(hide yes)
			(effects
				(font
					(size 1.27 1.27)
					(thickness 0.15)
				)
				(justify mirror)
			)
		)
		(property "MPN" "CC0402KRX5R6BB224"
			(at 0 0 0)
			(unlocked yes)
			(layer "B.Fab")
			(hide yes)
			(effects
				(font
					(size 1 1)
					(thickness 0.15)
				)
				(justify mirror)
			)
		)
		(property "Val" "220n"
			(at 0 0 0)
			(unlocked yes)
			(layer "B.Fab")
			(hide yes)
			(effects
				(font
					(size 1 1)
					(thickness 0.15)
				)
				(justify mirror)
			)
		)
		(property "Voltage" "25V"
			(at 0 0 0)
			(unlocked yes)
			(layer "B.Fab")
			(hide yes)
			(effects
				(font
					(size 1 1)
					(thickness 0.15)
				)
				(justify mirror)
			)
		)
		(property "Dielectric" "X7R"
			(at 0 0 0)
			(unlocked yes)
			(layer "B.Fab")
			(hide yes)
			(effects
				(font
					(size 1 1)
					(thickness 0.15)
				)
				(justify mirror)
			)
		)
		(property "Manufacturer" "YAGEO"
			(at 0 0 0)
			(unlocked yes)
			(layer "B.Fab")
			(hide yes)
			(effects
				(font
					(size 1 1)
					(thickness 0.15)
				)
				(justify mirror)
			)
		)
		(property "License" "Apache-2.0"
			(at 0 0 0)
			(unlocked yes)
			(layer "B.Fab")
			(hide yes)
			(effects
				(font
					(size 1 1)
					(thickness 0.15)
				)
				(justify mirror)
			)
		)
		(property "Author" "Antmicro"
			(at 0 0 0)
			(unlocked yes)
			(layer "B.Fab")
			(hide yes)
			(effects
				(font
					(size 1 1)
					(thickness 0.15)
				)
				(justify mirror)
			)
		)
		(property "Public" "False"
			(at 0 0 0)
			(unlocked yes)
			(layer "B.Fab")
			(hide yes)
			(effects
				(font
					(size 1 1)
					(thickness 0.15)
				)
				(justify mirror)
			)
		)
		(sheetname "/M.2/")
		(sheetfile "m2.kicad_sch")
		(attr smd)
		(fp_poly
			(pts
				(xy -0.925 0.47) (xy -0.925 -0.47) (xy 0.925 -0.47) (xy 0.925 0.47)
			)
			(stroke
				(width 0.05)
				(type default)
			)
			(fill no)
			(layer "B.CrtYd")
		)
		(fp_line
			(start -0.494 -0.248)
			(end -0.494 0.25)
			(stroke
				(width 0.15)
				(type solid)
			)
			(layer "B.Fab")
		)
		(fp_line
			(start -0.494 0.25)
			(end 0.504 0.25)
			(stroke
				(width 0.15)
				(type solid)
			)
			(layer "B.Fab")
		)
		(fp_line
			(start 0.504 -0.248)
			(end -0.494 -0.248)
			(stroke
				(width 0.15)
				(type solid)
			)
			(layer "B.Fab")
		)
		(fp_line
			(start 0.504 0.25)
			(end 0.504 -0.248)
			(stroke
				(width 0.15)
				(type solid)
			)
			(layer "B.Fab")
		)
		(fp_text user "License: Apache-2.0"
			(at -0.939 -5.799 0)
			(layer "B.Fab")
			(effects
				(font
					(size 0.7 0.7)
					(thickness 0.15)
				)
				(justify right top mirror)
			)
		)
		(fp_text user "Author: Antmicro"
			(at -0.939 -3.399 0)
			(layer "B.Fab")
			(effects
				(font
					(size 0.7 0.7)
					(thickness 0.15)
				)
				(justify right top mirror)
			)
		)
		(fp_text user "${REFERENCE}"
			(at -0.939 -4.599 0)
			(layer "B.Fab")
			(effects
				(font
					(size 0.7 0.7)
					(thickness 0.15)
				)
				(justify right top mirror)
			)
		)
		(pad "1" smd roundrect
			(at -0.48 0)
			(size 0.59 0.64)
			(layers "B.Cu" "B.Mask" "B.Paste")
			(roundrect_rratio 0.25)
			(net 439 "/M.2/PCIe_{C5x4}.TX3-")
			(pintype "passive")
		)
		(pad "2" smd roundrect
			(at 0.48 0)
			(size 0.59 0.64)
			(layers "B.Cu" "B.Mask" "B.Paste")
			(roundrect_rratio 0.25)
			(net 436 "/M.2/M2_M_PET3_N")
			(pintype "passive")
		)
	)
	(footprint "antmicro-footprints:SOT-523"
		(layer "B.Cu")
		(at 218.192132 97.084486 -90)
		(property "Reference" "Q35"
			(at 2.015514 -1.007868 0)
			(layer "B.SilkS")
			(effects
				(font
					(size 0.7 0.7)
					(thickness 0.15)
				)
				(justify left bottom mirror)
			)
		)
		(property "Value" "DMG1012T-7"
			(at 0.1 -1.824 90)
			(layer "B.Fab")
			(effects
				(font
					(size 0.7 0.7)
					(thickness 0.15)
				)
				(justify left bottom mirror)
			)
		)
		(property "Datasheet" "https://www.diodes.com/assets/Datasheets/ds31783.pdf"
			(at 0 0 90)
			(layer "B.Fab")
			(hide yes)
			(effects
				(font
					(size 1.27 1.27)
					(thickness 0.15)
				)
				(justify mirror)
			)
		)
		(property "Description" "Power MOSFET, N Channel, 20 V, 630 mA, 0.3 ohm, SOT-523, Surface Mount"
			(at 0 0 90)
			(layer "B.Fab")
			(hide yes)
			(effects
				(font
					(size 1.27 1.27)
					(thickness 0.15)
				)
				(justify mirror)
			)
		)
		(property "MPN" "DMG1012T-7"
			(at 0 0 90)
			(unlocked yes)
			(layer "B.Fab")
			(hide yes)
			(effects
				(font
					(size 1 1)
					(thickness 0.15)
				)
				(justify mirror)
			)
		)
		(property "Manufacturer" "Diodes Incorporated"
			(at 0 0 90)
			(unlocked yes)
			(layer "B.Fab")
			(hide yes)
			(effects
				(font
					(size 1 1)
					(thickness 0.15)
				)
				(justify mirror)
			)
		)
		(property "Author" "Antmicro"
			(at 0 0 90)
			(unlocked yes)
			(layer "B.Fab")
			(hide yes)
			(effects
				(font
					(size 1 1)
					(thickness 0.15)
				)
				(justify mirror)
			)
		)
		(property "License" "Apache-2.0"
			(at 0 0 90)
			(unlocked yes)
			(layer "B.Fab")
			(hide yes)
			(effects
				(font
					(size 1 1)
					(thickness 0.15)
				)
				(justify mirror)
			)
		)
		(sheetname "/USB DP Alt mode/")
		(sheetfile "usb_dp.kicad_sch")
		(attr smd)
		(fp_line
			(start -0.725 0.551)
			(end -0.277 0.551)
			(stroke
				(width 0.15)
				(type solid)
			)
			(layer "B.SilkS")
		)
		(fp_line
			(start -0.277 0.551)
			(end -0.277 0.75)
			(stroke
				(width 0.15)
				(type solid)
			)
			(layer "B.SilkS")
		)
		(fp_line
			(start -0.927 0.351)
			(end -0.725 0.551)
			(stroke
				(width 0.15)
				(type solid)
			)
			(layer "B.SilkS")
		)
		(fp_line
			(start -0.927 0.051)
			(end -0.927 0.351)
			(stroke
				(width 0.15)
				(type solid)
			)
			(layer "B.SilkS")
		)
		(fp_circle
			(center -0.9652 -0.9652)
			(end -0.9152 -0.9652)
			(stroke
				(width 0.15)
				(type solid)
			)
			(fill yes)
			(layer "B.SilkS")
		)
		(fp_line
			(start -1.12 1.16)
			(end 1.1 1.16)
			(stroke
				(width 0.05)
				(type solid)
			)
			(layer "B.CrtYd")
		)
		(fp_line
			(start -1.12 1.16)
			(end -1.12 -1.15)
			(stroke
				(width 0.05)
				(type solid)
			)
			(layer "B.CrtYd")
		)
		(fp_line
			(start 1.1 1.16)
			(end 1.1 -1.15)
			(stroke
				(width 0.05)
				(type solid)
			)
			(layer "B.CrtYd")
		)
		(fp_line
			(start -1.12 -1.15)
			(end 1.1 -1.15)
			(stroke
				(width 0.05)
				(type solid)
			)
			(layer "B.CrtYd")
		)
		(fp_line
			(start -0.652 0.425)
			(end -0.802 0.276)
			(stroke
				(width 0.15)
				(type solid)
			)
			(layer "B.Fab")
		)
		(fp_line
			(start 0.8 0.425)
			(end -0.652 0.425)
			(stroke
				(width 0.15)
				(type solid)
			)
			(layer "B.Fab")
		)
		(fp_line
			(start 0.8 0.425)
			(end 0.8 -0.424)
			(stroke
				(width 0.15)
				(type solid)
			)
			(layer "B.Fab")
		)
		(fp_line
			(start -0.802 0.276)
			(end -0.802 -0.424)
			(stroke
				(width 0.15)
				(type solid)
			)
			(layer "B.Fab")
		)
		(fp_line
			(start 0.8 -0.424)
			(end -0.802 -0.424)
			(stroke
				(width 0.15)
				(type solid)
			)
			(layer "B.Fab")
		)
		(fp_circle
			(center -0.9652 -0.9652)
			(end -0.9144 -0.9652)
			(stroke
				(width 0.15)
				(type solid)
			)
			(fill no)
			(layer "B.Fab")
		)
		(fp_text user "Author: Antmicro"
			(at -1.12 -6.224 90)
			(layer "B.Fab")
			(effects
				(font
					(size 0.7 0.7)
					(thickness 0.15)
				)
				(justify left bottom mirror)
			)
		)
		(fp_text user "License: Apache-2.0"
			(at -1.12 -5.024 90)
			(layer "B.Fab")
			(effects
				(font
					(size 0.7 0.7)
					(thickness 0.15)
				)
				(justify left bottom mirror)
			)
		)
		(fp_text user "${REFERENCE}"
			(at -1.12 -3.824 90)
			(layer "B.Fab")
			(effects
				(font
					(size 0.7 0.7)
					(thickness 0.15)
				)
				(justify left bottom mirror)
			)
		)
		(pad "1" smd rect
			(at -0.5 -0.65 270)
			(size 0.4 0.51)
			(layers "B.Cu" "B.Mask" "B.Paste")
			(net 1300 "Net-(Q34-D)")
			(pinfunction "G")
			(pintype "input")
		)
		(pad "2" smd rect
			(at 0.498 -0.65 270)
			(size 0.4 0.51)
			(layers "B.Cu" "B.Mask" "B.Paste")
			(net 1 "GND")
			(pinfunction "S")
			(pintype "passive")
		)
		(pad "3" smd rect
			(at 0 0.652 270)
			(size 0.4 0.51)
			(layers "B.Cu" "B.Mask" "B.Paste")
			(net 1301 "Net-(Q35-D)")
			(pinfunction "D")
			(pintype "passive")
		)
	)
	(footprint "antmicro-footprints:TP_SMD_0.75mm"
		(layer "B.Cu")
		(at 197.6 118.4 90)
		(property "Reference" "TP69"
			(at 0.4 0.6 0)
			(layer "B.SilkS")
			(effects
				(font
					(size 0.7 0.7)
					(thickness 0.15)
				)
				(justify right top mirror)
			)
		)
		(property "Value" "TP_0.75mm_SMD"
			(at 0 -1.2 90)
			(layer "B.Fab")
			(effects
				(font
					(size 0.7 0.7)
					(thickness 0.15)
				)
				(justify right top mirror)
			)
		)
		(property "Description" "SMT test point"
			(at 0 0 90)
			(layer "B.Fab")
			(hide yes)
			(effects
				(font
					(size 1.27 1.27)
					(thickness 0.15)
				)
				(justify mirror)
			)
		)
		(property "MPN" ""
			(at 0 0 270)
			(unlocked yes)
			(layer "B.Fab")
			(hide yes)
			(effects
				(font
					(size 1 1)
					(thickness 0.15)
				)
				(justify mirror)
			)
		)
		(property "Manufacturer" ""
			(at 0 0 270)
			(unlocked yes)
			(layer "B.Fab")
			(hide yes)
			(effects
				(font
					(size 1 1)
					(thickness 0.15)
				)
				(justify mirror)
			)
		)
		(property "Author" "Antmicro"
			(at 0 0 270)
			(unlocked yes)
			(layer "B.Fab")
			(hide yes)
			(effects
				(font
					(size 1 1)
					(thickness 0.15)
				)
				(justify mirror)
			)
		)
		(property "License" "Apache-2.0"
			(at 0 0 270)
			(unlocked yes)
			(layer "B.Fab")
			(hide yes)
			(effects
				(font
					(size 1 1)
					(thickness 0.15)
				)
				(justify mirror)
			)
		)
		(sheetname "/USB Hub/")
		(sheetfile "usb_hub.kicad_sch")
		(attr exclude_from_pos_files exclude_from_bom)
		(fp_circle
			(center 0 0)
			(end 0.475 0)
			(stroke
				(width 0.05)
				(type default)
			)
			(fill no)
			(layer "B.CrtYd")
		)
		(fp_text user "License: Apache-2.0"
			(at -0.4 -5.101 90)
			(layer "B.Fab")
			(effects
				(font
					(size 0.7 0.7)
					(thickness 0.15)
				)
				(justify right top mirror)
			)
		)
		(fp_text user "Author: Antmicro"
			(at -0.4 -3.901 90)
			(layer "B.Fab")
			(effects
				(font
					(size 0.7 0.7)
					(thickness 0.15)
				)
				(justify right top mirror)
			)
		)
		(fp_text user "${REFERENCE}"
			(at -0.4 -2.7 90)
			(layer "B.Fab")
			(effects
				(font
					(size 0.7 0.7)
					(thickness 0.15)
				)
				(justify right top mirror)
			)
		)
		(pad "1" smd circle
			(at 0 0 90)
			(size 0.75 0.75)
			(layers "B.Cu" "B.Mask")
			(net 1099 "/USB Hub/DP2_VCONN1")
			(pinfunction "1")
			(pintype "passive")
		)
	)
	(footprint "antmicro-footprints:C_0402_1005Metric"
		(layer "B.Cu")
		(at 107.85 70.66 180)
		(descr "Capacitor SMD 0402")
		(tags "capacitor SMD 0402")
		(property "Reference" "C4"
			(at -0.75 -1.44 0)
			(layer "B.SilkS")
			(effects
				(font
					(size 0.7 0.7)
					(thickness 0.15)
				)
				(justify left bottom mirror)
			)
		)
		(property "Value" "C_10u_0402"
			(at -1.022927 -2.155213 0)
			(layer "B.Fab")
			(effects
				(font
					(size 0.7 0.7)
					(thickness 0.15)
				)
				(justify left bottom mirror)
			)
		)
		(property "Datasheet" "https://www.yageo.com/en/Chart/Download/pdf/CC0402MRX5R5BB106"
			(at 0 0 0)
			(layer "B.Fab")
			(hide yes)
			(effects
				(font
					(size 1.27 1.27)
					(thickness 0.15)
				)
				(justify mirror)
			)
		)
		(property "Description" "SMD Multilayer Ceramic Capacitor, 10 µF, 6.3 V, 0402 [1005 Metric], ± 20%, X5R, CC Series"
			(at 0 0 0)
			(layer "B.Fab")
			(hide yes)
			(effects
				(font
					(size 1.27 1.27)
					(thickness 0.15)
				)
				(justify mirror)
			)
		)
		(property "MPN" "CC0402MRX5R5BB106"
			(at 0 0 0)
			(unlocked yes)
			(layer "B.Fab")
			(hide yes)
			(effects
				(font
					(size 1 1)
					(thickness 0.15)
				)
				(justify mirror)
			)
		)
		(property "Manufacturer" "YAGEO"
			(at 0 0 0)
			(unlocked yes)
			(layer "B.Fab")
			(hide yes)
			(effects
				(font
					(size 1 1)
					(thickness 0.15)
				)
				(justify mirror)
			)
		)
		(property "License" "Apache-2.0"
			(at 0 0 0)
			(unlocked yes)
			(layer "B.Fab")
			(hide yes)
			(effects
				(font
					(size 1 1)
					(thickness 0.15)
				)
				(justify mirror)
			)
		)
		(property "Author" "Antmicro"
			(at 0 0 0)
			(unlocked yes)
			(layer "B.Fab")
			(hide yes)
			(effects
				(font
					(size 1 1)
					(thickness 0.15)
				)
				(justify mirror)
			)
		)
		(property "Val" "10u"
			(at 0 0 0)
			(unlocked yes)
			(layer "B.Fab")
			(hide yes)
			(effects
				(font
					(size 1 1)
					(thickness 0.15)
				)
				(justify mirror)
			)
		)
		(property "Voltage" ""
			(at 0 0 0)
			(unlocked yes)
			(layer "B.Fab")
			(hide yes)
			(effects
				(font
					(size 1 1)
					(thickness 0.15)
				)
				(justify mirror)
			)
		)
		(property "Dielectric" "template_dielectric"
			(at 0 0 0)
			(unlocked yes)
			(layer "B.Fab")
			(hide yes)
			(effects
				(font
					(size 1 1)
					(thickness 0.15)
				)
				(justify mirror)
			)
		)
		(sheetname "/SoM_Power/")
		(sheetfile "som_power.kicad_sch")
		(attr smd)
		(fp_rect
			(start -0.925 0.47)
			(end 0.925 -0.47)
			(stroke
				(width 0.05)
				(type default)
			)
			(fill no)
			(layer "B.CrtYd")
		)
		(fp_line
			(start 0.504 0.25)
			(end 0.504 -0.248)
			(stroke
				(width 0.15)
				(type solid)
			)
			(layer "B.Fab")
		)
		(fp_line
			(start 0.504 -0.248)
			(end -0.494 -0.248)
			(stroke
				(width 0.15)
				(type solid)
			)
			(layer "B.Fab")
		)
		(fp_line
			(start -0.494 0.25)
			(end 0.504 0.25)
			(stroke
				(width 0.15)
				(type solid)
			)
			(layer "B.Fab")
		)
		(fp_line
			(start -0.494 -0.248)
			(end -0.494 0.25)
			(stroke
				(width 0.15)
				(type solid)
			)
			(layer "B.Fab")
		)
		(fp_text user "${REFERENCE}"
			(at -0.939 -4.599 0)
			(layer "B.Fab")
			(effects
				(font
					(size 0.7 0.7)
					(thickness 0.15)
				)
				(justify left bottom mirror)
			)
		)
		(fp_text user "Author: Antmicro"
			(at -0.939 -3.399 0)
			(layer "B.Fab")
			(effects
				(font
					(size 0.7 0.7)
					(thickness 0.15)
				)
				(justify left bottom mirror)
			)
		)
		(fp_text user "License: Apache-2.0"
			(at -0.939 -5.799 0)
			(layer "B.Fab")
			(effects
				(font
					(size 0.7 0.7)
					(thickness 0.15)
				)
				(justify left bottom mirror)
			)
		)
		(pad "1" smd roundrect
			(at -0.48 0 180)
			(size 0.59 0.64)
			(layers "B.Cu" "B.Mask" "B.Paste")
			(roundrect_rratio 0.25)
			(net 1 "GND")
			(pintype "passive")
		)
		(pad "2" smd roundrect
			(at 0.48 0 180)
			(size 0.59 0.64)
			(layers "B.Cu" "B.Mask" "B.Paste")
			(roundrect_rratio 0.25)
			(net 213 "+5V_SOM")
			(pintype "passive")
		)
	)
	(footprint "antmicro-footprints:R_0402_1005Metric"
		(layer "B.Cu")
		(at 203.4 101.800001 180)
		(descr "Resistor SMD 0402")
		(tags "resistor SMD 0402")
		(property "Reference" "R252"
			(at -0.8 0.600001 0)
			(layer "B.SilkS")
			(effects
				(font
					(size 0.7 0.7)
					(thickness 0.15)
				)
				(justify left bottom mirror)
			)
		)
		(property "Value" "R_0R_0402"
			(at -1.011843 -1.772046 0)
			(layer "B.Fab")
			(effects
				(font
					(size 0.7 0.7)
					(thickness 0.15)
				)
				(justify left bottom mirror)
			)
		)
		(property "Datasheet" "https://industrial.panasonic.com/cdbs/www-data/pdf/RDA0000/AOA0000C301.pdf"
			(at 0 0 0)
			(layer "B.Fab")
			(hide yes)
			(effects
				(font
					(size 1.27 1.27)
					(thickness 0.15)
				)
				(justify mirror)
			)
		)
		(property "Description" "SMD Chip Resistor, Jumper, 0 ohm, 100 mW, 0402 [1005 Metric], Thick Film, General Purpose"
			(at 0 0 0)
			(layer "B.Fab")
			(hide yes)
			(effects
				(font
					(size 1.27 1.27)
					(thickness 0.15)
				)
				(justify mirror)
			)
		)
		(property "Manufacturer" "Panasonic"
			(at 0 0 0)
			(unlocked yes)
			(layer "B.Fab")
			(hide yes)
			(effects
				(font
					(size 1 1)
					(thickness 0.15)
				)
				(justify mirror)
			)
		)
		(property "MPN" "ERJ2GE0R00X"
			(at 0 0 0)
			(unlocked yes)
			(layer "B.Fab")
			(hide yes)
			(effects
				(font
					(size 1 1)
					(thickness 0.15)
				)
				(justify mirror)
			)
		)
		(property "Val" "0R"
			(at 0 0 0)
			(unlocked yes)
			(layer "B.Fab")
			(hide yes)
			(effects
				(font
					(size 1 1)
					(thickness 0.15)
				)
				(justify mirror)
			)
		)
		(property "License" "Apache-2.0"
			(at 0 0 0)
			(unlocked yes)
			(layer "B.Fab")
			(hide yes)
			(effects
				(font
					(size 1 1)
					(thickness 0.15)
				)
				(justify mirror)
			)
		)
		(property "Author" "Antmicro"
			(at 0 0 0)
			(unlocked yes)
			(layer "B.Fab")
			(hide yes)
			(effects
				(font
					(size 1 1)
					(thickness 0.15)
				)
				(justify mirror)
			)
		)
		(property "Tolerance" "~"
			(at 0 0 0)
			(unlocked yes)
			(layer "B.Fab")
			(hide yes)
			(effects
				(font
					(size 1 1)
					(thickness 0.15)
				)
				(justify mirror)
			)
		)
		(property "Current" "1A"
			(at 0 0 0)
			(unlocked yes)
			(layer "B.Fab")
			(hide yes)
			(effects
				(font
					(size 1 1)
					(thickness 0.15)
				)
				(justify mirror)
			)
		)
		(sheetname "/Recovery USB/")
		(sheetfile "recovery_usb.kicad_sch")
		(attr smd exclude_from_pos_files exclude_from_bom dnp)
		(fp_poly
			(pts
				(xy -0.925 0.47) (xy 0.925 0.47) (xy 0.925 -0.47) (xy -0.925 -0.47)
			)
			(stroke
				(width 0.05)
				(type default)
			)
			(fill no)
			(layer "B.CrtYd")
		)
		(fp_poly
			(pts
				(xy -0.5 0.25) (xy 0.5 0.25) (xy 0.5 -0.25) (xy -0.5 -0.25)
			)
			(stroke
				(width 0.15)
				(type solid)
			)
			(fill no)
			(layer "B.Fab")
		)
		(fp_text user "Author: Antmicro"
			(at -0.95 -4.169 0)
			(layer "B.Fab")
			(effects
				(font
					(size 0.7 0.7)
					(thickness 0.15)
				)
				(justify left bottom mirror)
			)
		)
		(fp_text user "License: Apache-2.0"
			(at -0.949999 -5.169 0)
			(layer "B.Fab")
			(effects
				(font
					(size 0.7 0.7)
					(thickness 0.15)
				)
				(justify left bottom mirror)
			)
		)
		(fp_text user "${REFERENCE}"
			(at -0.95 -3.168 0)
			(layer "B.Fab")
			(effects
				(font
					(size 0.7 0.7)
					(thickness 0.15)
				)
				(justify left bottom mirror)
			)
		)
		(pad "1" smd roundrect
			(at -0.48 0 180)
			(size 0.59 0.64)
			(layers "B.Cu" "B.Mask" "B.Paste")
			(roundrect_rratio 0.25)
			(net 1011 "/Recovery USB/USBC2_ADDR")
			(pintype "passive")
		)
		(pad "2" smd roundrect
			(at 0.48 0 180)
			(size 0.59 0.64)
			(layers "B.Cu" "B.Mask" "B.Paste")
			(roundrect_rratio 0.25)
			(net 5 "+5V")
			(pintype "passive")
		)
	)
	(footprint "antmicro-footprints:R_0402_1005Metric"
		(layer "B.Cu")
		(at 178.3 66.3)
		(descr "Resistor SMD 0402")
		(tags "resistor SMD 0402")
		(property "Reference" "R217"
			(at 1.1 -0.5 180)
			(layer "B.SilkS")
			(effects
				(font
					(size 0.7 0.7)
					(thickness 0.15)
				)
				(justify left bottom mirror)
			)
		)
		(property "Value" "R_0R_0402"
			(at -1.011843 -1.772046 180)
			(layer "B.Fab")
			(effects
				(font
					(size 0.7 0.7)
					(thickness 0.15)
				)
				(justify left bottom mirror)
			)
		)
		(property "Datasheet" "https://industrial.panasonic.com/cdbs/www-data/pdf/RDA0000/AOA0000C301.pdf"
			(at 0 0 180)
			(layer "B.Fab")
			(hide yes)
			(effects
				(font
					(size 1.27 1.27)
					(thickness 0.15)
				)
				(justify mirror)
			)
		)
		(property "Description" "SMD Chip Resistor, Jumper, 0 ohm, 100 mW, 0402 [1005 Metric], Thick Film, General Purpose"
			(at 0 0 180)
			(layer "B.Fab")
			(hide yes)
			(effects
				(font
					(size 1.27 1.27)
					(thickness 0.15)
				)
				(justify mirror)
			)
		)
		(property "MPN" "ERJ2GE0R00X"
			(at 0 0 180)
			(unlocked yes)
			(layer "B.Fab")
			(hide yes)
			(effects
				(font
					(size 1 1)
					(thickness 0.15)
				)
				(justify mirror)
			)
		)
		(property "Manufacturer" "Panasonic"
			(at 0 0 180)
			(unlocked yes)
			(layer "B.Fab")
			(hide yes)
			(effects
				(font
					(size 1 1)
					(thickness 0.15)
				)
				(justify mirror)
			)
		)
		(property "License" "Apache-2.0"
			(at 0 0 180)
			(unlocked yes)
			(layer "B.Fab")
			(hide yes)
			(effects
				(font
					(size 1 1)
					(thickness 0.15)
				)
				(justify mirror)
			)
		)
		(property "Author" "Antmicro"
			(at 0 0 180)
			(unlocked yes)
			(layer "B.Fab")
			(hide yes)
			(effects
				(font
					(size 1 1)
					(thickness 0.15)
				)
				(justify mirror)
			)
		)
		(property "Val" "0R"
			(at 0 0 180)
			(unlocked yes)
			(layer "B.Fab")
			(hide yes)
			(effects
				(font
					(size 1 1)
					(thickness 0.15)
				)
				(justify mirror)
			)
		)
		(property "Tolerance" "~"
			(at 0 0 180)
			(unlocked yes)
			(layer "B.Fab")
			(hide yes)
			(effects
				(font
					(size 1 1)
					(thickness 0.15)
				)
				(justify mirror)
			)
		)
		(property "Current" "1A"
			(at 0 0 180)
			(unlocked yes)
			(layer "B.Fab")
			(hide yes)
			(effects
				(font
					(size 1 1)
					(thickness 0.15)
				)
				(justify mirror)
			)
		)
		(component_classes
			(class "DCDC_20V")
		)
		(sheetname "/DCDC/")
		(sheetfile "dcdc.kicad_sch")
		(attr smd)
		(fp_poly
			(pts
				(xy -0.925 0.47) (xy 0.925 0.47) (xy 0.925 -0.47) (xy -0.925 -0.47)
			)
			(stroke
				(width 0.05)
				(type default)
			)
			(fill no)
			(layer "B.CrtYd")
		)
		(fp_poly
			(pts
				(xy -0.5 0.25) (xy 0.5 0.25) (xy 0.5 -0.25) (xy -0.5 -0.25)
			)
			(stroke
				(width 0.15)
				(type solid)
			)
			(fill no)
			(layer "B.Fab")
		)
		(fp_text user "License: Apache-2.0"
			(at -0.949999 -5.169 180)
			(layer "B.Fab")
			(effects
				(font
					(size 0.7 0.7)
					(thickness 0.15)
				)
				(justify left bottom mirror)
			)
		)
		(fp_text user "${REFERENCE}"
			(at -0.95 -3.168 180)
			(layer "B.Fab")
			(effects
				(font
					(size 0.7 0.7)
					(thickness 0.15)
				)
				(justify left bottom mirror)
			)
		)
		(fp_text user "Author: Antmicro"
			(at -0.95 -4.169 180)
			(layer "B.Fab")
			(effects
				(font
					(size 0.7 0.7)
					(thickness 0.15)
				)
				(justify left bottom mirror)
			)
		)
		(pad "1" smd roundrect
			(at -0.48 0)
			(size 0.59 0.64)
			(layers "B.Cu" "B.Mask" "B.Paste")
			(roundrect_rratio 0.25)
			(net 1293 "/DCDC/CARRIER_PWR_ON")
			(pintype "passive")
		)
		(pad "2" smd roundrect
			(at 0.48 0)
			(size 0.59 0.64)
			(layers "B.Cu" "B.Mask" "B.Paste")
			(roundrect_rratio 0.25)
			(net 1211 "/DCDC/20V_EN")
			(pintype "passive")
		)
	)
	(footprint "antmicro-footprints:R_0402_1005Metric"
		(layer "B.Cu")
		(at 237.68 94.4 180)
		(descr "Resistor SMD 0402")
		(tags "resistor SMD 0402")
		(property "Reference" "R143"
			(at -2.12 -1.4 0)
			(layer "B.SilkS")
			(effects
				(font
					(size 0.7 0.7)
					(thickness 0.15)
				)
				(justify left bottom mirror)
			)
		)
		(property "Value" "R_0R_0402"
			(at -1.011843 -1.772046 0)
			(layer "B.Fab")
			(effects
				(font
					(size 0.7 0.7)
					(thickness 0.15)
				)
				(justify left bottom mirror)
			)
		)
		(property "Datasheet" "https://industrial.panasonic.com/cdbs/www-data/pdf/RDA0000/AOA0000C301.pdf"
			(at 0 0 0)
			(layer "B.Fab")
			(hide yes)
			(effects
				(font
					(size 1.27 1.27)
					(thickness 0.15)
				)
				(justify mirror)
			)
		)
		(property "Description" "SMD Chip Resistor, Jumper, 0 ohm, 100 mW, 0402 [1005 Metric], Thick Film, General Purpose"
			(at 0 0 0)
			(layer "B.Fab")
			(hide yes)
			(effects
				(font
					(size 1.27 1.27)
					(thickness 0.15)
				)
				(justify mirror)
			)
		)
		(property "Manufacturer" "Panasonic"
			(at 0 0 0)
			(unlocked yes)
			(layer "B.Fab")
			(hide yes)
			(effects
				(font
					(size 1 1)
					(thickness 0.15)
				)
				(justify mirror)
			)
		)
		(property "MPN" "ERJ2GE0R00X"
			(at 0 0 0)
			(unlocked yes)
			(layer "B.Fab")
			(hide yes)
			(effects
				(font
					(size 1 1)
					(thickness 0.15)
				)
				(justify mirror)
			)
		)
		(property "Val" "0R"
			(at 0 0 0)
			(unlocked yes)
			(layer "B.Fab")
			(hide yes)
			(effects
				(font
					(size 1 1)
					(thickness 0.15)
				)
				(justify mirror)
			)
		)
		(property "License" "Apache-2.0"
			(at 0 0 0)
			(unlocked yes)
			(layer "B.Fab")
			(hide yes)
			(effects
				(font
					(size 1 1)
					(thickness 0.15)
				)
				(justify mirror)
			)
		)
		(property "Author" "Antmicro"
			(at 0 0 0)
			(unlocked yes)
			(layer "B.Fab")
			(hide yes)
			(effects
				(font
					(size 1 1)
					(thickness 0.15)
				)
				(justify mirror)
			)
		)
		(property "Tolerance" "~"
			(at 0 0 0)
			(unlocked yes)
			(layer "B.Fab")
			(hide yes)
			(effects
				(font
					(size 1 1)
					(thickness 0.15)
				)
				(justify mirror)
			)
		)
		(property "Current" "1A"
			(at 0 0 0)
			(unlocked yes)
			(layer "B.Fab")
			(hide yes)
			(effects
				(font
					(size 1 1)
					(thickness 0.15)
				)
				(justify mirror)
			)
		)
		(sheetname "/USB DP Alt mode/")
		(sheetfile "usb_dp.kicad_sch")
		(attr smd)
		(fp_poly
			(pts
				(xy -0.925 0.47) (xy -0.925 -0.47) (xy 0.925 -0.47) (xy 0.925 0.47)
			)
			(stroke
				(width 0.05)
				(type default)
			)
			(fill no)
			(layer "B.CrtYd")
		)
		(fp_poly
			(pts
				(xy -0.5 0.25) (xy -0.5 -0.25) (xy 0.5 -0.25) (xy 0.5 0.25)
			)
			(stroke
				(width 0.15)
				(type solid)
			)
			(fill no)
			(layer "B.Fab")
		)
		(fp_text user "${REFERENCE}"
			(at -0.95 -3.168 0)
			(layer "B.Fab")
			(effects
				(font
					(size 0.7 0.7)
					(thickness 0.15)
				)
				(justify left bottom mirror)
			)
		)
		(fp_text user "Author: Antmicro"
			(at -0.95 -4.169 0)
			(layer "B.Fab")
			(effects
				(font
					(size 0.7 0.7)
					(thickness 0.15)
				)
				(justify left bottom mirror)
			)
		)
		(fp_text user "License: Apache-2.0"
			(at -0.949999 -5.169 0)
			(layer "B.Fab")
			(effects
				(font
					(size 0.7 0.7)
					(thickness 0.15)
				)
				(justify left bottom mirror)
			)
		)
		(pad "1" smd roundrect
			(at -0.48 0 180)
			(size 0.59 0.64)
			(layers "B.Cu" "B.Mask" "B.Paste")
			(roundrect_rratio 0.25)
			(net 970 "/USB DP Alt mode/USBC1_5V_PEN")
			(pintype "passive")
		)
		(pad "2" smd roundrect
			(at 0.48 0 180)
			(size 0.59 0.64)
			(layers "B.Cu" "B.Mask" "B.Paste")
			(roundrect_rratio 0.25)
			(net 971 "Net-(U35-EN)")
			(pintype "passive")
		)
	)
	(footprint "antmicro-footprints:C_0603_1608Metric_EIA"
		(layer "B.Cu")
		(at 124.6 112)
		(descr "Capacitor SMD 0603, IPC-7351 Density Level A")
		(tags "Capacitor 0603")
		(property "Reference" "C192"
			(at 1.2 1.2 0)
			(layer "B.SilkS")
			(effects
				(font
					(size 0.7 0.7)
					(thickness 0.15)
				)
				(justify right top mirror)
			)
		)
		(property "Value" "C_22u_16V_0603"
			(at -1.42757 -1.770288 0)
			(layer "B.Fab")
			(effects
				(font
					(size 0.7 0.7)
					(thickness 0.15)
				)
				(justify right top mirror)
			)
		)
		(property "Datasheet" "https://product.samsungsem.com/mlcc/CL10A226MO7JZN.do"
			(at 0 0 0)
			(layer "B.Fab")
			(hide yes)
			(effects
				(font
					(size 1.27 1.27)
					(thickness 0.15)
				)
				(justify mirror)
			)
		)
		(property "Description" "SMD Multilayer Ceramic Capacitor"
			(at 0 0 0)
			(layer "B.Fab")
			(hide yes)
			(effects
				(font
					(size 1.27 1.27)
					(thickness 0.15)
				)
				(justify mirror)
			)
		)
		(property "Manufacturer" "Samsung Electro-Mechanics"
			(at 0 0 0)
			(unlocked yes)
			(layer "B.Fab")
			(hide yes)
			(effects
				(font
					(size 1 1)
					(thickness 0.15)
				)
				(justify mirror)
			)
		)
		(property "MPN" "CL10A226MO7JZNC"
			(at 0 0 0)
			(unlocked yes)
			(layer "B.Fab")
			(hide yes)
			(effects
				(font
					(size 1 1)
					(thickness 0.15)
				)
				(justify mirror)
			)
		)
		(property "Val" "22u"
			(at 0 0 0)
			(unlocked yes)
			(layer "B.Fab")
			(hide yes)
			(effects
				(font
					(size 1 1)
					(thickness 0.15)
				)
				(justify mirror)
			)
		)
		(property "License" "Apache-2.0"
			(at 0 0 0)
			(unlocked yes)
			(layer "B.Fab")
			(hide yes)
			(effects
				(font
					(size 1 1)
					(thickness 0.15)
				)
				(justify mirror)
			)
		)
		(property "Author" "Antmicro"
			(at 0 0 0)
			(unlocked yes)
			(layer "B.Fab")
			(hide yes)
			(effects
				(font
					(size 1 1)
					(thickness 0.15)
				)
				(justify mirror)
			)
		)
		(property "Voltage" "16V"
			(at 0 0 0)
			(unlocked yes)
			(layer "B.Fab")
			(hide yes)
			(effects
				(font
					(size 1 1)
					(thickness 0.15)
				)
				(justify mirror)
			)
		)
		(property "Dielectric" "template_dielectric"
			(at 0 0 0)
			(unlocked yes)
			(layer "B.Fab")
			(hide yes)
			(effects
				(font
					(size 1 1)
					(thickness 0.15)
				)
				(justify mirror)
			)
		)
		(sheetname "/M.2/")
		(sheetfile "m2.kicad_sch")
		(attr smd)
		(fp_line
			(start -0.15 -0.55)
			(end 0.15 -0.55)
			(stroke
				(width 0.15)
				(type solid)
			)
			(layer "B.SilkS")
		)
		(fp_line
			(start -0.15 0.55)
			(end 0.15 0.55)
			(stroke
				(width 0.15)
				(type solid)
			)
			(layer "B.SilkS")
		)
		(fp_poly
			(pts
				(xy -1.25 0.65) (xy -1.25 -0.65) (xy 1.25 -0.65) (xy 1.25 0.65)
			)
			(stroke
				(width 0.05)
				(type solid)
			)
			(fill no)
			(layer "B.CrtYd")
		)
		(fp_poly
			(pts
				(xy -0.799999 0.45) (xy -0.799999 -0.45) (xy 0.799999 -0.45) (xy 0.799999 0.45)
			)
			(stroke
				(width 0.15)
				(type solid)
			)
			(fill no)
			(layer "B.Fab")
		)
		(fp_text user "${REFERENCE}"
			(at -1.682001 -3.895 0)
			(layer "B.Fab")
			(effects
				(font
					(size 0.7 0.7)
					(thickness 0.15)
				)
				(justify right top mirror)
			)
		)
		(fp_text user "License: Apache-2.0"
			(at -1.682 -5.895 0)
			(layer "B.Fab")
			(effects
				(font
					(size 0.7 0.7)
					(thickness 0.15)
				)
				(justify right top mirror)
			)
		)
		(fp_text user "Author: Antmicro"
			(at -1.682 -4.894 0)
			(layer "B.Fab")
			(effects
				(font
					(size 0.7 0.7)
					(thickness 0.15)
				)
				(justify right top mirror)
			)
		)
		(pad "1" smd roundrect
			(at -0.7 0)
			(size 0.8 1.1)
			(layers "B.Cu" "B.Mask" "B.Paste")
			(roundrect_rratio 0.2)
			(net 14 "/M.2/3V3_M2")
			(pintype "passive")
		)
		(pad "2" smd roundrect
			(at 0.7 0)
			(size 0.8 1.1)
			(layers "B.Cu" "B.Mask" "B.Paste")
			(roundrect_rratio 0.2)
			(net 1 "GND")
			(pintype "passive")
		)
	)
	(footprint "antmicro-footprints:R_0402_1005Metric"
		(layer "B.Cu")
		(at 238.2 106.8)
		(descr "Resistor SMD 0402")
		(tags "resistor SMD 0402")
		(property "Reference" "R265"
			(at -1.1 1.6 0)
			(layer "B.SilkS")
			(effects
				(font
					(size 0.7 0.7)
					(thickness 0.15)
				)
				(justify right top mirror)
			)
		)
		(property "Value" "R_1k_0402"
			(at -1.011843 -1.772046 0)
			(layer "B.Fab")
			(effects
				(font
					(size 0.7 0.7)
					(thickness 0.15)
				)
				(justify right top mirror)
			)
		)
		(property "Datasheet" "https://www.bourns.com/docs/product-datasheets/cr.pdf"
			(at 0 0 0)
			(layer "B.Fab")
			(hide yes)
			(effects
				(font
					(size 1.27 1.27)
					(thickness 0.15)
				)
				(justify mirror)
			)
		)
		(property "Description" "SMD Chip Resistor, 1 kohm, ± 1%, 63 mW, 0402 [1005 Metric], Thick Film, General Purpose"
			(at 0 0 0)
			(layer "B.Fab")
			(hide yes)
			(effects
				(font
					(size 1.27 1.27)
					(thickness 0.15)
				)
				(justify mirror)
			)
		)
		(property "Manufacturer" "Bourns"
			(at 0 0 180)
			(unlocked yes)
			(layer "B.Fab")
			(hide yes)
			(effects
				(font
					(size 1 1)
					(thickness 0.15)
				)
				(justify mirror)
			)
		)
		(property "MPN" "CR0402-FX-1001GLF"
			(at 0 0 180)
			(unlocked yes)
			(layer "B.Fab")
			(hide yes)
			(effects
				(font
					(size 1 1)
					(thickness 0.15)
				)
				(justify mirror)
			)
		)
		(property "Val" "1k"
			(at 0 0 180)
			(unlocked yes)
			(layer "B.Fab")
			(hide yes)
			(effects
				(font
					(size 1 1)
					(thickness 0.15)
				)
				(justify mirror)
			)
		)
		(property "License" "Apache-2.0"
			(at 0 0 180)
			(unlocked yes)
			(layer "B.Fab")
			(hide yes)
			(effects
				(font
					(size 1 1)
					(thickness 0.15)
				)
				(justify mirror)
			)
		)
		(property "Author" "Antmicro"
			(at 0 0 180)
			(unlocked yes)
			(layer "B.Fab")
			(hide yes)
			(effects
				(font
					(size 1 1)
					(thickness 0.15)
				)
				(justify mirror)
			)
		)
		(property "Tolerance" "1%"
			(at 0 0 180)
			(unlocked yes)
			(layer "B.Fab")
			(hide yes)
			(effects
				(font
					(size 1 1)
					(thickness 0.15)
				)
				(justify mirror)
			)
		)
		(sheetname "/Recovery USB/")
		(sheetfile "recovery_usb.kicad_sch")
		(attr smd)
		(fp_poly
			(pts
				(xy -0.925 0.47) (xy -0.925 -0.47) (xy 0.925 -0.47) (xy 0.925 0.47)
			)
			(stroke
				(width 0.05)
				(type default)
			)
			(fill no)
			(layer "B.CrtYd")
		)
		(fp_poly
			(pts
				(xy -0.5 0.25) (xy -0.5 -0.25) (xy 0.5 -0.25) (xy 0.5 0.25)
			)
			(stroke
				(width 0.15)
				(type solid)
			)
			(fill no)
			(layer "B.Fab")
		)
		(fp_text user "${REFERENCE}"
			(at -0.95 -3.168 0)
			(layer "B.Fab")
			(effects
				(font
					(size 0.7 0.7)
					(thickness 0.15)
				)
				(justify right top mirror)
			)
		)
		(fp_text user "Author: Antmicro"
			(at -0.95 -4.169 0)
			(layer "B.Fab")
			(effects
				(font
					(size 0.7 0.7)
					(thickness 0.15)
				)
				(justify right top mirror)
			)
		)
		(fp_text user "License: Apache-2.0"
			(at -0.949999 -5.169 0)
			(layer "B.Fab")
			(effects
				(font
					(size 0.7 0.7)
					(thickness 0.15)
				)
				(justify right top mirror)
			)
		)
		(pad "1" smd roundrect
			(at -0.48 0)
			(size 0.59 0.64)
			(layers "B.Cu" "B.Mask" "B.Paste")
			(roundrect_rratio 0.25)
			(net 1245 "Net-(R265-Pad1)")
			(pintype "passive")
		)
		(pad "2" smd roundrect
			(at 0.48 0)
			(size 0.59 0.64)
			(layers "B.Cu" "B.Mask" "B.Paste")
			(roundrect_rratio 0.25)
			(net 2 "+3V3")
			(pintype "passive")
		)
	)
	(footprint "antmicro-footprints:C_0805_2012Metric"
		(layer "B.Cu")
		(at 229.4 82.4 180)
		(descr "Capacitor SMD 0805")
		(tags "capacitor SMD 0805")
		(property "Reference" "C151"
			(at -0.1 1 0)
			(layer "B.SilkS")
			(effects
				(font
					(size 0.7 0.7)
					(thickness 0.15)
				)
				(justify left bottom mirror)
			)
		)
		(property "Value" "C_22u_25V_0805"
			(at -2.055717 -1.963153 0)
			(layer "B.Fab")
			(effects
				(font
					(size 0.7 0.7)
					(thickness 0.15)
				)
				(justify left bottom mirror)
			)
		)
		(property "Datasheet" "https://product.samsungsem.com/mlcc/CL21A226MAYNNN.do"
			(at 0 0 0)
			(layer "B.Fab")
			(hide yes)
			(effects
				(font
					(size 1.27 1.27)
					(thickness 0.15)
				)
				(justify mirror)
			)
		)
		(property "Description" "SMT Multilayer Ceramic Capacitor, 22uF, +/-20%, 25V, X5R, 0805 [2012 Metric]"
			(at 0 0 0)
			(layer "B.Fab")
			(hide yes)
			(effects
				(font
					(size 1.27 1.27)
					(thickness 0.15)
				)
				(justify mirror)
			)
		)
		(property "Manufacturer" "Samsung Electro-Mechanics"
			(at 0 0 180)
			(unlocked yes)
			(layer "B.Fab")
			(hide yes)
			(effects
				(font
					(size 1 1)
					(thickness 0.15)
				)
				(justify mirror)
			)
		)
		(property "MPN" "CL21A226MAYNNNE"
			(at 0 0 180)
			(unlocked yes)
			(layer "B.Fab")
			(hide yes)
			(effects
				(font
					(size 1 1)
					(thickness 0.15)
				)
				(justify mirror)
			)
		)
		(property "Val" "22u"
			(at 0 0 180)
			(unlocked yes)
			(layer "B.Fab")
			(hide yes)
			(effects
				(font
					(size 1 1)
					(thickness 0.15)
				)
				(justify mirror)
			)
		)
		(property "License" "Apache-2.0"
			(at 0 0 180)
			(unlocked yes)
			(layer "B.Fab")
			(hide yes)
			(effects
				(font
					(size 1 1)
					(thickness 0.15)
				)
				(justify mirror)
			)
		)
		(property "Author" "Antmicro"
			(at 0 0 180)
			(unlocked yes)
			(layer "B.Fab")
			(hide yes)
			(effects
				(font
					(size 1 1)
					(thickness 0.15)
				)
				(justify mirror)
			)
		)
		(property "Voltage" "25V"
			(at 0 0 180)
			(unlocked yes)
			(layer "B.Fab")
			(hide yes)
			(effects
				(font
					(size 1 1)
					(thickness 0.15)
				)
				(justify mirror)
			)
		)
		(property "Dielectric" "X5R"
			(at 0 0 180)
			(unlocked yes)
			(layer "B.Fab")
			(hide yes)
			(effects
				(font
					(size 1 1)
					(thickness 0.15)
				)
				(justify mirror)
			)
		)
		(property "Public" "False"
			(at 0 0 180)
			(unlocked yes)
			(layer "B.Fab")
			(hide yes)
			(effects
				(font
					(size 1 1)
					(thickness 0.15)
				)
				(justify mirror)
			)
		)
		(sheetname "/USB Debug, PD/")
		(sheetfile "usb_debug_pd.kicad_sch")
		(attr smd)
		(fp_line
			(start -0.3 0.7)
			(end 0.3 0.7)
			(stroke
				(width 0.15)
				(type solid)
			)
			(layer "B.SilkS")
		)
		(fp_line
			(start -0.3 -0.7)
			(end 0.3 -0.7)
			(stroke
				(width 0.15)
				(type solid)
			)
			(layer "B.SilkS")
		)
		(fp_poly
			(pts
				(xy 1.95 0.9) (xy -1.95 0.9) (xy -1.95 -0.9) (xy 1.95 -0.9)
			)
			(stroke
				(width 0.05)
				(type default)
			)
			(fill no)
			(layer "B.CrtYd")
		)
		(fp_poly
			(pts
				(xy -0.95 0.675001) (xy 0.95 0.675001) (xy 0.95 -0.675001) (xy -0.95 -0.675001)
			)
			(stroke
				(width 0.15)
				(type solid)
			)
			(fill no)
			(layer "B.Fab")
		)
		(fp_text user "${REFERENCE}"
			(at -1.899999 -3.947 0)
			(layer "B.Fab")
			(effects
				(font
					(size 0.7 0.7)
					(thickness 0.15)
				)
				(justify left bottom mirror)
			)
		)
		(fp_text user "License: Apache-2.0"
			(at -1.9 -4.947 0)
			(layer "B.Fab")
			(effects
				(font
					(size 0.7 0.7)
					(thickness 0.15)
				)
				(justify left bottom mirror)
			)
		)
		(fp_text user "Author: Antmicro"
			(at -1.9 -5.947 0)
			(layer "B.Fab")
			(effects
				(font
					(size 0.7 0.7)
					(thickness 0.15)
				)
				(justify left bottom mirror)
			)
		)
		(pad "1" smd roundrect
			(at -1.099999 0 180)
			(size 1.2 1.3)
			(layers "B.Cu" "B.Mask" "B.Paste")
			(roundrect_rratio 0.25)
			(net 176 "/USB Debug, PD/USBC0_VBUS")
			(pintype "passive")
		)
		(pad "2" smd roundrect
			(at 1.099999 0 180)
			(size 1.2 1.3)
			(layers "B.Cu" "B.Mask" "B.Paste")
			(roundrect_rratio 0.25)
			(net 1 "GND")
			(pintype "passive")
		)
	)
	(footprint "antmicro-footprints:R_0402_1005Metric"
		(layer "B.Cu")
		(at 227.2 109.4 -90)
		(descr "Resistor SMD 0402")
		(tags "resistor SMD 0402")
		(property "Reference" "R266"
			(at -3.84 -0.285 90)
			(layer "B.SilkS")
			(effects
				(font
					(size 0.7 0.7)
					(thickness 0.15)
				)
				(justify left bottom mirror)
			)
		)
		(property "Value" "R_10k_0402"
			(at -1.011843 -1.772047 90)
			(layer "B.Fab")
			(effects
				(font
					(size 0.7 0.7)
					(thickness 0.15)
				)
				(justify left bottom mirror)
			)
		)
		(property "Datasheet" "https://www.bourns.com/docs/product-datasheets/cr.pdf"
			(at 0 0 90)
			(layer "B.Fab")
			(hide yes)
			(effects
				(font
					(size 1.27 1.27)
					(thickness 0.15)
				)
				(justify mirror)
			)
		)
		(property "Description" "SMD Chip Resistor, 10 kohm, ± 1%, 62.5 mW, 0402 [1005 Metric], Thick Film, General Purpose"
			(at 0 0 90)
			(layer "B.Fab")
			(hide yes)
			(effects
				(font
					(size 1.27 1.27)
					(thickness 0.15)
				)
				(justify mirror)
			)
		)
		(property "Manufacturer" "Bourns"
			(at 0 0 90)
			(unlocked yes)
			(layer "B.Fab")
			(hide yes)
			(effects
				(font
					(size 1 1)
					(thickness 0.15)
				)
				(justify mirror)
			)
		)
		(property "MPN" "CR0402-FX-1002GLF"
			(at 0 0 90)
			(unlocked yes)
			(layer "B.Fab")
			(hide yes)
			(effects
				(font
					(size 1 1)
					(thickness 0.15)
				)
				(justify mirror)
			)
		)
		(property "Val" "10k"
			(at 0 0 90)
			(unlocked yes)
			(layer "B.Fab")
			(hide yes)
			(effects
				(font
					(size 1 1)
					(thickness 0.15)
				)
				(justify mirror)
			)
		)
		(property "License" "Apache-2.0"
			(at 0 0 90)
			(unlocked yes)
			(layer "B.Fab")
			(hide yes)
			(effects
				(font
					(size 1 1)
					(thickness 0.15)
				)
				(justify mirror)
			)
		)
		(property "Author" "Antmicro"
			(at 0 0 90)
			(unlocked yes)
			(layer "B.Fab")
			(hide yes)
			(effects
				(font
					(size 1 1)
					(thickness 0.15)
				)
				(justify mirror)
			)
		)
		(property "Tolerance" "1%"
			(at 0 0 90)
			(unlocked yes)
			(layer "B.Fab")
			(hide yes)
			(effects
				(font
					(size 1 1)
					(thickness 0.15)
				)
				(justify mirror)
			)
		)
		(sheetname "/Recovery USB/")
		(sheetfile "recovery_usb.kicad_sch")
		(attr smd)
		(fp_rect
			(start -0.925 0.47)
			(end 0.925 -0.47)
			(stroke
				(width 0.05)
				(type default)
			)
			(fill no)
			(layer "B.CrtYd")
		)
		(fp_rect
			(start -0.5 0.25)
			(end 0.5 -0.25)
			(stroke
				(width 0.15)
				(type solid)
			)
			(fill no)
			(layer "B.Fab")
		)
		(fp_text user "License: Apache-2.0"
			(at -0.95 -5.169 90)
			(layer "B.Fab")
			(effects
				(font
					(size 0.7 0.7)
					(thickness 0.15)
				)
				(justify left bottom mirror)
			)
		)
		(fp_text user "Author: Antmicro"
			(at -0.95 -4.169 90)
			(layer "B.Fab")
			(effects
				(font
					(size 0.7 0.7)
					(thickness 0.15)
				)
				(justify left bottom mirror)
			)
		)
		(fp_text user "${REFERENCE}"
			(at -0.95 -3.168 90)
			(layer "B.Fab")
			(effects
				(font
					(size 0.7 0.7)
					(thickness 0.15)
				)
				(justify left bottom mirror)
			)
		)
		(pad "1" smd roundrect
			(at -0.48 0 270)
			(size 0.59 0.64)
			(layers "B.Cu" "B.Mask" "B.Paste")
			(roundrect_rratio 0.25)
			(net 2 "+3V3")
			(pintype "passive")
		)
		(pad "2" smd roundrect
			(at 0.48 0 270)
			(size 0.59 0.64)
			(layers "B.Cu" "B.Mask" "B.Paste")
			(roundrect_rratio 0.25)
			(net 889 "/Recovery USB/USBC2_ID")
			(pintype "passive")
		)
	)
	(footprint "antmicro-footprints:Spacer_Drill3.7mm_H2.5mm_9774025151R"
		(locked yes)
		(layer "B.Cu")
		(at 159.46 129.51 90)
		(descr "Spacer M=3 h=2.5mm fi=5.1mm")
		(property "Reference" "H10"
			(at -3.49 -0.975 0)
			(layer "B.SilkS")
			(effects
				(font
					(size 0.7 0.7)
					(thickness 0.15)
				)
				(justify right top mirror)
			)
		)
		(property "Value" "Spacer_Drill3.7mm_H2.5mm_9774025151R"
			(at 0 -4 90)
			(layer "B.Fab")
			(effects
				(font
					(size 0.7 0.7)
					(thickness 0.15)
				)
				(justify right top mirror)
			)
		)
		(property "Datasheet" "https://www.we-online.com/components/products/datasheet/9774025151R.pdf"
			(at 0 0 90)
			(layer "B.Fab")
			(hide yes)
			(effects
				(font
					(size 1.27 1.27)
					(thickness 0.15)
				)
				(justify mirror)
			)
		)
		(property "Description" "Spacer, SMT, Non Stop, Steel, Swage Round, 5.1 mm x 2.5 mm, M2.5 Thread, WA-SMSI Series"
			(at 0 0 90)
			(layer "B.Fab")
			(hide yes)
			(effects
				(font
					(size 1.27 1.27)
					(thickness 0.15)
				)
				(justify mirror)
			)
		)
		(property "Manufacturer" "Würth Elektronik"
			(at 0 0 270)
			(unlocked yes)
			(layer "B.Fab")
			(hide yes)
			(effects
				(font
					(size 1 1)
					(thickness 0.15)
				)
				(justify mirror)
			)
		)
		(property "MPN" "9774025151R"
			(at 0 0 270)
			(unlocked yes)
			(layer "B.Fab")
			(hide yes)
			(effects
				(font
					(size 1 1)
					(thickness 0.15)
				)
				(justify mirror)
			)
		)
		(property "Author" "Antmicro"
			(at 0 0 270)
			(unlocked yes)
			(layer "B.Fab")
			(hide yes)
			(effects
				(font
					(size 1 1)
					(thickness 0.15)
				)
				(justify mirror)
			)
		)
		(property "License" "Apache-2.0"
			(at 0 0 270)
			(unlocked yes)
			(layer "B.Fab")
			(hide yes)
			(effects
				(font
					(size 1 1)
					(thickness 0.15)
				)
				(justify mirror)
			)
		)
		(sheetname "/M.2/")
		(sheetfile "m2.kicad_sch")
		(solder_paste_margin_ratio -1)
		(attr smd)
		(fp_circle
			(center 0 0)
			(end 3.05 0)
			(stroke
				(width 0.05)
				(type solid)
			)
			(fill no)
			(layer "B.CrtYd")
		)
		(fp_circle
			(center 0 0)
			(end 2.6 0)
			(stroke
				(width 0.15)
				(type solid)
			)
			(fill no)
			(layer "B.Fab")
		)
		(fp_text user "${REFERENCE}"
			(at -9.6 -6.5 90)
			(layer "B.Fab")
			(effects
				(font
					(size 0.7 0.7)
					(thickness 0.15)
				)
				(justify right top mirror)
			)
		)
		(fp_text user "Author: Antmicro"
			(at -9.6 -7.7 90)
			(layer "B.Fab")
			(effects
				(font
					(size 0.7 0.7)
					(thickness 0.15)
				)
				(justify right top mirror)
			)
		)
		(fp_text user "License: Apache-2.0"
			(at -9.6 -8.9 90)
			(layer "B.Fab")
			(effects
				(font
					(size 0.7 0.7)
					(thickness 0.15)
				)
				(justify right top mirror)
			)
		)
		(pad "" smd custom
			(at -1.7 -1.7)
			(size 0.62 0.62)
			(layers "B.Paste")
			(thermal_bridge_angle 90)
			(options
				(clearance outline)
				(anchor circle)
			)
			(primitives
				(gr_arc
					(start 1.266786 0.24747)
					(mid 0.285453 -0.29439)
					(end -0.250195 -1.279127)
					(width 0.2)
				)
				(gr_arc
					(start 1.259603 0.339191)
					(mid 0.218448 -0.232561)
					(end -0.34334 -1.279127)
					(width 0.2)
				)
				(gr_arc
					(start 1.255279 0.431435)
					(mid 0.152481 -0.169693)
					(end -0.436309 -1.279127)
					(width 0.2)
				)
				(gr_arc
					(start 1.253811 0.524161)
					(mid 0.087542 -0.105784)
					(end -0.529126 -1.279127)
					(width 0.2)
				)
				(gr_arc
					(start 1.275473 0.621136)
					(mid 0.0309 -0.033527)
					(end -0.621807 -1.279127)
					(width 0.2)
				)
				(gr_arc
					(start 1.263664 0.711602)
					(mid -0.037759 0.026651)
					(end -0.71437 -1.279127)
					(width 0.2)
				)
				(gr_arc
					(start 1.253435 0.802342)
					(mid -0.105837 0.087395)
					(end -0.806826 -1.279127)
					(width 0.2)
				)
				(gr_arc
					(start 1.267475 0.897258)
					(mid -0.165236 0.156885)
					(end -0.899187 -1.279127)
					(width 0.2)
				)
				(gr_arc
					(start 1.270645 0.990112)
					(mid -0.228522 0.222449)
					(end -0.991463 -1.279127)
					(width 0.2)
				)
				(gr_arc
					(start 1.266278 1.081674)
					(mid -0.294507 0.285313)
					(end -1.083663 -1.279127)
					(width 0.2)
				)
				(gr_line
					(start 1.279127 0.250195)
					(end 1.279127 1.083663)
					(width 0.2)
				)
				(gr_line
					(start -0.250195 -1.279127)
					(end -1.083663 -1.279127)
					(width 0.2)
				)
			)
		)
		(pad "" smd custom
			(at -1.7 1.7 90)
			(size 0.62 0.62)
			(layers "B.Paste")
			(thermal_bridge_angle 90)
			(options
				(clearance outline)
				(anchor circle)
			)
			(primitives
				(gr_arc
					(start 1.266786 0.24747)
					(mid 0.285453 -0.29439)
					(end -0.250195 -1.279127)
					(width 0.2)
				)
				(gr_arc
					(start 1.259603 0.339191)
					(mid 0.218448 -0.232561)
					(end -0.34334 -1.279127)
					(width 0.2)
				)
				(gr_arc
					(start 1.255279 0.431435)
					(mid 0.152481 -0.169693)
					(end -0.436309 -1.279127)
					(width 0.2)
				)
				(gr_arc
					(start 1.253811 0.524161)
					(mid 0.087542 -0.105784)
					(end -0.529126 -1.279127)
					(width 0.2)
				)
				(gr_arc
					(start 1.275473 0.621136)
					(mid 0.0309 -0.033527)
					(end -0.621807 -1.279127)
					(width 0.2)
				)
				(gr_arc
					(start 1.263664 0.711602)
					(mid -0.037759 0.026651)
					(end -0.71437 -1.279127)
					(width 0.2)
				)
				(gr_arc
					(start 1.253435 0.802342)
					(mid -0.105837 0.087395)
					(end -0.806826 -1.279127)
					(width 0.2)
				)
				(gr_arc
					(start 1.267475 0.897258)
					(mid -0.165236 0.156885)
					(end -0.899187 -1.279127)
					(width 0.2)
				)
				(gr_arc
					(start 1.270645 0.990112)
					(mid -0.228522 0.222449)
					(end -0.991463 -1.279127)
					(width 0.2)
				)
				(gr_arc
					(start 1.266278 1.081674)
					(mid -0.294507 0.285313)
					(end -1.083663 -1.279127)
					(width 0.2)
				)
				(gr_line
					(start 1.279127 0.250195)
					(end 1.279127 1.083663)
					(width 0.2)
				)
				(gr_line
					(start -0.250195 -1.279127)
					(end -1.083663 -1.279127)
					(width 0.2)
				)
			)
		)
		(pad "" smd custom
			(at 1.7 -1.7 270)
			(size 0.62 0.62)
			(layers "B.Paste")
			(thermal_bridge_angle 90)
			(options
				(clearance outline)
				(anchor circle)
			)
			(primitives
				(gr_arc
					(start 1.266786 0.24747)
					(mid 0.285453 -0.29439)
					(end -0.250195 -1.279127)
					(width 0.2)
				)
				(gr_arc
					(start 1.259603 0.339191)
					(mid 0.218448 -0.232561)
					(end -0.34334 -1.279127)
					(width 0.2)
				)
				(gr_arc
					(start 1.255279 0.431435)
					(mid 0.152481 -0.169693)
					(end -0.436309 -1.279127)
					(width 0.2)
				)
				(gr_arc
					(start 1.253811 0.524161)
					(mid 0.087542 -0.105784)
					(end -0.529126 -1.279127)
					(width 0.2)
				)
				(gr_arc
					(start 1.275473 0.621136)
					(mid 0.0309 -0.033527)
					(end -0.621807 -1.279127)
					(width 0.2)
				)
				(gr_arc
					(start 1.263664 0.711602)
					(mid -0.037759 0.026651)
					(end -0.71437 -1.279127)
					(width 0.2)
				)
				(gr_arc
					(start 1.253435 0.802342)
					(mid -0.105837 0.087395)
					(end -0.806826 -1.279127)
					(width 0.2)
				)
				(gr_arc
					(start 1.267475 0.897258)
					(mid -0.165236 0.156885)
					(end -0.899187 -1.279127)
					(width 0.2)
				)
				(gr_arc
					(start 1.270645 0.990112)
					(mid -0.228522 0.222449)
					(end -0.991463 -1.279127)
					(width 0.2)
				)
				(gr_arc
					(start 1.266278 1.081674)
					(mid -0.294507 0.285313)
					(end -1.083663 -1.279127)
					(width 0.2)
				)
				(gr_line
					(start 1.279127 0.250195)
					(end 1.279127 1.083663)
					(width 0.2)
				)
				(gr_line
					(start -0.250195 -1.279127)
					(end -1.083663 -1.279127)
					(width 0.2)
				)
			)
		)
		(pad "" smd custom
			(at 1.7 1.7 180)
			(size 0.62 0.62)
			(layers "B.Paste")
			(thermal_bridge_angle 90)
			(options
				(clearance outline)
				(anchor circle)
			)
			(primitives
				(gr_arc
					(start 1.266786 0.24747)
					(mid 0.285453 -0.29439)
					(end -0.250195 -1.279127)
					(width 0.2)
				)
				(gr_arc
					(start 1.259603 0.339191)
					(mid 0.218448 -0.232561)
					(end -0.34334 -1.279127)
					(width 0.2)
				)
				(gr_arc
					(start 1.255279 0.431435)
					(mid 0.152481 -0.169693)
					(end -0.436309 -1.279127)
					(width 0.2)
				)
				(gr_arc
					(start 1.253811 0.524161)
					(mid 0.087542 -0.105784)
					(end -0.529126 -1.279127)
					(width 0.2)
				)
				(gr_arc
					(start 1.275473 0.621136)
					(mid 0.0309 -0.033527)
					(end -0.621807 -1.279127)
					(width 0.2)
				)
				(gr_arc
					(start 1.263664 0.711602)
					(mid -0.037759 0.026651)
					(end -0.71437 -1.279127)
					(width 0.2)
				)
				(gr_arc
					(start 1.253435 0.802342)
					(mid -0.105837 0.087395)
					(end -0.806826 -1.279127)
					(width 0.2)
				)
				(gr_arc
					(start 1.267475 0.897258)
					(mid -0.165236 0.156885)
					(end -0.899187 -1.279127)
					(width 0.2)
				)
				(gr_arc
					(start 1.270645 0.990112)
					(mid -0.228522 0.222449)
					(end -0.991463 -1.279127)
					(width 0.2)
				)
				(gr_arc
					(start 1.266278 1.081674)
					(mid -0.294507 0.285313)
					(end -1.083663 -1.279127)
					(width 0.2)
				)
				(gr_line
					(start 1.279127 0.250195)
					(end 1.279127 1.083663)
					(width 0.2)
				)
				(gr_line
					(start -0.250195 -1.279127)
					(end -1.083663 -1.279127)
					(width 0.2)
				)
			)
		)
		(pad "1" thru_hole circle
			(at 0 0 90)
			(size 6 6)
			(drill 3.7)
			(layers "*.Cu" "*.Mask")
			(remove_unused_layers no)
			(net 1 "GND")
			(pintype "passive")
		)
	)
	(footprint "antmicro-footprints:C_0402_1005Metric"
		(layer "B.Cu")
		(at 115.82 70.6 180)
		(descr "Capacitor SMD 0402")
		(tags "capacitor SMD 0402")
		(property "Reference" "C14"
			(at -1.48 -1.5 0)
			(layer "B.SilkS")
			(effects
				(font
					(size 0.7 0.7)
					(thickness 0.15)
				)
				(justify left bottom mirror)
			)
		)
		(property "Value" "C_10u_0402"
			(at -1.022927 -2.155213 0)
			(layer "B.Fab")
			(effects
				(font
					(size 0.7 0.7)
					(thickness 0.15)
				)
				(justify left bottom mirror)
			)
		)
		(property "Datasheet" "https://www.yageo.com/en/Chart/Download/pdf/CC0402MRX5R5BB106"
			(at 0 0 0)
			(layer "B.Fab")
			(hide yes)
			(effects
				(font
					(size 1.27 1.27)
					(thickness 0.15)
				)
				(justify mirror)
			)
		)
		(property "Description" "SMD Multilayer Ceramic Capacitor, 10 µF, 6.3 V, 0402 [1005 Metric], ± 20%, X5R, CC Series"
			(at 0 0 0)
			(layer "B.Fab")
			(hide yes)
			(effects
				(font
					(size 1.27 1.27)
					(thickness 0.15)
				)
				(justify mirror)
			)
		)
		(property "MPN" "CC0402MRX5R5BB106"
			(at 0 0 180)
			(unlocked yes)
			(layer "B.Fab")
			(hide yes)
			(effects
				(font
					(size 1 1)
					(thickness 0.15)
				)
				(justify mirror)
			)
		)
		(property "Manufacturer" "YAGEO"
			(at 0 0 180)
			(unlocked yes)
			(layer "B.Fab")
			(hide yes)
			(effects
				(font
					(size 1 1)
					(thickness 0.15)
				)
				(justify mirror)
			)
		)
		(property "License" "Apache-2.0"
			(at 0 0 180)
			(unlocked yes)
			(layer "B.Fab")
			(hide yes)
			(effects
				(font
					(size 1 1)
					(thickness 0.15)
				)
				(justify mirror)
			)
		)
		(property "Author" "Antmicro"
			(at 0 0 180)
			(unlocked yes)
			(layer "B.Fab")
			(hide yes)
			(effects
				(font
					(size 1 1)
					(thickness 0.15)
				)
				(justify mirror)
			)
		)
		(property "Val" "10u"
			(at 0 0 180)
			(unlocked yes)
			(layer "B.Fab")
			(hide yes)
			(effects
				(font
					(size 1 1)
					(thickness 0.15)
				)
				(justify mirror)
			)
		)
		(property "Voltage" ""
			(at 0 0 180)
			(unlocked yes)
			(layer "B.Fab")
			(hide yes)
			(effects
				(font
					(size 1 1)
					(thickness 0.15)
				)
				(justify mirror)
			)
		)
		(property "Dielectric" "template_dielectric"
			(at 0 0 180)
			(unlocked yes)
			(layer "B.Fab")
			(hide yes)
			(effects
				(font
					(size 1 1)
					(thickness 0.15)
				)
				(justify mirror)
			)
		)
		(sheetname "/SoM_Power/")
		(sheetfile "som_power.kicad_sch")
		(attr smd)
		(fp_rect
			(start -0.925 0.47)
			(end 0.925 -0.47)
			(stroke
				(width 0.05)
				(type default)
			)
			(fill no)
			(layer "B.CrtYd")
		)
		(fp_line
			(start 0.504 0.25)
			(end 0.504 -0.248)
			(stroke
				(width 0.15)
				(type solid)
			)
			(layer "B.Fab")
		)
		(fp_line
			(start 0.504 -0.248)
			(end -0.494 -0.248)
			(stroke
				(width 0.15)
				(type solid)
			)
			(layer "B.Fab")
		)
		(fp_line
			(start -0.494 0.25)
			(end 0.504 0.25)
			(stroke
				(width 0.15)
				(type solid)
			)
			(layer "B.Fab")
		)
		(fp_line
			(start -0.494 -0.248)
			(end -0.494 0.25)
			(stroke
				(width 0.15)
				(type solid)
			)
			(layer "B.Fab")
		)
		(fp_text user "License: Apache-2.0"
			(at -0.939 -5.799 0)
			(layer "B.Fab")
			(effects
				(font
					(size 0.7 0.7)
					(thickness 0.15)
				)
				(justify left bottom mirror)
			)
		)
		(fp_text user "Author: Antmicro"
			(at -0.939 -3.399 0)
			(layer "B.Fab")
			(effects
				(font
					(size 0.7 0.7)
					(thickness 0.15)
				)
				(justify left bottom mirror)
			)
		)
		(fp_text user "${REFERENCE}"
			(at -0.939 -4.599 0)
			(layer "B.Fab")
			(effects
				(font
					(size 0.7 0.7)
					(thickness 0.15)
				)
				(justify left bottom mirror)
			)
		)
		(pad "1" smd roundrect
			(at -0.48 0 180)
			(size 0.59 0.64)
			(layers "B.Cu" "B.Mask" "B.Paste")
			(roundrect_rratio 0.25)
			(net 1 "GND")
			(pintype "passive")
		)
		(pad "2" smd roundrect
			(at 0.48 0 180)
			(size 0.59 0.64)
			(layers "B.Cu" "B.Mask" "B.Paste")
			(roundrect_rratio 0.25)
			(net 213 "+5V_SOM")
			(pintype "passive")
		)
	)
	(footprint "antmicro-footprints:R_0402_1005Metric"
		(layer "B.Cu")
		(at 65 63.58 90)
		(descr "Resistor SMD 0402")
		(tags "resistor SMD 0402")
		(property "Reference" "R161"
			(at 0.78 -0.4 90)
			(layer "B.SilkS")
			(effects
				(font
					(size 0.7 0.7)
					(thickness 0.15)
				)
				(justify right top mirror)
			)
		)
		(property "Value" "R_0R_0402"
			(at -1.011843 -1.772046 90)
			(layer "B.Fab")
			(effects
				(font
					(size 0.7 0.7)
					(thickness 0.15)
				)
				(justify right top mirror)
			)
		)
		(property "Datasheet" "https://industrial.panasonic.com/cdbs/www-data/pdf/RDA0000/AOA0000C301.pdf"
			(at 0 0 90)
			(layer "B.Fab")
			(hide yes)
			(effects
				(font
					(size 1.27 1.27)
					(thickness 0.15)
				)
				(justify mirror)
			)
		)
		(property "Description" "SMD Chip Resistor, Jumper, 0 ohm, 100 mW, 0402 [1005 Metric], Thick Film, General Purpose"
			(at 0 0 90)
			(layer "B.Fab")
			(hide yes)
			(effects
				(font
					(size 1.27 1.27)
					(thickness 0.15)
				)
				(justify mirror)
			)
		)
		(property "Manufacturer" "Panasonic"
			(at 0 0 270)
			(unlocked yes)
			(layer "B.Fab")
			(hide yes)
			(effects
				(font
					(size 1 1)
					(thickness 0.15)
				)
				(justify mirror)
			)
		)
		(property "MPN" "ERJ2GE0R00X"
			(at 0 0 270)
			(unlocked yes)
			(layer "B.Fab")
			(hide yes)
			(effects
				(font
					(size 1 1)
					(thickness 0.15)
				)
				(justify mirror)
			)
		)
		(property "Val" "0R"
			(at 0 0 270)
			(unlocked yes)
			(layer "B.Fab")
			(hide yes)
			(effects
				(font
					(size 1 1)
					(thickness 0.15)
				)
				(justify mirror)
			)
		)
		(property "License" "Apache-2.0"
			(at 0 0 270)
			(unlocked yes)
			(layer "B.Fab")
			(hide yes)
			(effects
				(font
					(size 1 1)
					(thickness 0.15)
				)
				(justify mirror)
			)
		)
		(property "Author" "Antmicro"
			(at 0 0 270)
			(unlocked yes)
			(layer "B.Fab")
			(hide yes)
			(effects
				(font
					(size 1 1)
					(thickness 0.15)
				)
				(justify mirror)
			)
		)
		(property "Tolerance" "~"
			(at 0 0 270)
			(unlocked yes)
			(layer "B.Fab")
			(hide yes)
			(effects
				(font
					(size 1 1)
					(thickness 0.15)
				)
				(justify mirror)
			)
		)
		(property "Current" "1A"
			(at 0 0 270)
			(unlocked yes)
			(layer "B.Fab")
			(hide yes)
			(effects
				(font
					(size 1 1)
					(thickness 0.15)
				)
				(justify mirror)
			)
		)
		(sheetname "/CSI/")
		(sheetfile "csi.kicad_sch")
		(attr smd exclude_from_pos_files exclude_from_bom dnp)
		(fp_poly
			(pts
				(xy -0.925 0.47) (xy -0.925 -0.47) (xy 0.925 -0.47) (xy 0.925 0.47)
			)
			(stroke
				(width 0.05)
				(type default)
			)
			(fill no)
			(layer "B.CrtYd")
		)
		(fp_poly
			(pts
				(xy -0.5 0.25) (xy -0.5 -0.25) (xy 0.5 -0.25) (xy 0.5 0.25)
			)
			(stroke
				(width 0.15)
				(type solid)
			)
			(fill no)
			(layer "B.Fab")
		)
		(fp_text user "Author: Antmicro"
			(at -0.95 -4.169 90)
			(layer "B.Fab")
			(effects
				(font
					(size 0.7 0.7)
					(thickness 0.15)
				)
				(justify right top mirror)
			)
		)
		(fp_text user "License: Apache-2.0"
			(at -0.949999 -5.169 90)
			(layer "B.Fab")
			(effects
				(font
					(size 0.7 0.7)
					(thickness 0.15)
				)
				(justify right top mirror)
			)
		)
		(fp_text user "${REFERENCE}"
			(at -0.95 -3.168 90)
			(layer "B.Fab")
			(effects
				(font
					(size 0.7 0.7)
					(thickness 0.15)
				)
				(justify right top mirror)
			)
		)
		(pad "1" smd roundrect
			(at -0.48 0 90)
			(size 0.59 0.64)
			(layers "B.Cu" "B.Mask" "B.Paste")
			(roundrect_rratio 0.25)
			(net 979 "/CSI/CSIA_I2C_VCC")
			(pintype "passive")
		)
		(pad "2" smd roundrect
			(at 0.48 0 90)
			(size 0.59 0.64)
			(layers "B.Cu" "B.Mask" "B.Paste")
			(roundrect_rratio 0.25)
			(net 11 "+1V8")
			(pintype "passive")
		)
	)
	(footprint "antmicro-footprints:R_0402_1005Metric"
		(layer "B.Cu")
		(at 216 89.2 180)
		(descr "Resistor SMD 0402")
		(tags "resistor SMD 0402")
		(property "Reference" "R141"
			(at -7.6 -2.4 0)
			(layer "B.SilkS")
			(effects
				(font
					(size 0.7 0.7)
					(thickness 0.15)
				)
				(justify left bottom mirror)
			)
		)
		(property "Value" "R_1k_0402"
			(at -1.011843 -1.772047 0)
			(layer "B.Fab")
			(effects
				(font
					(size 0.7 0.7)
					(thickness 0.15)
				)
				(justify left bottom mirror)
			)
		)
		(property "Datasheet" "https://www.bourns.com/docs/product-datasheets/cr.pdf"
			(at 0 0 0)
			(layer "B.Fab")
			(hide yes)
			(effects
				(font
					(size 1.27 1.27)
					(thickness 0.15)
				)
				(justify mirror)
			)
		)
		(property "Description" "SMD Chip Resistor, 1 kohm, ± 1%, 63 mW, 0402 [1005 Metric], Thick Film, General Purpose"
			(at 0 0 0)
			(layer "B.Fab")
			(hide yes)
			(effects
				(font
					(size 1.27 1.27)
					(thickness 0.15)
				)
				(justify mirror)
			)
		)
		(property "Manufacturer" "Bourns"
			(at 0 0 0)
			(unlocked yes)
			(layer "B.Fab")
			(hide yes)
			(effects
				(font
					(size 1 1)
					(thickness 0.15)
				)
				(justify mirror)
			)
		)
		(property "MPN" "CR0402-FX-1001GLF"
			(at 0 0 0)
			(unlocked yes)
			(layer "B.Fab")
			(hide yes)
			(effects
				(font
					(size 1 1)
					(thickness 0.15)
				)
				(justify mirror)
			)
		)
		(property "Val" "1k"
			(at 0 0 0)
			(unlocked yes)
			(layer "B.Fab")
			(hide yes)
			(effects
				(font
					(size 1 1)
					(thickness 0.15)
				)
				(justify mirror)
			)
		)
		(property "License" "Apache-2.0"
			(at 0 0 0)
			(unlocked yes)
			(layer "B.Fab")
			(hide yes)
			(effects
				(font
					(size 1 1)
					(thickness 0.15)
				)
				(justify mirror)
			)
		)
		(property "Author" "Antmicro"
			(at 0 0 0)
			(unlocked yes)
			(layer "B.Fab")
			(hide yes)
			(effects
				(font
					(size 1 1)
					(thickness 0.15)
				)
				(justify mirror)
			)
		)
		(property "Tolerance" "1%"
			(at 0 0 0)
			(unlocked yes)
			(layer "B.Fab")
			(hide yes)
			(effects
				(font
					(size 1 1)
					(thickness 0.15)
				)
				(justify mirror)
			)
		)
		(sheetname "/USB DP Alt mode/")
		(sheetfile "usb_dp.kicad_sch")
		(attr smd)
		(fp_rect
			(start -0.925 0.47)
			(end 0.925 -0.47)
			(stroke
				(width 0.05)
				(type default)
			)
			(fill no)
			(layer "B.CrtYd")
		)
		(fp_rect
			(start -0.5 0.25)
			(end 0.5 -0.25)
			(stroke
				(width 0.15)
				(type solid)
			)
			(fill no)
			(layer "B.Fab")
		)
		(fp_text user "Author: Antmicro"
			(at -0.95 -4.169 0)
			(layer "B.Fab")
			(effects
				(font
					(size 0.7 0.7)
					(thickness 0.15)
				)
				(justify left bottom mirror)
			)
		)
		(fp_text user "License: Apache-2.0"
			(at -0.95 -5.169 0)
			(layer "B.Fab")
			(effects
				(font
					(size 0.7 0.7)
					(thickness 0.15)
				)
				(justify left bottom mirror)
			)
		)
		(fp_text user "${REFERENCE}"
			(at -0.95 -3.168 0)
			(layer "B.Fab")
			(effects
				(font
					(size 0.7 0.7)
					(thickness 0.15)
				)
				(justify left bottom mirror)
			)
		)
		(pad "1" smd roundrect
			(at -0.48 0 180)
			(size 0.59 0.64)
			(layers "B.Cu" "B.Mask" "B.Paste")
			(roundrect_rratio 0.25)
			(net 969 "/USB DP Alt mode/USBC1_EQ1")
			(pintype "passive")
		)
		(pad "2" smd roundrect
			(at 0.48 0 180)
			(size 0.59 0.64)
			(layers "B.Cu" "B.Mask" "B.Paste")
			(roundrect_rratio 0.25)
			(net 1 "GND")
			(pintype "passive")
		)
	)
	(footprint "antmicro-footprints:R_0402_1005Metric"
		(layer "B.Cu")
		(at 218.714999 86.718 -90)
		(descr "Resistor SMD 0402")
		(tags "resistor SMD 0402")
		(property "Reference" "R132"
			(at -0.918 -2.485001 90)
			(layer "B.SilkS")
			(effects
				(font
					(size 0.7 0.7)
					(thickness 0.15)
				)
				(justify left bottom mirror)
			)
		)
		(property "Value" "R_1k_0402"
			(at -1.011843 -1.772046 90)
			(layer "B.Fab")
			(effects
				(font
					(size 0.7 0.7)
					(thickness 0.15)
				)
				(justify left bottom mirror)
			)
		)
		(property "Datasheet" "https://www.bourns.com/docs/product-datasheets/cr.pdf"
			(at 0 0 90)
			(layer "B.Fab")
			(hide yes)
			(effects
				(font
					(size 1.27 1.27)
					(thickness 0.15)
				)
				(justify mirror)
			)
		)
		(property "Description" "SMD Chip Resistor, 1 kohm, ± 1%, 63 mW, 0402 [1005 Metric], Thick Film, General Purpose"
			(at 0 0 90)
			(layer "B.Fab")
			(hide yes)
			(effects
				(font
					(size 1.27 1.27)
					(thickness 0.15)
				)
				(justify mirror)
			)
		)
		(property "Manufacturer" "Bourns"
			(at 0 0 90)
			(unlocked yes)
			(layer "B.Fab")
			(hide yes)
			(effects
				(font
					(size 1 1)
					(thickness 0.15)
				)
				(justify mirror)
			)
		)
		(property "MPN" "CR0402-FX-1001GLF"
			(at 0 0 90)
			(unlocked yes)
			(layer "B.Fab")
			(hide yes)
			(effects
				(font
					(size 1 1)
					(thickness 0.15)
				)
				(justify mirror)
			)
		)
		(property "Val" "1k"
			(at 0 0 90)
			(unlocked yes)
			(layer "B.Fab")
			(hide yes)
			(effects
				(font
					(size 1 1)
					(thickness 0.15)
				)
				(justify mirror)
			)
		)
		(property "License" "Apache-2.0"
			(at 0 0 90)
			(unlocked yes)
			(layer "B.Fab")
			(hide yes)
			(effects
				(font
					(size 1 1)
					(thickness 0.15)
				)
				(justify mirror)
			)
		)
		(property "Author" "Antmicro"
			(at 0 0 90)
			(unlocked yes)
			(layer "B.Fab")
			(hide yes)
			(effects
				(font
					(size 1 1)
					(thickness 0.15)
				)
				(justify mirror)
			)
		)
		(property "Tolerance" "1%"
			(at 0 0 90)
			(unlocked yes)
			(layer "B.Fab")
			(hide yes)
			(effects
				(font
					(size 1 1)
					(thickness 0.15)
				)
				(justify mirror)
			)
		)
		(sheetname "/USB DP Alt mode/")
		(sheetfile "usb_dp.kicad_sch")
		(attr smd exclude_from_pos_files exclude_from_bom dnp)
		(fp_poly
			(pts
				(xy -0.925 0.47) (xy 0.925 0.47) (xy 0.925 -0.47) (xy -0.925 -0.47)
			)
			(stroke
				(width 0.05)
				(type default)
			)
			(fill no)
			(layer "B.CrtYd")
		)
		(fp_poly
			(pts
				(xy -0.5 0.25) (xy 0.5 0.25) (xy 0.5 -0.25) (xy -0.5 -0.25)
			)
			(stroke
				(width 0.15)
				(type solid)
			)
			(fill no)
			(layer "B.Fab")
		)
		(fp_text user "${REFERENCE}"
			(at -0.95 -3.168 90)
			(layer "B.Fab")
			(effects
				(font
					(size 0.7 0.7)
					(thickness 0.15)
				)
				(justify left bottom mirror)
			)
		)
		(fp_text user "Author: Antmicro"
			(at -0.95 -4.169 90)
			(layer "B.Fab")
			(effects
				(font
					(size 0.7 0.7)
					(thickness 0.15)
				)
				(justify left bottom mirror)
			)
		)
		(fp_text user "License: Apache-2.0"
			(at -0.949999 -5.169 90)
			(layer "B.Fab")
			(effects
				(font
					(size 0.7 0.7)
					(thickness 0.15)
				)
				(justify left bottom mirror)
			)
		)
		(pad "1" smd roundrect
			(at -0.48 0 270)
			(size 0.59 0.64)
			(layers "B.Cu" "B.Mask" "B.Paste")
			(roundrect_rratio 0.25)
			(net 965 "/USB DP Alt mode/USBC1_SSEQ1")
			(pintype "passive")
		)
		(pad "2" smd roundrect
			(at 0.48 0 270)
			(size 0.59 0.64)
			(layers "B.Cu" "B.Mask" "B.Paste")
			(roundrect_rratio 0.25)
			(net 2 "+3V3")
			(pintype "passive")
		)
	)
	(footprint "antmicro-footprints:R_0402_1005Metric"
		(layer "B.Cu")
		(at 67.16 63.58 90)
		(descr "Resistor SMD 0402")
		(tags "resistor SMD 0402")
		(property "Reference" "R169"
			(at 0.78 -0.31 90)
			(layer "B.SilkS")
			(effects
				(font
					(size 0.7 0.7)
					(thickness 0.15)
				)
				(justify right top mirror)
			)
		)
		(property "Value" "R_0R_0402"
			(at -1.011843 -1.772046 90)
			(layer "B.Fab")
			(effects
				(font
					(size 0.7 0.7)
					(thickness 0.15)
				)
				(justify right top mirror)
			)
		)
		(property "Datasheet" "https://industrial.panasonic.com/cdbs/www-data/pdf/RDA0000/AOA0000C301.pdf"
			(at 0 0 90)
			(layer "B.Fab")
			(hide yes)
			(effects
				(font
					(size 1.27 1.27)
					(thickness 0.15)
				)
				(justify mirror)
			)
		)
		(property "Description" "SMD Chip Resistor, Jumper, 0 ohm, 100 mW, 0402 [1005 Metric], Thick Film, General Purpose"
			(at 0 0 90)
			(layer "B.Fab")
			(hide yes)
			(effects
				(font
					(size 1.27 1.27)
					(thickness 0.15)
				)
				(justify mirror)
			)
		)
		(property "Manufacturer" "Panasonic"
			(at 0 0 270)
			(unlocked yes)
			(layer "B.Fab")
			(hide yes)
			(effects
				(font
					(size 1 1)
					(thickness 0.15)
				)
				(justify mirror)
			)
		)
		(property "MPN" "ERJ2GE0R00X"
			(at 0 0 270)
			(unlocked yes)
			(layer "B.Fab")
			(hide yes)
			(effects
				(font
					(size 1 1)
					(thickness 0.15)
				)
				(justify mirror)
			)
		)
		(property "Val" "0R"
			(at 0 0 270)
			(unlocked yes)
			(layer "B.Fab")
			(hide yes)
			(effects
				(font
					(size 1 1)
					(thickness 0.15)
				)
				(justify mirror)
			)
		)
		(property "License" "Apache-2.0"
			(at 0 0 270)
			(unlocked yes)
			(layer "B.Fab")
			(hide yes)
			(effects
				(font
					(size 1 1)
					(thickness 0.15)
				)
				(justify mirror)
			)
		)
		(property "Author" "Antmicro"
			(at 0 0 270)
			(unlocked yes)
			(layer "B.Fab")
			(hide yes)
			(effects
				(font
					(size 1 1)
					(thickness 0.15)
				)
				(justify mirror)
			)
		)
		(property "Tolerance" "~"
			(at 0 0 270)
			(unlocked yes)
			(layer "B.Fab")
			(hide yes)
			(effects
				(font
					(size 1 1)
					(thickness 0.15)
				)
				(justify mirror)
			)
		)
		(property "Current" "1A"
			(at 0 0 270)
			(unlocked yes)
			(layer "B.Fab")
			(hide yes)
			(effects
				(font
					(size 1 1)
					(thickness 0.15)
				)
				(justify mirror)
			)
		)
		(sheetname "/CSI/")
		(sheetfile "csi.kicad_sch")
		(attr smd)
		(fp_poly
			(pts
				(xy -0.925 0.47) (xy -0.925 -0.47) (xy 0.925 -0.47) (xy 0.925 0.47)
			)
			(stroke
				(width 0.05)
				(type default)
			)
			(fill no)
			(layer "B.CrtYd")
		)
		(fp_poly
			(pts
				(xy -0.5 0.25) (xy -0.5 -0.25) (xy 0.5 -0.25) (xy 0.5 0.25)
			)
			(stroke
				(width 0.15)
				(type solid)
			)
			(fill no)
			(layer "B.Fab")
		)
		(fp_text user "License: Apache-2.0"
			(at -0.949999 -5.169 90)
			(layer "B.Fab")
			(effects
				(font
					(size 0.7 0.7)
					(thickness 0.15)
				)
				(justify right top mirror)
			)
		)
		(fp_text user "Author: Antmicro"
			(at -0.95 -4.169 90)
			(layer "B.Fab")
			(effects
				(font
					(size 0.7 0.7)
					(thickness 0.15)
				)
				(justify right top mirror)
			)
		)
		(fp_text user "${REFERENCE}"
			(at -0.95 -3.168 90)
			(layer "B.Fab")
			(effects
				(font
					(size 0.7 0.7)
					(thickness 0.15)
				)
				(justify right top mirror)
			)
		)
		(pad "1" smd roundrect
			(at -0.48 0 90)
			(size 0.59 0.64)
			(layers "B.Cu" "B.Mask" "B.Paste")
			(roundrect_rratio 0.25)
			(net 990 "/CSI/CSIB_I2C_VCC")
			(pintype "passive")
		)
		(pad "2" smd roundrect
			(at 0.48 0 90)
			(size 0.59 0.64)
			(layers "B.Cu" "B.Mask" "B.Paste")
			(roundrect_rratio 0.25)
			(net 2 "+3V3")
			(pintype "passive")
		)
	)
	(footprint "antmicro-footprints:TP_SMD_0.75mm"
		(layer "B.Cu")
		(at 217.39 92.322 -90)
		(property "Reference" "TP18"
			(at 0.44 -3.3 0)
			(layer "B.SilkS")
			(effects
				(font
					(size 0.7 0.7)
					(thickness 0.15)
				)
				(justify left bottom mirror)
			)
		)
		(property "Value" "TP_0.75mm_SMD"
			(at 0 -1.2 90)
			(layer "B.Fab")
			(effects
				(font
					(size 0.7 0.7)
					(thickness 0.15)
				)
				(justify left bottom mirror)
			)
		)
		(property "Description" "SMT test point"
			(at 0 0 90)
			(layer "B.Fab")
			(hide yes)
			(effects
				(font
					(size 1.27 1.27)
					(thickness 0.15)
				)
				(justify mirror)
			)
		)
		(property "MPN" ""
			(at 0 0 90)
			(unlocked yes)
			(layer "B.Fab")
			(hide yes)
			(effects
				(font
					(size 1 1)
					(thickness 0.15)
				)
				(justify mirror)
			)
		)
		(property "Manufacturer" ""
			(at 0 0 90)
			(unlocked yes)
			(layer "B.Fab")
			(hide yes)
			(effects
				(font
					(size 1 1)
					(thickness 0.15)
				)
				(justify mirror)
			)
		)
		(property "Author" "Antmicro"
			(at 0 0 90)
			(unlocked yes)
			(layer "B.Fab")
			(hide yes)
			(effects
				(font
					(size 1 1)
					(thickness 0.15)
				)
				(justify mirror)
			)
		)
		(property "License" "Apache-2.0"
			(at 0 0 90)
			(unlocked yes)
			(layer "B.Fab")
			(hide yes)
			(effects
				(font
					(size 1 1)
					(thickness 0.15)
				)
				(justify mirror)
			)
		)
		(sheetname "/USB DP Alt mode/")
		(sheetfile "usb_dp.kicad_sch")
		(attr exclude_from_pos_files exclude_from_bom)
		(fp_circle
			(center 0 0)
			(end 0.475 0)
			(stroke
				(width 0.05)
				(type default)
			)
			(fill no)
			(layer "B.CrtYd")
		)
		(fp_text user "License: Apache-2.0"
			(at -0.4 -5.101 90)
			(layer "B.Fab")
			(effects
				(font
					(size 0.7 0.7)
					(thickness 0.15)
				)
				(justify left bottom mirror)
			)
		)
		(fp_text user "Author: Antmicro"
			(at -0.4 -3.901 90)
			(layer "B.Fab")
			(effects
				(font
					(size 0.7 0.7)
					(thickness 0.15)
				)
				(justify left bottom mirror)
			)
		)
		(fp_text user "${REFERENCE}"
			(at -0.4 -2.7 90)
			(layer "B.Fab")
			(effects
				(font
					(size 0.7 0.7)
					(thickness 0.15)
				)
				(justify left bottom mirror)
			)
		)
		(pad "1" smd circle
			(at 0 -0.01 270)
			(size 0.75 0.75)
			(layers "B.Cu" "B.Mask")
			(net 1044 "Net-(U33-CAD_SNK{slash}RSVD1)")
			(pinfunction "1")
			(pintype "passive")
		)
	)
	(footprint "antmicro-footprints:C_0402_1005Metric"
		(layer "B.Cu")
		(at 197.626 139.8)
		(descr "Capacitor SMD 0402")
		(tags "capacitor SMD 0402")
		(property "Reference" "C176"
			(at -1.3 0.7 0)
			(layer "B.SilkS")
			(effects
				(font
					(size 0.7 0.7)
					(thickness 0.15)
				)
				(justify right top mirror)
			)
		)
		(property "Value" "C_100n_0402"
			(at -1.022927 -2.155213 0)
			(layer "B.Fab")
			(effects
				(font
					(size 0.7 0.7)
					(thickness 0.15)
				)
				(justify right top mirror)
			)
		)
		(property "Datasheet" "https://www.murata.com/products/productdetail?partno=GRM155R61H104KE14%23"
			(at 0 0 0)
			(layer "B.Fab")
			(hide yes)
			(effects
				(font
					(size 1.27 1.27)
					(thickness 0.15)
				)
				(justify mirror)
			)
		)
		(property "Description" "SMD Multilayer Ceramic Capacitor, 0.1 µF, 50 V, 0402 [1005 Metric], ± 10%, X5R, GRM Series"
			(at 0 0 0)
			(layer "B.Fab")
			(hide yes)
			(effects
				(font
					(size 1.27 1.27)
					(thickness 0.15)
				)
				(justify mirror)
			)
		)
		(property "MPN" "GRM155R61H104KE14D"
			(at 0 0 180)
			(unlocked yes)
			(layer "B.Fab")
			(hide yes)
			(effects
				(font
					(size 1 1)
					(thickness 0.15)
				)
				(justify mirror)
			)
		)
		(property "Manufacturer" "Murata"
			(at 0 0 180)
			(unlocked yes)
			(layer "B.Fab")
			(hide yes)
			(effects
				(font
					(size 1 1)
					(thickness 0.15)
				)
				(justify mirror)
			)
		)
		(property "License" "Apache-2.0"
			(at 0 0 180)
			(unlocked yes)
			(layer "B.Fab")
			(hide yes)
			(effects
				(font
					(size 1 1)
					(thickness 0.15)
				)
				(justify mirror)
			)
		)
		(property "Author" "Antmicro"
			(at 0 0 180)
			(unlocked yes)
			(layer "B.Fab")
			(hide yes)
			(effects
				(font
					(size 1 1)
					(thickness 0.15)
				)
				(justify mirror)
			)
		)
		(property "Val" "100n"
			(at 0 0 180)
			(unlocked yes)
			(layer "B.Fab")
			(hide yes)
			(effects
				(font
					(size 1 1)
					(thickness 0.15)
				)
				(justify mirror)
			)
		)
		(property "Voltage" "50V"
			(at 0 0 180)
			(unlocked yes)
			(layer "B.Fab")
			(hide yes)
			(effects
				(font
					(size 1 1)
					(thickness 0.15)
				)
				(justify mirror)
			)
		)
		(property "Dielectric" "X5R"
			(at 0 0 180)
			(unlocked yes)
			(layer "B.Fab")
			(hide yes)
			(effects
				(font
					(size 1 1)
					(thickness 0.15)
				)
				(justify mirror)
			)
		)
		(sheetname "/SFP/")
		(sheetfile "sfp.kicad_sch")
		(attr smd)
		(fp_rect
			(start -0.925 0.47)
			(end 0.925 -0.47)
			(stroke
				(width 0.05)
				(type default)
			)
			(fill no)
			(layer "B.CrtYd")
		)
		(fp_line
			(start -0.494 -0.248)
			(end -0.494 0.25)
			(stroke
				(width 0.15)
				(type solid)
			)
			(layer "B.Fab")
		)
		(fp_line
			(start -0.494 0.25)
			(end 0.504 0.25)
			(stroke
				(width 0.15)
				(type solid)
			)
			(layer "B.Fab")
		)
		(fp_line
			(start 0.504 -0.248)
			(end -0.494 -0.248)
			(stroke
				(width 0.15)
				(type solid)
			)
			(layer "B.Fab")
		)
		(fp_line
			(start 0.504 0.25)
			(end 0.504 -0.248)
			(stroke
				(width 0.15)
				(type solid)
			)
			(layer "B.Fab")
		)
		(fp_text user "License: Apache-2.0"
			(at -0.939 -5.799 0)
			(layer "B.Fab")
			(effects
				(font
					(size 0.7 0.7)
					(thickness 0.15)
				)
				(justify right top mirror)
			)
		)
		(fp_text user "Author: Antmicro"
			(at -0.939 -3.399 0)
			(layer "B.Fab")
			(effects
				(font
					(size 0.7 0.7)
					(thickness 0.15)
				)
				(justify right top mirror)
			)
		)
		(fp_text user "${REFERENCE}"
			(at -0.939 -4.599 0)
			(layer "B.Fab")
			(effects
				(font
					(size 0.7 0.7)
					(thickness 0.15)
				)
				(justify right top mirror)
			)
		)
		(pad "1" smd roundrect
			(at -0.48 0)
			(size 0.59 0.64)
			(layers "B.Cu" "B.Mask" "B.Paste")
			(roundrect_rratio 0.25)
			(net 1 "GND")
			(pintype "passive")
		)
		(pad "2" smd roundrect
			(at 0.48 0)
			(size 0.59 0.64)
			(layers "B.Cu" "B.Mask" "B.Paste")
			(roundrect_rratio 0.25)
			(net 379 "/SFP/SH")
			(pintype "passive")
		)
	)
	(footprint "antmicro-footprints:TP_SMD_0.75mm"
		(layer "B.Cu")
		(at 155.5 110 -90)
		(property "Reference" "TP88"
			(at 0 0.6 90)
			(layer "B.SilkS")
			(effects
				(font
					(size 0.7 0.7)
					(thickness 0.15)
				)
				(justify left bottom mirror)
			)
		)
		(property "Value" "TP_0.75mm_SMD"
			(at 0 -1.2 90)
			(layer "B.Fab")
			(effects
				(font
					(size 0.7 0.7)
					(thickness 0.15)
				)
				(justify left bottom mirror)
			)
		)
		(property "Description" "SMT test point"
			(at 0 0 90)
			(layer "B.Fab")
			(hide yes)
			(effects
				(font
					(size 1.27 1.27)
					(thickness 0.15)
				)
				(justify mirror)
			)
		)
		(property "MPN" ""
			(at 0 0 90)
			(unlocked yes)
			(layer "B.Fab")
			(hide yes)
			(effects
				(font
					(size 1 1)
					(thickness 0.15)
				)
				(justify mirror)
			)
		)
		(property "Manufacturer" ""
			(at 0 0 90)
			(unlocked yes)
			(layer "B.Fab")
			(hide yes)
			(effects
				(font
					(size 1 1)
					(thickness 0.15)
				)
				(justify mirror)
			)
		)
		(property "Author" "Antmicro"
			(at 0 0 90)
			(unlocked yes)
			(layer "B.Fab")
			(hide yes)
			(effects
				(font
					(size 1 1)
					(thickness 0.15)
				)
				(justify mirror)
			)
		)
		(property "License" "Apache-2.0"
			(at 0 0 90)
			(unlocked yes)
			(layer "B.Fab")
			(hide yes)
			(effects
				(font
					(size 1 1)
					(thickness 0.15)
				)
				(justify mirror)
			)
		)
		(sheetname "/Peripherals/")
		(sheetfile "peripherals.kicad_sch")
		(attr exclude_from_pos_files exclude_from_bom)
		(fp_circle
			(center 0 0)
			(end 0.475 0)
			(stroke
				(width 0.05)
				(type default)
			)
			(fill no)
			(layer "B.CrtYd")
		)
		(fp_text user "${REFERENCE}"
			(at -0.4 -2.7 90)
			(layer "B.Fab")
			(effects
				(font
					(size 0.7 0.7)
					(thickness 0.15)
				)
				(justify left bottom mirror)
			)
		)
		(fp_text user "Author: Antmicro"
			(at -0.4 -3.901 90)
			(layer "B.Fab")
			(effects
				(font
					(size 0.7 0.7)
					(thickness 0.15)
				)
				(justify left bottom mirror)
			)
		)
		(fp_text user "License: Apache-2.0"
			(at -0.4 -5.101 90)
			(layer "B.Fab")
			(effects
				(font
					(size 0.7 0.7)
					(thickness 0.15)
				)
				(justify left bottom mirror)
			)
		)
		(pad "1" smd circle
			(at 0 0 270)
			(size 0.75 0.75)
			(layers "B.Cu" "B.Mask")
			(net 853 "/I2C_{SYS}.SCL")
			(pinfunction "1")
			(pintype "passive")
		)
	)
	(footprint "antmicro-footprints:R_0402_1005Metric"
		(layer "B.Cu")
		(at 62.2 66.5 -90)
		(descr "Resistor SMD 0402")
		(tags "resistor SMD 0402")
		(property "Reference" "R390"
			(at -9.7 0 90)
			(layer "B.SilkS")
			(effects
				(font
					(size 0.7 0.7)
					(thickness 0.15)
				)
				(justify left bottom mirror)
			)
		)
		(property "Value" "R_2k2_0402"
			(at -1.011843 -1.772047 90)
			(layer "B.Fab")
			(effects
				(font
					(size 0.7 0.7)
					(thickness 0.15)
				)
				(justify left bottom mirror)
			)
		)
		(property "Datasheet" "https://www.bourns.com/docs/product-datasheets/cr.pdf"
			(at 0 0 90)
			(layer "B.Fab")
			(hide yes)
			(effects
				(font
					(size 1.27 1.27)
					(thickness 0.15)
				)
				(justify mirror)
			)
		)
		(property "Description" "SMD Chip Resistor, 2.2 kohm, ± 1%, 62.5 mW, 0402 [1005 Metric], Thick Film, General Purpose"
			(at 0 0 90)
			(layer "B.Fab")
			(hide yes)
			(effects
				(font
					(size 1.27 1.27)
					(thickness 0.15)
				)
				(justify mirror)
			)
		)
		(property "MPN" "CR0402-FX-2201GLF"
			(at 0 0 90)
			(unlocked yes)
			(layer "B.Fab")
			(hide yes)
			(effects
				(font
					(size 1 1)
					(thickness 0.15)
				)
				(justify mirror)
			)
		)
		(property "Manufacturer" "Bourns"
			(at 0 0 90)
			(unlocked yes)
			(layer "B.Fab")
			(hide yes)
			(effects
				(font
					(size 1 1)
					(thickness 0.15)
				)
				(justify mirror)
			)
		)
		(property "License" "Apache-2.0"
			(at 0 0 90)
			(unlocked yes)
			(layer "B.Fab")
			(hide yes)
			(effects
				(font
					(size 1 1)
					(thickness 0.15)
				)
				(justify mirror)
			)
		)
		(property "Author" "Antmicro"
			(at 0 0 90)
			(unlocked yes)
			(layer "B.Fab")
			(hide yes)
			(effects
				(font
					(size 1 1)
					(thickness 0.15)
				)
				(justify mirror)
			)
		)
		(property "Val" "2k2"
			(at 0 0 90)
			(unlocked yes)
			(layer "B.Fab")
			(hide yes)
			(effects
				(font
					(size 1 1)
					(thickness 0.15)
				)
				(justify mirror)
			)
		)
		(property "Tolerance" "1%"
			(at 0 0 90)
			(unlocked yes)
			(layer "B.Fab")
			(hide yes)
			(effects
				(font
					(size 1 1)
					(thickness 0.15)
				)
				(justify mirror)
			)
		)
		(sheetname "/CSI/")
		(sheetfile "csi.kicad_sch")
		(attr smd)
		(fp_rect
			(start -0.925 0.47)
			(end 0.925 -0.47)
			(stroke
				(width 0.05)
				(type default)
			)
			(fill no)
			(layer "B.CrtYd")
		)
		(fp_rect
			(start -0.5 0.25)
			(end 0.5 -0.25)
			(stroke
				(width 0.15)
				(type solid)
			)
			(fill no)
			(layer "B.Fab")
		)
		(fp_text user "Author: Antmicro"
			(at -0.95 -4.169 90)
			(layer "B.Fab")
			(effects
				(font
					(size 0.7 0.7)
					(thickness 0.15)
				)
				(justify left bottom mirror)
			)
		)
		(fp_text user "${REFERENCE}"
			(at -0.95 -3.168 90)
			(layer "B.Fab")
			(effects
				(font
					(size 0.7 0.7)
					(thickness 0.15)
				)
				(justify left bottom mirror)
			)
		)
		(fp_text user "License: Apache-2.0"
			(at -0.95 -5.169 90)
			(layer "B.Fab")
			(effects
				(font
					(size 0.7 0.7)
					(thickness 0.15)
				)
				(justify left bottom mirror)
			)
		)
		(pad "1" smd roundrect
			(at -0.48 0 270)
			(size 0.59 0.64)
			(layers "B.Cu" "B.Mask" "B.Paste")
			(roundrect_rratio 0.25)
			(net 979 "/CSI/CSIA_I2C_VCC")
			(pintype "passive")
		)
		(pad "2" smd roundrect
			(at 0.48 0 270)
			(size 0.59 0.64)
			(layers "B.Cu" "B.Mask" "B.Paste")
			(roundrect_rratio 0.25)
			(net 985 "/CSI/SCL_CAM0")
			(pintype "passive")
		)
	)
	(footprint "antmicro-footprints:R_0402_1005Metric"
		(layer "B.Cu")
		(at 197.6 70.6 -90)
		(descr "Resistor SMD 0402")
		(tags "resistor SMD 0402")
		(property "Reference" "R104"
			(at -1.5 1.5 90)
			(layer "B.SilkS")
			(effects
				(font
					(size 0.7 0.7)
					(thickness 0.15)
				)
				(justify left bottom mirror)
			)
		)
		(property "Value" "R_4k7_0402"
			(at -1.011843 -1.772046 90)
			(layer "B.Fab")
			(effects
				(font
					(size 0.7 0.7)
					(thickness 0.15)
				)
				(justify left bottom mirror)
			)
		)
		(property "Datasheet" "https://www.bourns.com/docs/product-datasheets/cr.pdf"
			(at 0 0 90)
			(layer "B.Fab")
			(hide yes)
			(effects
				(font
					(size 1.27 1.27)
					(thickness 0.15)
				)
				(justify mirror)
			)
		)
		(property "Description" "SMD Chip Resistor, 4.7 kohm, ± 1%, 62.5 mW, 0402 [1005 Metric], Thick Film, General Purpose"
			(at 0 0 90)
			(layer "B.Fab")
			(hide yes)
			(effects
				(font
					(size 1.27 1.27)
					(thickness 0.15)
				)
				(justify mirror)
			)
		)
		(property "Manufacturer" "Bourns"
			(at 0 0 90)
			(unlocked yes)
			(layer "B.Fab")
			(hide yes)
			(effects
				(font
					(size 1 1)
					(thickness 0.15)
				)
				(justify mirror)
			)
		)
		(property "MPN" "CR0402-FX-4701GLF"
			(at 0 0 90)
			(unlocked yes)
			(layer "B.Fab")
			(hide yes)
			(effects
				(font
					(size 1 1)
					(thickness 0.15)
				)
				(justify mirror)
			)
		)
		(property "Val" "4k7"
			(at 0 0 90)
			(unlocked yes)
			(layer "B.Fab")
			(hide yes)
			(effects
				(font
					(size 1 1)
					(thickness 0.15)
				)
				(justify mirror)
			)
		)
		(property "License" "Apache-2.0"
			(at 0 0 90)
			(unlocked yes)
			(layer "B.Fab")
			(hide yes)
			(effects
				(font
					(size 1 1)
					(thickness 0.15)
				)
				(justify mirror)
			)
		)
		(property "Author" "Antmicro"
			(at 0 0 90)
			(unlocked yes)
			(layer "B.Fab")
			(hide yes)
			(effects
				(font
					(size 1 1)
					(thickness 0.15)
				)
				(justify mirror)
			)
		)
		(property "Tolerance" "1%"
			(at 0 0 90)
			(unlocked yes)
			(layer "B.Fab")
			(hide yes)
			(effects
				(font
					(size 1 1)
					(thickness 0.15)
				)
				(justify mirror)
			)
		)
		(sheetname "/USB Debug, PD/")
		(sheetfile "usb_debug_pd.kicad_sch")
		(attr smd exclude_from_pos_files exclude_from_bom dnp)
		(fp_poly
			(pts
				(xy -0.925 0.47) (xy 0.925 0.47) (xy 0.925 -0.47) (xy -0.925 -0.47)
			)
			(stroke
				(width 0.05)
				(type default)
			)
			(fill no)
			(layer "B.CrtYd")
		)
		(fp_poly
			(pts
				(xy -0.5 0.25) (xy 0.5 0.25) (xy 0.5 -0.25) (xy -0.5 -0.25)
			)
			(stroke
				(width 0.15)
				(type solid)
			)
			(fill no)
			(layer "B.Fab")
		)
		(fp_text user "License: Apache-2.0"
			(at -0.949999 -5.169 90)
			(layer "B.Fab")
			(effects
				(font
					(size 0.7 0.7)
					(thickness 0.15)
				)
				(justify left bottom mirror)
			)
		)
		(fp_text user "Author: Antmicro"
			(at -0.95 -4.169 90)
			(layer "B.Fab")
			(effects
				(font
					(size 0.7 0.7)
					(thickness 0.15)
				)
				(justify left bottom mirror)
			)
		)
		(fp_text user "${REFERENCE}"
			(at -0.95 -3.168 90)
			(layer "B.Fab")
			(effects
				(font
					(size 0.7 0.7)
					(thickness 0.15)
				)
				(justify left bottom mirror)
			)
		)
		(pad "1" smd roundrect
			(at -0.48 0 270)
			(size 0.59 0.64)
			(layers "B.Cu" "B.Mask" "B.Paste")
			(roundrect_rratio 0.25)
			(net 2 "+3V3")
			(pintype "passive")
		)
		(pad "2" smd roundrect
			(at 0.48 0 270)
			(size 0.59 0.64)
			(layers "B.Cu" "B.Mask" "B.Paste")
			(roundrect_rratio 0.25)
			(net 946 "/USB Debug, PD/DEBUG_SDA")
			(pintype "passive")
		)
	)
	(footprint "antmicro-footprints:R_0603_1608Metric"
		(layer "B.Cu")
		(at 84 140.75)
		(descr "Resistor SMD 0603")
		(tags "resistor SMD 0603")
		(property "Reference" "R247"
			(at -1.6 -1.55 0)
			(layer "B.SilkS")
			(effects
				(font
					(size 0.7 0.7)
					(thickness 0.15)
				)
				(justify right top mirror)
			)
		)
		(property "Value" "R_0R_22.4A_0603"
			(at 0 -1.6 0)
			(layer "B.Fab")
			(effects
				(font
					(size 0.7 0.7)
					(thickness 0.15)
				)
				(justify right top mirror)
			)
		)
		(property "Datasheet" "https://fscdn.rohm.com/en/products/databook/datasheet/passive/resistor/chip_resistor/pmr-jpw-e.pdf"
			(at 0 0 0)
			(layer "B.Fab")
			(hide yes)
			(effects
				(font
					(size 1.27 1.27)
					(thickness 0.15)
				)
				(justify mirror)
			)
		)
		(property "Description" "SMD Chip Resistor"
			(at 0 0 0)
			(layer "B.Fab")
			(hide yes)
			(effects
				(font
					(size 1.27 1.27)
					(thickness 0.15)
				)
				(justify mirror)
			)
		)
		(property "MPN" "PMR03EZPJ000"
			(at 0 0 180)
			(unlocked yes)
			(layer "B.Fab")
			(hide yes)
			(effects
				(font
					(size 1 1)
					(thickness 0.15)
				)
				(justify mirror)
			)
		)
		(property "Manufacturer" "ROHM Semiconductor"
			(at 0 0 180)
			(unlocked yes)
			(layer "B.Fab")
			(hide yes)
			(effects
				(font
					(size 1 1)
					(thickness 0.15)
				)
				(justify mirror)
			)
		)
		(property "Val" "0R"
			(at 0 0 180)
			(unlocked yes)
			(layer "B.Fab")
			(hide yes)
			(effects
				(font
					(size 1 1)
					(thickness 0.15)
				)
				(justify mirror)
			)
		)
		(property "Max. Curr." "22.4A"
			(at 0 0 180)
			(unlocked yes)
			(layer "B.Fab")
			(hide yes)
			(effects
				(font
					(size 1 1)
					(thickness 0.15)
				)
				(justify mirror)
			)
		)
		(property "Author" "Antmicro"
			(at 0 0 180)
			(unlocked yes)
			(layer "B.Fab")
			(hide yes)
			(effects
				(font
					(size 1 1)
					(thickness 0.15)
				)
				(justify mirror)
			)
		)
		(property "License" "Apache-2.0"
			(at 0 0 180)
			(unlocked yes)
			(layer "B.Fab")
			(hide yes)
			(effects
				(font
					(size 1 1)
					(thickness 0.15)
				)
				(justify mirror)
			)
		)
		(property "Tolerance" "template_tolerance"
			(at 0 0 180)
			(unlocked yes)
			(layer "B.Fab")
			(hide yes)
			(effects
				(font
					(size 1 1)
					(thickness 0.15)
				)
				(justify mirror)
			)
		)
		(sheetname "/Expansion connector/")
		(sheetfile "expansion_connector.kicad_sch")
		(attr smd exclude_from_pos_files exclude_from_bom dnp)
		(fp_line
			(start -0.15 -0.4)
			(end 0.15 -0.4)
			(stroke
				(width 0.15)
				(type solid)
			)
			(layer "B.SilkS")
		)
		(fp_line
			(start -0.15 0.4)
			(end 0.15 0.4)
			(stroke
				(width 0.15)
				(type solid)
			)
			(layer "B.SilkS")
		)
		(fp_poly
			(pts
				(xy -1.25 0.65) (xy -1.25 -0.65) (xy 1.25 -0.65) (xy 1.25 0.65)
			)
			(stroke
				(width 0.05)
				(type solid)
			)
			(fill no)
			(layer "B.CrtYd")
		)
		(fp_poly
			(pts
				(xy -0.8 0.4) (xy -0.8 -0.4) (xy 0.8 -0.4) (xy 0.8 0.4)
			)
			(stroke
				(width 0.15)
				(type solid)
			)
			(fill no)
			(layer "B.Fab")
		)
		(fp_text user "Author: Antmicro"
			(at -1.25 -4.9 0)
			(layer "B.Fab")
			(effects
				(font
					(size 0.7 0.7)
					(thickness 0.15)
				)
				(justify right top mirror)
			)
		)
		(fp_text user "License: Apache-2.0"
			(at -1.249999 -5.9 0)
			(layer "B.Fab")
			(effects
				(font
					(size 0.7 0.7)
					(thickness 0.15)
				)
				(justify right top mirror)
			)
		)
		(fp_text user "${REFERENCE}"
			(at -1.25 -3.898 0)
			(layer "B.Fab")
			(effects
				(font
					(size 0.7 0.7)
					(thickness 0.15)
				)
				(justify right top mirror)
			)
		)
		(pad "1" smd roundrect
			(at -0.7 0)
			(size 0.8 1)
			(layers "B.Cu" "B.Mask" "B.Paste")
			(roundrect_rratio 0.2)
			(net 289 "/Expansion connector/+12V_FMC")
			(pintype "passive")
		)
		(pad "2" smd roundrect
			(at 0.7 0)
			(size 0.8 1)
			(layers "B.Cu" "B.Mask" "B.Paste")
			(roundrect_rratio 0.2)
			(net 634 "+12V")
			(pintype "passive")
		)
	)
	(footprint "antmicro-footprints:TSOT23-6"
		(layer "B.Cu")
		(at 232.4 122)
		(property "Reference" "U18"
			(at -0.939999 1.947 0)
			(layer "B.SilkS")
			(effects
				(font
					(size 0.7 0.7)
					(thickness 0.15)
				)
				(justify right top mirror)
			)
		)
		(property "Value" "AP22615A_TSOT26"
			(at 0 -2.600001 0)
			(layer "B.Fab")
			(effects
				(font
					(size 0.7 0.7)
					(thickness 0.15)
				)
				(justify right top mirror)
			)
		)
		(property "Datasheet" "https://www.mouser.com/datasheet/2/115/DIOD_S_A0008958405_1-2543193.pdf"
			(at 0 0 0)
			(layer "B.Fab")
			(hide yes)
			(effects
				(font
					(size 1.27 1.27)
					(thickness 0.15)
				)
				(justify mirror)
			)
		)
		(property "Description" "Power Load Distribution Switch, High Side, Active High, 1 Output, 5.5 V, 3.6 A, 0.04 ohm, TSOT-26-6"
			(at 0 0 0)
			(layer "B.Fab")
			(hide yes)
			(effects
				(font
					(size 1.27 1.27)
					(thickness 0.15)
				)
				(justify mirror)
			)
		)
		(property "MPN" "AP22615AWU-7"
			(at 0 0 180)
			(unlocked yes)
			(layer "B.Fab")
			(hide yes)
			(effects
				(font
					(size 1 1)
					(thickness 0.15)
				)
				(justify mirror)
			)
		)
		(property "Manufacturer" "Diodes Incorporated"
			(at 0 0 180)
			(unlocked yes)
			(layer "B.Fab")
			(hide yes)
			(effects
				(font
					(size 1 1)
					(thickness 0.15)
				)
				(justify mirror)
			)
		)
		(property "Author" "Antmicro"
			(at 0 0 180)
			(unlocked yes)
			(layer "B.Fab")
			(hide yes)
			(effects
				(font
					(size 1 1)
					(thickness 0.15)
				)
				(justify mirror)
			)
		)
		(property "License" "Apache-2.0"
			(at 0 0 180)
			(unlocked yes)
			(layer "B.Fab")
			(hide yes)
			(effects
				(font
					(size 1 1)
					(thickness 0.15)
				)
				(justify mirror)
			)
		)
		(sheetname "/USB Hub/")
		(sheetfile "usb_hub.kicad_sch")
		(attr smd)
		(fp_line
			(start -1 -1.55)
			(end -1 -1.4)
			(stroke
				(width 0.15)
				(type solid)
			)
			(layer "B.SilkS")
		)
		(fp_line
			(start -1 1.5)
			(end -1 1.375)
			(stroke
				(width 0.15)
				(type solid)
			)
			(layer "B.SilkS")
		)
		(fp_line
			(start 1 -1.55)
			(end -1 -1.55)
			(stroke
				(width 0.15)
				(type solid)
			)
			(layer "B.SilkS")
		)
		(fp_line
			(start 1 -1.55)
			(end 1 -1.4)
			(stroke
				(width 0.15)
				(type solid)
			)
			(layer "B.SilkS")
		)
		(fp_line
			(start 1 1.497)
			(end -1 1.5)
			(stroke
				(width 0.15)
				(type solid)
			)
			(layer "B.SilkS")
		)
		(fp_line
			(start 1 1.497)
			(end 1 1.375)
			(stroke
				(width 0.15)
				(type solid)
			)
			(layer "B.SilkS")
		)
		(fp_circle
			(center -1.44 1.5)
			(end -1.39 1.5)
			(stroke
				(width 0.15)
				(type solid)
			)
			(fill yes)
			(layer "B.SilkS")
		)
		(fp_poly
			(pts
				(xy 1.930001 1.7) (xy 1.930001 -1.7) (xy -1.930001 -1.7) (xy -1.930001 1.7)
			)
			(stroke
				(width 0.05)
				(type solid)
			)
			(fill no)
			(layer "B.CrtYd")
		)
		(fp_line
			(start -0.45 1.520999)
			(end -0.876001 1.096)
			(stroke
				(width 0.15)
				(type solid)
			)
			(layer "B.Fab")
		)
		(fp_poly
			(pts
				(xy 0.875 -1.528) (xy 0.875 1.525) (xy -0.875 1.525) (xy -0.875 -1.528)
			)
			(stroke
				(width 0.15)
				(type solid)
			)
			(fill no)
			(layer "B.Fab")
		)
		(fp_text user "Author: Antmicro"
			(at -1.93 -5 0)
			(layer "B.Fab")
			(effects
				(font
					(size 0.7 0.7)
					(thickness 0.15)
				)
				(justify right top mirror)
			)
		)
		(fp_text user "License: Apache-2.0"
			(at -1.93 -6.199 0)
			(layer "B.Fab")
			(effects
				(font
					(size 0.7 0.7)
					(thickness 0.15)
				)
				(justify right top mirror)
			)
		)
		(fp_text user "${REFERENCE}"
			(at -1.93 -3.8 0)
			(layer "B.Fab")
			(effects
				(font
					(size 0.7 0.7)
					(thickness 0.15)
				)
				(justify right top mirror)
			)
		)
		(pad "1" smd rect
			(at -1.301 0.947 90)
			(size 0.7 1.2)
			(layers "B.Cu" "B.Mask" "B.Paste")
			(net 71 "/USB Hub/USBC3_VBUS")
			(pinfunction "OUT")
			(pintype "power_out")
		)
		(pad "2" smd rect
			(at -1.300999 -0.004 90)
			(size 0.7 1.2)
			(layers "B.Cu" "B.Mask" "B.Paste")
			(net 1 "GND")
			(pinfunction "GND")
			(pintype "power_in")
		)
		(pad "3" smd rect
			(at -1.301 -0.954 90)
			(size 0.7 1.2)
			(layers "B.Cu" "B.Mask" "B.Paste")
			(net 911 "/USB Hub/PRT_CTL2")
			(pinfunction "FLG")
			(pintype "output")
		)
		(pad "4" smd rect
			(at 1.299 -0.954 90)
			(size 0.7 1.2)
			(layers "B.Cu" "B.Mask" "B.Paste")
			(net 911 "/USB Hub/PRT_CTL2")
			(pinfunction "EN")
			(pintype "input")
		)
		(pad "5" smd rect
			(at 1.299 -0.004 90)
			(size 0.7 1.2)
			(layers "B.Cu" "B.Mask" "B.Paste")
			(net 909 "/USB Hub/USBC3_ISET")
			(pinfunction "ISET")
			(pintype "passive")
		)
		(pad "6" smd rect
			(at 1.299 0.947 90)
			(size 0.7 1.2)
			(layers "B.Cu" "B.Mask" "B.Paste")
			(net 5 "+5V")
			(pinfunction "IN")
			(pintype "power_in")
		)
	)
	(footprint "antmicro-footprints:R_0402_1005Metric"
		(layer "B.Cu")
		(at 220.18 109.51)
		(descr "Resistor SMD 0402")
		(tags "resistor SMD 0402")
		(property "Reference" "R299"
			(at -1.48 -1.41 0)
			(layer "B.SilkS")
			(effects
				(font
					(size 0.7 0.7)
					(thickness 0.15)
				)
				(justify right top mirror)
			)
		)
		(property "Value" "R_10k_0402"
			(at -1.011843 -1.772047 0)
			(layer "B.Fab")
			(effects
				(font
					(size 0.7 0.7)
					(thickness 0.15)
				)
				(justify right top mirror)
			)
		)
		(property "Datasheet" "https://www.bourns.com/docs/product-datasheets/cr.pdf"
			(at 0 0 0)
			(layer "B.Fab")
			(hide yes)
			(effects
				(font
					(size 1.27 1.27)
					(thickness 0.15)
				)
				(justify mirror)
			)
		)
		(property "Description" "SMD Chip Resistor, 10 kohm, ± 1%, 62.5 mW, 0402 [1005 Metric], Thick Film, General Purpose"
			(at 0 0 0)
			(layer "B.Fab")
			(hide yes)
			(effects
				(font
					(size 1.27 1.27)
					(thickness 0.15)
				)
				(justify mirror)
			)
		)
		(property "MPN" "CR0402-FX-1002GLF"
			(at 0 0 180)
			(unlocked yes)
			(layer "B.Fab")
			(hide yes)
			(effects
				(font
					(size 1 1)
					(thickness 0.15)
				)
				(justify mirror)
			)
		)
		(property "Manufacturer" "Bourns"
			(at 0 0 180)
			(unlocked yes)
			(layer "B.Fab")
			(hide yes)
			(effects
				(font
					(size 1 1)
					(thickness 0.15)
				)
				(justify mirror)
			)
		)
		(property "License" "Apache-2.0"
			(at 0 0 180)
			(unlocked yes)
			(layer "B.Fab")
			(hide yes)
			(effects
				(font
					(size 1 1)
					(thickness 0.15)
				)
				(justify mirror)
			)
		)
		(property "Author" "Antmicro"
			(at 0 0 180)
			(unlocked yes)
			(layer "B.Fab")
			(hide yes)
			(effects
				(font
					(size 1 1)
					(thickness 0.15)
				)
				(justify mirror)
			)
		)
		(property "Val" "10k"
			(at 0 0 180)
			(unlocked yes)
			(layer "B.Fab")
			(hide yes)
			(effects
				(font
					(size 1 1)
					(thickness 0.15)
				)
				(justify mirror)
			)
		)
		(property "Tolerance" "1%"
			(at 0 0 180)
			(unlocked yes)
			(layer "B.Fab")
			(hide yes)
			(effects
				(font
					(size 1 1)
					(thickness 0.15)
				)
				(justify mirror)
			)
		)
		(sheetname "/USB Hub/")
		(sheetfile "usb_hub.kicad_sch")
		(attr smd)
		(fp_rect
			(start -0.925 0.47)
			(end 0.925 -0.47)
			(stroke
				(width 0.05)
				(type default)
			)
			(fill no)
			(layer "B.CrtYd")
		)
		(fp_rect
			(start -0.5 0.25)
			(end 0.5 -0.25)
			(stroke
				(width 0.15)
				(type solid)
			)
			(fill no)
			(layer "B.Fab")
		)
		(fp_text user "${REFERENCE}"
			(at -0.95 -3.168 0)
			(layer "B.Fab")
			(effects
				(font
					(size 0.7 0.7)
					(thickness 0.15)
				)
				(justify right top mirror)
			)
		)
		(fp_text user "Author: Antmicro"
			(at -0.95 -4.169 0)
			(layer "B.Fab")
			(effects
				(font
					(size 0.7 0.7)
					(thickness 0.15)
				)
				(justify right top mirror)
			)
		)
		(fp_text user "License: Apache-2.0"
			(at -0.95 -5.169 0)
			(layer "B.Fab")
			(effects
				(font
					(size 0.7 0.7)
					(thickness 0.15)
				)
				(justify right top mirror)
			)
		)
		(pad "1" smd roundrect
			(at -0.48 0)
			(size 0.59 0.64)
			(layers "B.Cu" "B.Mask" "B.Paste")
			(roundrect_rratio 0.25)
			(net 5 "+5V")
			(pintype "passive")
		)
		(pad "2" smd roundrect
			(at 0.48 0)
			(size 0.59 0.64)
			(layers "B.Cu" "B.Mask" "B.Paste")
			(roundrect_rratio 0.25)
			(net 1330 "Net-(Q21-D1)")
			(pintype "passive")
		)
	)
	(footprint "antmicro-footprints:TP_SMD_0.75mm"
		(layer "B.Cu")
		(at 155.5 113 -90)
		(property "Reference" "TP87"
			(at 0 0.6 90)
			(layer "B.SilkS")
			(effects
				(font
					(size 0.7 0.7)
					(thickness 0.15)
				)
				(justify left bottom mirror)
			)
		)
		(property "Value" "TP_0.75mm_SMD"
			(at 0 -1.2 90)
			(layer "B.Fab")
			(effects
				(font
					(size 0.7 0.7)
					(thickness 0.15)
				)
				(justify left bottom mirror)
			)
		)
		(property "Description" "SMT test point"
			(at 0 0 90)
			(layer "B.Fab")
			(hide yes)
			(effects
				(font
					(size 1.27 1.27)
					(thickness 0.15)
				)
				(justify mirror)
			)
		)
		(property "MPN" ""
			(at 0 0 90)
			(unlocked yes)
			(layer "B.Fab")
			(hide yes)
			(effects
				(font
					(size 1 1)
					(thickness 0.15)
				)
				(justify mirror)
			)
		)
		(property "Manufacturer" ""
			(at 0 0 90)
			(unlocked yes)
			(layer "B.Fab")
			(hide yes)
			(effects
				(font
					(size 1 1)
					(thickness 0.15)
				)
				(justify mirror)
			)
		)
		(property "Author" "Antmicro"
			(at 0 0 90)
			(unlocked yes)
			(layer "B.Fab")
			(hide yes)
			(effects
				(font
					(size 1 1)
					(thickness 0.15)
				)
				(justify mirror)
			)
		)
		(property "License" "Apache-2.0"
			(at 0 0 90)
			(unlocked yes)
			(layer "B.Fab")
			(hide yes)
			(effects
				(font
					(size 1 1)
					(thickness 0.15)
				)
				(justify mirror)
			)
		)
		(sheetname "/Peripherals/")
		(sheetfile "peripherals.kicad_sch")
		(attr exclude_from_pos_files exclude_from_bom)
		(fp_circle
			(center 0 0)
			(end 0.475 0)
			(stroke
				(width 0.05)
				(type default)
			)
			(fill no)
			(layer "B.CrtYd")
		)
		(fp_text user "License: Apache-2.0"
			(at -0.4 -5.101 90)
			(layer "B.Fab")
			(effects
				(font
					(size 0.7 0.7)
					(thickness 0.15)
				)
				(justify left bottom mirror)
			)
		)
		(fp_text user "Author: Antmicro"
			(at -0.4 -3.901 90)
			(layer "B.Fab")
			(effects
				(font
					(size 0.7 0.7)
					(thickness 0.15)
				)
				(justify left bottom mirror)
			)
		)
		(fp_text user "${REFERENCE}"
			(at -0.4 -2.7 90)
			(layer "B.Fab")
			(effects
				(font
					(size 0.7 0.7)
					(thickness 0.15)
				)
				(justify left bottom mirror)
			)
		)
		(pad "1" smd circle
			(at 0 0 270)
			(size 0.75 0.75)
			(layers "B.Cu" "B.Mask")
			(net 850 "/I2C_{SYS}.SDA")
			(pinfunction "1")
			(pintype "passive")
		)
	)
	(footprint "antmicro-footprints:Tag-Connect_TC2050-IDC-NL_2x5_P1.27mm"
		(layer "B.Cu")
		(at 196.4 97)
		(property "Reference" "J4"
			(at 0.75 3.15 180)
			(layer "B.SilkS")
			(effects
				(font
					(size 0.7 0.7)
					(thickness 0.15)
				)
				(justify left bottom mirror)
			)
		)
		(property "Value" "Tag-Connect_TC2050-IDC-NL_2x5_P1.27mm"
			(at 0 -4.4 180)
			(layer "B.Fab")
			(effects
				(font
					(size 0.7 0.7)
					(thickness 0.15)
				)
				(justify left bottom mirror)
			)
		)
		(property "Datasheet" "https://www.tag-connect.com/wp-content/uploads/bsk-pdf-manager/TC2050-IDC-NL_Datasheet_8.pdf"
			(at 0 0 180)
			(layer "B.Fab")
			(hide yes)
			(effects
				(font
					(size 1.27 1.27)
					(thickness 0.15)
				)
				(justify mirror)
			)
		)
		(property "Description" "Tag Connect 2x5 1.27mm terminal"
			(at 0 0 180)
			(layer "B.Fab")
			(hide yes)
			(effects
				(font
					(size 1.27 1.27)
					(thickness 0.15)
				)
				(justify mirror)
			)
		)
		(property "MPN" "TC2050-IDC-NL"
			(at 0 0 180)
			(unlocked yes)
			(layer "B.Fab")
			(hide yes)
			(effects
				(font
					(size 1 1)
					(thickness 0.15)
				)
				(justify mirror)
			)
		)
		(property "Manufacturer" "Tag Connect"
			(at 0 0 180)
			(unlocked yes)
			(layer "B.Fab")
			(hide yes)
			(effects
				(font
					(size 1 1)
					(thickness 0.15)
				)
				(justify mirror)
			)
		)
		(property "Author" "Antmicro"
			(at 0 0 180)
			(unlocked yes)
			(layer "B.Fab")
			(hide yes)
			(effects
				(font
					(size 1 1)
					(thickness 0.15)
				)
				(justify mirror)
			)
		)
		(property "License" "Apache-2.0"
			(at 0 0 180)
			(unlocked yes)
			(layer "B.Fab")
			(hide yes)
			(effects
				(font
					(size 1 1)
					(thickness 0.15)
				)
				(justify mirror)
			)
		)
		(sheetname "/USB Debug, PD/")
		(sheetfile "usb_debug_pd.kicad_sch")
		(attr exclude_from_bom)
		(fp_line
			(start -5.08 -0.8)
			(end -5.08 0.900001)
			(stroke
				(width 0.15)
				(type solid)
			)
			(layer "B.SilkS")
		)
		(fp_line
			(start -5.08 0.900001)
			(end -2.2 2.05)
			(stroke
				(width 0.15)
				(type solid)
			)
			(layer "B.SilkS")
		)
		(fp_line
			(start -3.101001 -1.269)
			(end -3.101 -0.4)
			(stroke
				(width 0.15)
				(type solid)
			)
			(layer "B.SilkS")
		)
		(fp_line
			(start -2.3 -2.049)
			(end -5.08 -0.8)
			(stroke
				(width 0.15)
				(type solid)
			)
			(layer "B.SilkS")
		)
		(fp_line
			(start -2.2 2.05)
			(end 4.7 2.05)
			(stroke
				(width 0.15)
				(type solid)
			)
			(layer "B.SilkS")
		)
		(fp_line
			(start 4.7 -2.049)
			(end -2.3 -2.049)
			(stroke
				(width 0.15)
				(type solid)
			)
			(layer "B.SilkS")
		)
		(fp_line
			(start 4.7 -2.049)
			(end 5.1 -1.7)
			(stroke
				(width 0.15)
				(type solid)
			)
			(layer "B.SilkS")
		)
		(fp_line
			(start 4.7 2.05)
			(end 5.1 1.7)
			(stroke
				(width 0.15)
				(type solid)
			)
			(layer "B.SilkS")
		)
		(fp_line
			(start 5.1 1.7)
			(end 5.1 -1.7)
			(stroke
				(width 0.15)
				(type solid)
			)
			(layer "B.SilkS")
		)
		(fp_line
			(start -5.330001 1.1)
			(end -2.3 2.3)
			(stroke
				(width 0.05)
				(type solid)
			)
			(layer "B.CrtYd")
		)
		(fp_line
			(start -5.33 -1)
			(end -5.330001 1.1)
			(stroke
				(width 0.05)
				(type solid)
			)
			(layer "B.CrtYd")
		)
		(fp_line
			(start -2.4 -2.29)
			(end -5.33 -1)
			(stroke
				(width 0.05)
				(type solid)
			)
			(layer "B.CrtYd")
		)
		(fp_line
			(start -2.3 2.3)
			(end 4.8 2.3)
			(stroke
				(width 0.05)
				(type solid)
			)
			(layer "B.CrtYd")
		)
		(fp_line
			(start 4.8 -2.29)
			(end -2.4 -2.29)
			(stroke
				(width 0.05)
				(type solid)
			)
			(layer "B.CrtYd")
		)
		(fp_line
			(start 4.8 -2.29)
			(end 5.32 -1.8)
			(stroke
				(width 0.05)
				(type solid)
			)
			(layer "B.CrtYd")
		)
		(fp_line
			(start 4.8 2.3)
			(end 5.32 1.8)
			(stroke
				(width 0.05)
				(type solid)
			)
			(layer "B.CrtYd")
		)
		(fp_line
			(start 5.32 1.8)
			(end 5.32 -1.8)
			(stroke
				(width 0.05)
				(type solid)
			)
			(layer "B.CrtYd")
		)
		(fp_text user "Author: Antmicro"
			(at -6.223 -7.249001 180)
			(layer "B.Fab")
			(effects
				(font
					(size 0.7 0.7)
					(thickness 0.15)
				)
				(justify left bottom mirror)
			)
		)
		(fp_text user "${REFERENCE}"
			(at -6.223 -6.048999 180)
			(layer "B.Fab")
			(effects
				(font
					(size 0.7 0.7)
					(thickness 0.15)
				)
				(justify left bottom mirror)
			)
		)
		(fp_text user "License: Apache-2.0"
			(at -6.223 -8.449 180)
			(layer "B.Fab")
			(effects
				(font
					(size 0.7 0.7)
					(thickness 0.15)
				)
				(justify left bottom mirror)
			)
		)
		(pad "" np_thru_hole circle
			(at -3.81 0)
			(size 0.9906 0.9906)
			(drill 0.9906)
			(layers "*.Cu" "*.Mask")
		)
		(pad "" np_thru_hole circle
			(at 3.809 -1.015)
			(size 0.9906 0.9906)
			(drill 0.9906)
			(layers "*.Cu" "*.Mask")
		)
		(pad "" np_thru_hole circle
			(at 3.809 1.016)
			(size 0.9906 0.9906)
			(drill 0.9906)
			(layers "*.Cu" "*.Mask")
		)
		(pad "1" connect circle
			(at -2.54 -0.634)
			(size 0.7874 0.7874)
			(layers "B.Cu" "B.Mask")
			(net 271 "FLASH_PWR")
			(pinfunction "1")
			(pintype "passive")
		)
		(pad "2" connect circle
			(at -1.27 -0.634)
			(size 0.7874 0.7874)
			(layers "B.Cu" "B.Mask")
			(net 812 "/USB Debug, PD/~{CS}")
			(pinfunction "2")
			(pintype "passive")
		)
		(pad "3" connect circle
			(at 0 -0.634)
			(size 0.7874 0.7874)
			(layers "B.Cu" "B.Mask")
			(net 1 "GND")
			(pinfunction "3")
			(pintype "passive")
		)
		(pad "4" connect circle
			(at 1.269 -0.634)
			(size 0.7874 0.7874)
			(layers "B.Cu" "B.Mask")
			(net 532 "/USB Debug, PD/SCK")
			(pinfunction "4")
			(pintype "passive")
		)
		(pad "5" connect circle
			(at 2.539 -0.634)
			(size 0.7874 0.7874)
			(layers "B.Cu" "B.Mask")
			(net 1 "GND")
			(pinfunction "5")
			(pintype "passive")
		)
		(pad "6" connect circle
			(at 2.539 0.635)
			(size 0.7874 0.7874)
			(layers "B.Cu" "B.Mask")
			(net 810 "/USB Debug, PD/MISO")
			(pinfunction "6")
			(pintype "passive")
		)
		(pad "7" connect circle
			(at 1.269 0.635)
			(size 0.7874 0.7874)
			(layers "B.Cu" "B.Mask")
			(net 809 "unconnected-(J4-Pad7)")
			(pinfunction "7")
			(pintype "passive+no_connect")
		)
		(pad "8" connect circle
			(at 0 0.635)
			(size 0.7874 0.7874)
			(layers "B.Cu" "B.Mask")
			(net 811 "/USB Debug, PD/MOSI")
			(pinfunction "8")
			(pintype "passive")
		)
		(pad "9" connect circle
			(at -1.27 0.635)
			(size 0.7874 0.7874)
			(layers "B.Cu" "B.Mask")
			(net 1 "GND")
			(pinfunction "9")
			(pintype "passive")
		)
		(pad "10" connect circle
			(at -2.54 0.635)
			(size 0.7874 0.7874)
			(layers "B.Cu" "B.Mask")
			(net 808 "unconnected-(J4-Pad10)")
			(pinfunction "10")
			(pintype "passive+no_connect")
		)
	)
	(footprint "antmicro-footprints:R_0402_1005Metric"
		(layer "B.Cu")
		(at 166.25 57.5 -90)
		(descr "Resistor SMD 0402")
		(tags "resistor SMD 0402")
		(property "Reference" "R79"
			(at -3.58 -0.365532 90)
			(layer "B.SilkS")
			(effects
				(font
					(size 0.7 0.7)
					(thickness 0.15)
				)
				(justify left bottom mirror)
			)
		)
		(property "Value" "R_200R_0402"
			(at -1.011843 -1.772047 90)
			(layer "B.Fab")
			(effects
				(font
					(size 0.7 0.7)
					(thickness 0.15)
				)
				(justify left bottom mirror)
			)
		)
		(property "Datasheet" "https://www.bourns.com/docs/product-datasheets/cr.pdf"
			(at 0 0 90)
			(layer "B.Fab")
			(hide yes)
			(effects
				(font
					(size 1.27 1.27)
					(thickness 0.15)
				)
				(justify mirror)
			)
		)
		(property "Description" "SMD Chip Resistor, 200 ohm, ± 1%, 62.5 mW, 0402 [1005 Metric], Thick Film, General Purpose"
			(at 0 0 90)
			(layer "B.Fab")
			(hide yes)
			(effects
				(font
					(size 1.27 1.27)
					(thickness 0.15)
				)
				(justify mirror)
			)
		)
		(property "MPN" "CR0402-FX-2000GLF"
			(at 0 0 90)
			(unlocked yes)
			(layer "B.Fab")
			(hide yes)
			(effects
				(font
					(size 1 1)
					(thickness 0.15)
				)
				(justify mirror)
			)
		)
		(property "Manufacturer" "Bourns"
			(at 0 0 90)
			(unlocked yes)
			(layer "B.Fab")
			(hide yes)
			(effects
				(font
					(size 1 1)
					(thickness 0.15)
				)
				(justify mirror)
			)
		)
		(property "License" "Apache-2.0"
			(at 0 0 90)
			(unlocked yes)
			(layer "B.Fab")
			(hide yes)
			(effects
				(font
					(size 1 1)
					(thickness 0.15)
				)
				(justify mirror)
			)
		)
		(property "Author" "Antmicro"
			(at 0 0 90)
			(unlocked yes)
			(layer "B.Fab")
			(hide yes)
			(effects
				(font
					(size 1 1)
					(thickness 0.15)
				)
				(justify mirror)
			)
		)
		(property "Val" "200R"
			(at 0 0 90)
			(unlocked yes)
			(layer "B.Fab")
			(hide yes)
			(effects
				(font
					(size 1 1)
					(thickness 0.15)
				)
				(justify mirror)
			)
		)
		(property "Tolerance" "1%"
			(at 0 0 90)
			(unlocked yes)
			(layer "B.Fab")
			(hide yes)
			(effects
				(font
					(size 1 1)
					(thickness 0.15)
				)
				(justify mirror)
			)
		)
		(sheetname "/Power/")
		(sheetfile "power.kicad_sch")
		(attr smd)
		(fp_rect
			(start -0.925 0.47)
			(end 0.925 -0.47)
			(stroke
				(width 0.05)
				(type default)
			)
			(fill no)
			(layer "B.CrtYd")
		)
		(fp_rect
			(start -0.5 0.25)
			(end 0.5 -0.25)
			(stroke
				(width 0.15)
				(type solid)
			)
			(fill no)
			(layer "B.Fab")
		)
		(fp_text user "License: Apache-2.0"
			(at -0.95 -5.169 90)
			(layer "B.Fab")
			(effects
				(font
					(size 0.7 0.7)
					(thickness 0.15)
				)
				(justify left bottom mirror)
			)
		)
		(fp_text user "${REFERENCE}"
			(at -0.95 -3.168 90)
			(layer "B.Fab")
			(effects
				(font
					(size 0.7 0.7)
					(thickness 0.15)
				)
				(justify left bottom mirror)
			)
		)
		(fp_text user "Author: Antmicro"
			(at -0.95 -4.169 90)
			(layer "B.Fab")
			(effects
				(font
					(size 0.7 0.7)
					(thickness 0.15)
				)
				(justify left bottom mirror)
			)
		)
		(pad "1" smd roundrect
			(at -0.48 0 270)
			(size 0.59 0.64)
			(layers "B.Cu" "B.Mask" "B.Paste")
			(roundrect_rratio 0.25)
			(net 639 "Net-(D31-A)")
			(pintype "passive")
		)
		(pad "2" smd roundrect
			(at 0.48 0 270)
			(size 0.59 0.64)
			(layers "B.Cu" "B.Mask" "B.Paste")
			(roundrect_rratio 0.25)
			(net 2 "+3V3")
			(pintype "passive")
		)
	)
	(footprint "antmicro-footprints:LED_0603_1608Metric_G"
		(layer "B.Cu")
		(at 110.015 140.76 90)
		(descr "LED SMD 0603 Green")
		(tags "LED SMD 0603 Green")
		(property "Reference" "D33"
			(at -1.14 0.845 90)
			(layer "B.SilkS")
			(effects
				(font
					(size 0.7 0.7)
					(thickness 0.15)
				)
				(justify right top mirror)
			)
		)
		(property "Value" "LED_G_0603_LTST-C190GKT"
			(at -0.001 -1.599 90)
			(layer "B.Fab")
			(effects
				(font
					(size 0.7 0.7)
					(thickness 0.15)
				)
				(justify right top mirror)
			)
		)
		(property "Datasheet" "https://media.digikey.com/pdf/Data%20Sheets/Lite-On%20PDFs/LTST-C190GKT.pdf"
			(at 0 0 90)
			(layer "B.Fab")
			(hide yes)
			(effects
				(font
					(size 1.27 1.27)
					(thickness 0.15)
				)
				(justify mirror)
			)
		)
		(property "Description" "LED, Green, SMD, 0603, 20 mA, 2.1 V, 569 nm"
			(at 0 0 90)
			(layer "B.Fab")
			(hide yes)
			(effects
				(font
					(size 1.27 1.27)
					(thickness 0.15)
				)
				(justify mirror)
			)
		)
		(property "MPN" "LTST-C190GKT"
			(at 0 0 270)
			(unlocked yes)
			(layer "B.Fab")
			(hide yes)
			(effects
				(font
					(size 1 1)
					(thickness 0.15)
				)
				(justify mirror)
			)
		)
		(property "Manufacturer" "Lite-On"
			(at 0 0 270)
			(unlocked yes)
			(layer "B.Fab")
			(hide yes)
			(effects
				(font
					(size 1 1)
					(thickness 0.15)
				)
				(justify mirror)
			)
		)
		(property "Author" "Antmicro"
			(at 0 0 270)
			(unlocked yes)
			(layer "B.Fab")
			(hide yes)
			(effects
				(font
					(size 1 1)
					(thickness 0.15)
				)
				(justify mirror)
			)
		)
		(property "License" "Apache-2.0"
			(at 0 0 270)
			(unlocked yes)
			(layer "B.Fab")
			(hide yes)
			(effects
				(font
					(size 1 1)
					(thickness 0.15)
				)
				(justify mirror)
			)
		)
		(property "Public" "False"
			(at 0 0 270)
			(unlocked yes)
			(layer "B.Fab")
			(hide yes)
			(effects
				(font
					(size 1 1)
					(thickness 0.15)
				)
				(justify mirror)
			)
		)
		(property "Color" "Green"
			(at 0 0 270)
			(unlocked yes)
			(layer "B.Fab")
			(hide yes)
			(effects
				(font
					(size 1 1)
					(thickness 0.15)
				)
				(justify mirror)
			)
		)
		(sheetname "/M.2/")
		(sheetfile "m2.kicad_sch")
		(attr smd)
		(fp_line
			(start 0.22 -0.35)
			(end -0.22 -0.35)
			(stroke
				(width 0.15)
				(type solid)
			)
			(layer "B.SilkS")
		)
		(fp_line
			(start 0.105328 -0.201008)
			(end -0.094672 -0.001008)
			(stroke
				(width 0.1)
				(type solid)
			)
			(layer "B.SilkS")
		)
		(fp_line
			(start 0.105328 -0.201008)
			(end 0.105328 0.198992)
			(stroke
				(width 0.1)
				(type solid)
			)
			(layer "B.SilkS")
		)
		(fp_line
			(start -0.094672 -0.201008)
			(end -0.094672 0.198992)
			(stroke
				(width 0.1)
				(type solid)
			)
			(layer "B.SilkS")
		)
		(fp_line
			(start 0.105328 -0.001008)
			(end 0.24 -0.001)
			(stroke
				(width 0.1)
				(type solid)
			)
			(layer "B.SilkS")
		)
		(fp_line
			(start -0.094672 -0.001008)
			(end -0.24 -0.001008)
			(stroke
				(width 0.1)
				(type solid)
			)
			(layer "B.SilkS")
		)
		(fp_line
			(start -0.094672 -0.001008)
			(end 0.105328 0.198992)
			(stroke
				(width 0.1)
				(type solid)
			)
			(layer "B.SilkS")
		)
		(fp_line
			(start -1.18 0.319)
			(end -1.18 -0.321)
			(stroke
				(width 0.15)
				(type solid)
			)
			(layer "B.SilkS")
		)
		(fp_line
			(start 0.22 0.35)
			(end -0.22 0.35)
			(stroke
				(width 0.15)
				(type solid)
			)
			(layer "B.SilkS")
		)
		(fp_rect
			(start 1.25 -0.65)
			(end -1.25 0.65)
			(stroke
				(width 0.05)
				(type solid)
			)
			(fill no)
			(layer "B.CrtYd")
		)
		(fp_line
			(start 0.201 -0.2)
			(end 0.201 0)
			(stroke
				(width 0.15)
				(type solid)
			)
			(layer "B.Fab")
		)
		(fp_line
			(start -0.199 -0.2)
			(end -0.199 -0.1)
			(stroke
				(width 0.15)
				(type solid)
			)
			(layer "B.Fab")
		)
		(fp_line
			(start 0.599 0)
			(end 0.201 0)
			(stroke
				(width 0.15)
				(type solid)
			)
			(layer "B.Fab")
		)
		(fp_line
			(start 0.201 0)
			(end 0.201 0.202)
			(stroke
				(width 0.15)
				(type solid)
			)
			(layer "B.Fab")
		)
		(fp_line
			(start -0.101 0)
			(end 0.201 -0.2)
			(stroke
				(width 0.15)
				(type solid)
			)
			(layer "B.Fab")
		)
		(fp_line
			(start -0.199 0)
			(end -0.597 0)
			(stroke
				(width 0.15)
				(type solid)
			)
			(layer "B.Fab")
		)
		(fp_line
			(start 0.201 0.202)
			(end -0.101 0)
			(stroke
				(width 0.15)
				(type solid)
			)
			(layer "B.Fab")
		)
		(fp_line
			(start -0.199 0.202)
			(end -0.199 -0.1)
			(stroke
				(width 0.15)
				(type solid)
			)
			(layer "B.Fab")
		)
		(fp_rect
			(start 0.848 -0.4)
			(end -0.85 0.402)
			(stroke
				(width 0.15)
				(type solid)
			)
			(fill no)
			(layer "B.Fab")
		)
		(fp_text user "License: Apache-2.0"
			(at -1.4224 -3.599 90)
			(layer "B.Fab")
			(effects
				(font
					(size 0.7 0.7)
					(thickness 0.15)
				)
				(justify right top mirror)
			)
		)
		(fp_text user "${REFERENCE}"
			(at -1.4224 -5.999 90)
			(layer "B.Fab")
			(effects
				(font
					(size 0.7 0.7)
					(thickness 0.15)
				)
				(justify right top mirror)
			)
		)
		(fp_text user "Author: Antmicro"
			(at -1.4224 -4.799 90)
			(layer "B.Fab")
			(effects
				(font
					(size 0.7 0.7)
					(thickness 0.15)
				)
				(justify right top mirror)
			)
		)
		(pad "1" smd roundrect
			(at -0.7 0 270)
			(size 0.8 1)
			(layers "B.Cu" "B.Mask" "B.Paste")
			(roundrect_rratio 0.2)
			(net 34 "/M.2/~{LED_1}")
			(pinfunction "C")
			(pintype "passive")
		)
		(pad "2" smd roundrect
			(at 0.7 0 270)
			(size 0.8 1)
			(layers "B.Cu" "B.Mask" "B.Paste")
			(roundrect_rratio 0.2)
			(net 545 "Net-(D33-A)")
			(pinfunction "A")
			(pintype "passive")
		)
	)
	(footprint "antmicro-footprints:C_0603_1608Metric_EIA"
		(layer "B.Cu")
		(at 124.6 98.5)
		(descr "Capacitor SMD 0603, IPC-7351 Density Level A")
		(tags "Capacitor 0603")
		(property "Reference" "C190"
			(at 1.2 -0.5 0)
			(layer "B.SilkS")
			(effects
				(font
					(size 0.7 0.7)
					(thickness 0.15)
				)
				(justify right top mirror)
			)
		)
		(property "Value" "C_22u_16V_0603"
			(at -1.42757 -1.770288 0)
			(layer "B.Fab")
			(effects
				(font
					(size 0.7 0.7)
					(thickness 0.15)
				)
				(justify right top mirror)
			)
		)
		(property "Datasheet" "https://product.samsungsem.com/mlcc/CL10A226MO7JZN.do"
			(at 0 0 0)
			(layer "B.Fab")
			(hide yes)
			(effects
				(font
					(size 1.27 1.27)
					(thickness 0.15)
				)
				(justify mirror)
			)
		)
		(property "Description" "SMD Multilayer Ceramic Capacitor"
			(at 0 0 0)
			(layer "B.Fab")
			(hide yes)
			(effects
				(font
					(size 1.27 1.27)
					(thickness 0.15)
				)
				(justify mirror)
			)
		)
		(property "Manufacturer" "Samsung Electro-Mechanics"
			(at 0 0 180)
			(unlocked yes)
			(layer "B.Fab")
			(hide yes)
			(effects
				(font
					(size 1 1)
					(thickness 0.15)
				)
				(justify mirror)
			)
		)
		(property "MPN" "CL10A226MO7JZNC"
			(at 0 0 180)
			(unlocked yes)
			(layer "B.Fab")
			(hide yes)
			(effects
				(font
					(size 1 1)
					(thickness 0.15)
				)
				(justify mirror)
			)
		)
		(property "Val" "22u"
			(at 0 0 180)
			(unlocked yes)
			(layer "B.Fab")
			(hide yes)
			(effects
				(font
					(size 1 1)
					(thickness 0.15)
				)
				(justify mirror)
			)
		)
		(property "License" "Apache-2.0"
			(at 0 0 180)
			(unlocked yes)
			(layer "B.Fab")
			(hide yes)
			(effects
				(font
					(size 1 1)
					(thickness 0.15)
				)
				(justify mirror)
			)
		)
		(property "Author" "Antmicro"
			(at 0 0 180)
			(unlocked yes)
			(layer "B.Fab")
			(hide yes)
			(effects
				(font
					(size 1 1)
					(thickness 0.15)
				)
				(justify mirror)
			)
		)
		(property "Voltage" "16V"
			(at 0 0 180)
			(unlocked yes)
			(layer "B.Fab")
			(hide yes)
			(effects
				(font
					(size 1 1)
					(thickness 0.15)
				)
				(justify mirror)
			)
		)
		(property "Dielectric" "template_dielectric"
			(at 0 0 180)
			(unlocked yes)
			(layer "B.Fab")
			(hide yes)
			(effects
				(font
					(size 1 1)
					(thickness 0.15)
				)
				(justify mirror)
			)
		)
		(sheetname "/M.2/")
		(sheetfile "m2.kicad_sch")
		(attr smd)
		(fp_line
			(start -0.15 -0.55)
			(end 0.15 -0.55)
			(stroke
				(width 0.15)
				(type solid)
			)
			(layer "B.SilkS")
		)
		(fp_line
			(start -0.15 0.55)
			(end 0.15 0.55)
			(stroke
				(width 0.15)
				(type solid)
			)
			(layer "B.SilkS")
		)
		(fp_poly
			(pts
				(xy -1.25 0.65) (xy -1.25 -0.65) (xy 1.25 -0.65) (xy 1.25 0.65)
			)
			(stroke
				(width 0.05)
				(type solid)
			)
			(fill no)
			(layer "B.CrtYd")
		)
		(fp_poly
			(pts
				(xy -0.799999 0.45) (xy -0.799999 -0.45) (xy 0.799999 -0.45) (xy 0.799999 0.45)
			)
			(stroke
				(width 0.15)
				(type solid)
			)
			(fill no)
			(layer "B.Fab")
		)
		(fp_text user "Author: Antmicro"
			(at -1.682 -4.894 0)
			(layer "B.Fab")
			(effects
				(font
					(size 0.7 0.7)
					(thickness 0.15)
				)
				(justify right top mirror)
			)
		)
		(fp_text user "License: Apache-2.0"
			(at -1.682 -5.895 0)
			(layer "B.Fab")
			(effects
				(font
					(size 0.7 0.7)
					(thickness 0.15)
				)
				(justify right top mirror)
			)
		)
		(fp_text user "${REFERENCE}"
			(at -1.682001 -3.895 0)
			(layer "B.Fab")
			(effects
				(font
					(size 0.7 0.7)
					(thickness 0.15)
				)
				(justify right top mirror)
			)
		)
		(pad "1" smd roundrect
			(at -0.7 0)
			(size 0.8 1.1)
			(layers "B.Cu" "B.Mask" "B.Paste")
			(roundrect_rratio 0.2)
			(net 14 "/M.2/3V3_M2")
			(pintype "passive")
		)
		(pad "2" smd roundrect
			(at 0.7 0)
			(size 0.8 1.1)
			(layers "B.Cu" "B.Mask" "B.Paste")
			(roundrect_rratio 0.2)
			(net 1 "GND")
			(pintype "passive")
		)
	)
	(footprint "antmicro-footprints:C_0402_1005Metric"
		(layer "B.Cu")
		(at 95.68 105.51 90)
		(descr "Capacitor SMD 0402")
		(tags "capacitor SMD 0402")
		(property "Reference" "C333"
			(at -3.69 -0.28 90)
			(layer "B.SilkS")
			(effects
				(font
					(size 0.7 0.7)
					(thickness 0.15)
				)
				(justify right top mirror)
			)
		)
		(property "Value" "C_100n_0402"
			(at -1.022927 -2.155213 90)
			(layer "B.Fab")
			(effects
				(font
					(size 0.7 0.7)
					(thickness 0.15)
				)
				(justify right top mirror)
			)
		)
		(property "Datasheet" "https://www.murata.com/products/productdetail?partno=GRM155R61H104KE14%23"
			(at 0 0 90)
			(layer "B.Fab")
			(hide yes)
			(effects
				(font
					(size 1.27 1.27)
					(thickness 0.15)
				)
				(justify mirror)
			)
		)
		(property "Description" "SMD Multilayer Ceramic Capacitor, 0.1 µF, 50 V, 0402 [1005 Metric], ± 10%, X5R, GRM Series"
			(at 0 0 90)
			(layer "B.Fab")
			(hide yes)
			(effects
				(font
					(size 1.27 1.27)
					(thickness 0.15)
				)
				(justify mirror)
			)
		)
		(property "Manufacturer" "Murata"
			(at 0 0 270)
			(unlocked yes)
			(layer "B.Fab")
			(hide yes)
			(effects
				(font
					(size 1 1)
					(thickness 0.15)
				)
				(justify mirror)
			)
		)
		(property "MPN" "GRM155R61H104KE14D"
			(at 0 0 270)
			(unlocked yes)
			(layer "B.Fab")
			(hide yes)
			(effects
				(font
					(size 1 1)
					(thickness 0.15)
				)
				(justify mirror)
			)
		)
		(property "Val" "100n"
			(at 0 0 270)
			(unlocked yes)
			(layer "B.Fab")
			(hide yes)
			(effects
				(font
					(size 1 1)
					(thickness 0.15)
				)
				(justify mirror)
			)
		)
		(property "License" "Apache-2.0"
			(at 0 0 270)
			(unlocked yes)
			(layer "B.Fab")
			(hide yes)
			(effects
				(font
					(size 1 1)
					(thickness 0.15)
				)
				(justify mirror)
			)
		)
		(property "Author" "Antmicro"
			(at 0 0 270)
			(unlocked yes)
			(layer "B.Fab")
			(hide yes)
			(effects
				(font
					(size 1 1)
					(thickness 0.15)
				)
				(justify mirror)
			)
		)
		(property "Voltage" "50V"
			(at 0 0 270)
			(unlocked yes)
			(layer "B.Fab")
			(hide yes)
			(effects
				(font
					(size 1 1)
					(thickness 0.15)
				)
				(justify mirror)
			)
		)
		(property "Dielectric" "X5R"
			(at 0 0 270)
			(unlocked yes)
			(layer "B.Fab")
			(hide yes)
			(effects
				(font
					(size 1 1)
					(thickness 0.15)
				)
				(justify mirror)
			)
		)
		(sheetname "/SoM_IO2/")
		(sheetfile "som_io2.kicad_sch")
		(attr smd)
		(fp_poly
			(pts
				(xy -0.925 0.47) (xy 0.925 0.47) (xy 0.925 -0.47) (xy -0.925 -0.47)
			)
			(stroke
				(width 0.05)
				(type default)
			)
			(fill no)
			(layer "B.CrtYd")
		)
		(fp_line
			(start 0.504 -0.248)
			(end -0.494 -0.248)
			(stroke
				(width 0.15)
				(type solid)
			)
			(layer "B.Fab")
		)
		(fp_line
			(start -0.494 -0.248)
			(end -0.494 0.25)
			(stroke
				(width 0.15)
				(type solid)
			)
			(layer "B.Fab")
		)
		(fp_line
			(start 0.504 0.25)
			(end 0.504 -0.248)
			(stroke
				(width 0.15)
				(type solid)
			)
			(layer "B.Fab")
		)
		(fp_line
			(start -0.494 0.25)
			(end 0.504 0.25)
			(stroke
				(width 0.15)
				(type solid)
			)
			(layer "B.Fab")
		)
		(fp_text user "Author: Antmicro"
			(at -0.939 -3.399 90)
			(layer "B.Fab")
			(effects
				(font
					(size 0.7 0.7)
					(thickness 0.15)
				)
				(justify right top mirror)
			)
		)
		(fp_text user "${REFERENCE}"
			(at -0.939 -4.599 90)
			(layer "B.Fab")
			(effects
				(font
					(size 0.7 0.7)
					(thickness 0.15)
				)
				(justify right top mirror)
			)
		)
		(fp_text user "License: Apache-2.0"
			(at -0.939 -5.799 90)
			(layer "B.Fab")
			(effects
				(font
					(size 0.7 0.7)
					(thickness 0.15)
				)
				(justify right top mirror)
			)
		)
		(pad "1" smd roundrect
			(at -0.48 0 90)
			(size 0.59 0.64)
			(layers "B.Cu" "B.Mask" "B.Paste")
			(roundrect_rratio 0.25)
			(net 1253 "/SoM_IO2/DP1.AUX_C-")
			(pintype "passive")
		)
		(pad "2" smd roundrect
			(at 0.48 0 90)
			(size 0.59 0.64)
			(layers "B.Cu" "B.Mask" "B.Paste")
			(roundrect_rratio 0.25)
			(net 738 "/Expansion connector/DP1.AUX-")
			(pintype "passive")
		)
	)
	(footprint "antmicro-footprints:R_0402_1005Metric"
		(layer "B.Cu")
		(at 214.5 84.3 90)
		(descr "Resistor SMD 0402")
		(tags "resistor SMD 0402")
		(property "Reference" "R136"
			(at -1 1.63 90)
			(layer "B.SilkS")
			(effects
				(font
					(size 0.7 0.7)
					(thickness 0.15)
				)
				(justify right top mirror)
			)
		)
		(property "Value" "R_1k_0402"
			(at -1.011843 -1.772047 90)
			(layer "B.Fab")
			(effects
				(font
					(size 0.7 0.7)
					(thickness 0.15)
				)
				(justify right top mirror)
			)
		)
		(property "Datasheet" "https://www.bourns.com/docs/product-datasheets/cr.pdf"
			(at 0 0 90)
			(layer "B.Fab")
			(hide yes)
			(effects
				(font
					(size 1.27 1.27)
					(thickness 0.15)
				)
				(justify mirror)
			)
		)
		(property "Description" "SMD Chip Resistor, 1 kohm, ± 1%, 63 mW, 0402 [1005 Metric], Thick Film, General Purpose"
			(at 0 0 90)
			(layer "B.Fab")
			(hide yes)
			(effects
				(font
					(size 1.27 1.27)
					(thickness 0.15)
				)
				(justify mirror)
			)
		)
		(property "Manufacturer" "Bourns"
			(at 0 0 270)
			(unlocked yes)
			(layer "B.Fab")
			(hide yes)
			(effects
				(font
					(size 1 1)
					(thickness 0.15)
				)
				(justify mirror)
			)
		)
		(property "MPN" "CR0402-FX-1001GLF"
			(at 0 0 270)
			(unlocked yes)
			(layer "B.Fab")
			(hide yes)
			(effects
				(font
					(size 1 1)
					(thickness 0.15)
				)
				(justify mirror)
			)
		)
		(property "Val" "1k"
			(at 0 0 270)
			(unlocked yes)
			(layer "B.Fab")
			(hide yes)
			(effects
				(font
					(size 1 1)
					(thickness 0.15)
				)
				(justify mirror)
			)
		)
		(property "License" "Apache-2.0"
			(at 0 0 270)
			(unlocked yes)
			(layer "B.Fab")
			(hide yes)
			(effects
				(font
					(size 1 1)
					(thickness 0.15)
				)
				(justify mirror)
			)
		)
		(property "Author" "Antmicro"
			(at 0 0 270)
			(unlocked yes)
			(layer "B.Fab")
			(hide yes)
			(effects
				(font
					(size 1 1)
					(thickness 0.15)
				)
				(justify mirror)
			)
		)
		(property "Tolerance" "1%"
			(at 0 0 270)
			(unlocked yes)
			(layer "B.Fab")
			(hide yes)
			(effects
				(font
					(size 1 1)
					(thickness 0.15)
				)
				(justify mirror)
			)
		)
		(sheetname "/USB DP Alt mode/")
		(sheetfile "usb_dp.kicad_sch")
		(attr smd exclude_from_pos_files exclude_from_bom dnp)
		(fp_rect
			(start -0.925 0.47)
			(end 0.925 -0.47)
			(stroke
				(width 0.05)
				(type default)
			)
			(fill no)
			(layer "B.CrtYd")
		)
		(fp_rect
			(start -0.5 0.25)
			(end 0.5 -0.25)
			(stroke
				(width 0.15)
				(type solid)
			)
			(fill no)
			(layer "B.Fab")
		)
		(fp_text user "${REFERENCE}"
			(at -0.95 -3.168 90)
			(layer "B.Fab")
			(effects
				(font
					(size 0.7 0.7)
					(thickness 0.15)
				)
				(justify right top mirror)
			)
		)
		(fp_text user "License: Apache-2.0"
			(at -0.95 -5.169 90)
			(layer "B.Fab")
			(effects
				(font
					(size 0.7 0.7)
					(thickness 0.15)
				)
				(justify right top mirror)
			)
		)
		(fp_text user "Author: Antmicro"
			(at -0.95 -4.169 90)
			(layer "B.Fab")
			(effects
				(font
					(size 0.7 0.7)
					(thickness 0.15)
				)
				(justify right top mirror)
			)
		)
		(pad "1" smd roundrect
			(at -0.48 0 90)
			(size 0.59 0.64)
			(layers "B.Cu" "B.Mask" "B.Paste")
			(roundrect_rratio 0.25)
			(net 967 "/USB DP Alt mode/USBC1_DPEQ1")
			(pintype "passive")
		)
		(pad "2" smd roundrect
			(at 0.48 0 90)
			(size 0.59 0.64)
			(layers "B.Cu" "B.Mask" "B.Paste")
			(roundrect_rratio 0.25)
			(net 2 "+3V3")
			(pintype "passive")
		)
	)
	(footprint "antmicro-footprints:C_0402_1005Metric"
		(layer "B.Cu")
		(at 92.680003 105.5 -90)
		(descr "Capacitor SMD 0402")
		(tags "capacitor SMD 0402")
		(property "Reference" "C328"
			(at 0.9 -0.4 90)
			(layer "B.SilkS")
			(effects
				(font
					(size 0.7 0.7)
					(thickness 0.15)
				)
				(justify left bottom mirror)
			)
		)
		(property "Value" "C_100n_0402"
			(at -1.022927 -2.155213 90)
			(layer "B.Fab")
			(effects
				(font
					(size 0.7 0.7)
					(thickness 0.15)
				)
				(justify left bottom mirror)
			)
		)
		(property "Datasheet" "https://www.murata.com/products/productdetail?partno=GRM155R61H104KE14%23"
			(at 0 0 90)
			(layer "B.Fab")
			(hide yes)
			(effects
				(font
					(size 1.27 1.27)
					(thickness 0.15)
				)
				(justify mirror)
			)
		)
		(property "Description" "SMD Multilayer Ceramic Capacitor, 0.1 µF, 50 V, 0402 [1005 Metric], ± 10%, X5R, GRM Series"
			(at 0 0 90)
			(layer "B.Fab")
			(hide yes)
			(effects
				(font
					(size 1.27 1.27)
					(thickness 0.15)
				)
				(justify mirror)
			)
		)
		(property "Manufacturer" "Murata"
			(at 0 0 90)
			(unlocked yes)
			(layer "B.Fab")
			(hide yes)
			(effects
				(font
					(size 1 1)
					(thickness 0.15)
				)
				(justify mirror)
			)
		)
		(property "MPN" "GRM155R61H104KE14D"
			(at 0 0 90)
			(unlocked yes)
			(layer "B.Fab")
			(hide yes)
			(effects
				(font
					(size 1 1)
					(thickness 0.15)
				)
				(justify mirror)
			)
		)
		(property "Val" "100n"
			(at 0 0 90)
			(unlocked yes)
			(layer "B.Fab")
			(hide yes)
			(effects
				(font
					(size 1 1)
					(thickness 0.15)
				)
				(justify mirror)
			)
		)
		(property "License" "Apache-2.0"
			(at 0 0 90)
			(unlocked yes)
			(layer "B.Fab")
			(hide yes)
			(effects
				(font
					(size 1 1)
					(thickness 0.15)
				)
				(justify mirror)
			)
		)
		(property "Author" "Antmicro"
			(at 0 0 90)
			(unlocked yes)
			(layer "B.Fab")
			(hide yes)
			(effects
				(font
					(size 1 1)
					(thickness 0.15)
				)
				(justify mirror)
			)
		)
		(property "Voltage" "50V"
			(at 0 0 90)
			(unlocked yes)
			(layer "B.Fab")
			(hide yes)
			(effects
				(font
					(size 1 1)
					(thickness 0.15)
				)
				(justify mirror)
			)
		)
		(property "Dielectric" "X5R"
			(at 0 0 90)
			(unlocked yes)
			(layer "B.Fab")
			(hide yes)
			(effects
				(font
					(size 1 1)
					(thickness 0.15)
				)
				(justify mirror)
			)
		)
		(sheetname "/SoM_IO2/")
		(sheetfile "som_io2.kicad_sch")
		(attr smd)
		(fp_poly
			(pts
				(xy -0.925 0.47) (xy 0.925 0.47) (xy 0.925 -0.47) (xy -0.925 -0.47)
			)
			(stroke
				(width 0.05)
				(type default)
			)
			(fill no)
			(layer "B.CrtYd")
		)
		(fp_line
			(start -0.494 0.25)
			(end 0.504 0.25)
			(stroke
				(width 0.15)
				(type solid)
			)
			(layer "B.Fab")
		)
		(fp_line
			(start 0.504 0.25)
			(end 0.504 -0.248)
			(stroke
				(width 0.15)
				(type solid)
			)
			(layer "B.Fab")
		)
		(fp_line
			(start -0.494 -0.248)
			(end -0.494 0.25)
			(stroke
				(width 0.15)
				(type solid)
			)
			(layer "B.Fab")
		)
		(fp_line
			(start 0.504 -0.248)
			(end -0.494 -0.248)
			(stroke
				(width 0.15)
				(type solid)
			)
			(layer "B.Fab")
		)
		(fp_text user "License: Apache-2.0"
			(at -0.939 -5.799 90)
			(layer "B.Fab")
			(effects
				(font
					(size 0.7 0.7)
					(thickness 0.15)
				)
				(justify left bottom mirror)
			)
		)
		(fp_text user "${REFERENCE}"
			(at -0.939 -4.599 90)
			(layer "B.Fab")
			(effects
				(font
					(size 0.7 0.7)
					(thickness 0.15)
				)
				(justify left bottom mirror)
			)
		)
		(fp_text user "Author: Antmicro"
			(at -0.939 -3.399 90)
			(layer "B.Fab")
			(effects
				(font
					(size 0.7 0.7)
					(thickness 0.15)
				)
				(justify left bottom mirror)
			)
		)
		(pad "1" smd roundrect
			(at -0.48 0 270)
			(size 0.59 0.64)
			(layers "B.Cu" "B.Mask" "B.Paste")
			(roundrect_rratio 0.25)
			(net 603 "/Expansion connector/DP1.TX0-")
			(pintype "passive")
		)
		(pad "2" smd roundrect
			(at 0.48 0 270)
			(size 0.59 0.64)
			(layers "B.Cu" "B.Mask" "B.Paste")
			(roundrect_rratio 0.25)
			(net 1248 "/SoM_IO2/DP1.TX0_C-")
			(pintype "passive")
		)
	)
	(footprint "antmicro-footprints:R_0402_1005Metric"
		(layer "B.Cu")
		(at 200.8 125.2 180)
		(descr "Resistor SMD 0402")
		(tags "resistor SMD 0402")
		(property "Reference" "R324"
			(at -3.8 -0.398197 0)
			(layer "B.SilkS")
			(effects
				(font
					(size 0.7 0.7)
					(thickness 0.15)
				)
				(justify left bottom mirror)
			)
		)
		(property "Value" "R_200k_0402"
			(at -1.011843 -1.772046 0)
			(layer "B.Fab")
			(effects
				(font
					(size 0.7 0.7)
					(thickness 0.15)
				)
				(justify left bottom mirror)
			)
		)
		(property "Datasheet" "https://www.bourns.com/docs/product-datasheets/cr.pdf"
			(at 0 0 0)
			(layer "B.Fab")
			(hide yes)
			(effects
				(font
					(size 1.27 1.27)
					(thickness 0.15)
				)
				(justify mirror)
			)
		)
		(property "Description" "SMD Chip Resistor, 200 kohm, ± 1%, 62.5 mW, 0402 [1005 Metric], Thick Film, General Purpose"
			(at 0 0 0)
			(layer "B.Fab")
			(hide yes)
			(effects
				(font
					(size 1.27 1.27)
					(thickness 0.15)
				)
				(justify mirror)
			)
		)
		(property "MPN" "CR0402-FX-2003GLF"
			(at 0 0 0)
			(unlocked yes)
			(layer "B.Fab")
			(hide yes)
			(effects
				(font
					(size 1 1)
					(thickness 0.15)
				)
				(justify mirror)
			)
		)
		(property "Manufacturer" "Bourns"
			(at 0 0 0)
			(unlocked yes)
			(layer "B.Fab")
			(hide yes)
			(effects
				(font
					(size 1 1)
					(thickness 0.15)
				)
				(justify mirror)
			)
		)
		(property "License" "Apache-2.0"
			(at 0 0 0)
			(unlocked yes)
			(layer "B.Fab")
			(hide yes)
			(effects
				(font
					(size 1 1)
					(thickness 0.15)
				)
				(justify mirror)
			)
		)
		(property "Author" "Antmicro"
			(at 0 0 0)
			(unlocked yes)
			(layer "B.Fab")
			(hide yes)
			(effects
				(font
					(size 1 1)
					(thickness 0.15)
				)
				(justify mirror)
			)
		)
		(property "Val" "200k"
			(at 0 0 0)
			(unlocked yes)
			(layer "B.Fab")
			(hide yes)
			(effects
				(font
					(size 1 1)
					(thickness 0.15)
				)
				(justify mirror)
			)
		)
		(property "Tolerance" "1%"
			(at 0 0 0)
			(unlocked yes)
			(layer "B.Fab")
			(hide yes)
			(effects
				(font
					(size 1 1)
					(thickness 0.15)
				)
				(justify mirror)
			)
		)
		(sheetname "/USB Hub/")
		(sheetfile "usb_hub.kicad_sch")
		(attr smd)
		(fp_poly
			(pts
				(xy -0.925 0.47) (xy -0.925 -0.47) (xy 0.925 -0.47) (xy 0.925 0.47)
			)
			(stroke
				(width 0.05)
				(type default)
			)
			(fill no)
			(layer "B.CrtYd")
		)
		(fp_poly
			(pts
				(xy -0.5 0.25) (xy -0.5 -0.25) (xy 0.5 -0.25) (xy 0.5 0.25)
			)
			(stroke
				(width 0.15)
				(type solid)
			)
			(fill no)
			(layer "B.Fab")
		)
		(fp_text user "License: Apache-2.0"
			(at -0.949999 -5.169 0)
			(layer "B.Fab")
			(effects
				(font
					(size 0.7 0.7)
					(thickness 0.15)
				)
				(justify left bottom mirror)
			)
		)
		(fp_text user "Author: Antmicro"
			(at -0.95 -4.169 0)
			(layer "B.Fab")
			(effects
				(font
					(size 0.7 0.7)
					(thickness 0.15)
				)
				(justify left bottom mirror)
			)
		)
		(fp_text user "${REFERENCE}"
			(at -0.95 -3.168 0)
			(layer "B.Fab")
			(effects
				(font
					(size 0.7 0.7)
					(thickness 0.15)
				)
				(justify left bottom mirror)
			)
		)
		(pad "1" smd roundrect
			(at -0.48 0 180)
			(size 0.59 0.64)
			(layers "B.Cu" "B.Mask" "B.Paste")
			(roundrect_rratio 0.25)
			(net 1 "GND")
			(pintype "passive")
		)
		(pad "2" smd roundrect
			(at 0.48 0 180)
			(size 0.59 0.64)
			(layers "B.Cu" "B.Mask" "B.Paste")
			(roundrect_rratio 0.25)
			(net 925 "/USB Hub/HUB_SPI_D0")
			(pintype "passive")
		)
	)
	(footprint "antmicro-footprints:C_0402_1005Metric"
		(layer "B.Cu")
		(at 220.3 82.3 -90)
		(descr "Capacitor SMD 0402")
		(tags "capacitor SMD 0402")
		(property "Reference" "C44"
			(at 0.9 -0.5 90)
			(layer "B.SilkS")
			(effects
				(font
					(size 0.7 0.7)
					(thickness 0.15)
				)
				(justify left bottom mirror)
			)
		)
		(property "Value" "C_100n_0402"
			(at -1.022927 -2.155213 90)
			(layer "B.Fab")
			(effects
				(font
					(size 0.7 0.7)
					(thickness 0.15)
				)
				(justify left bottom mirror)
			)
		)
		(property "Datasheet" "https://www.murata.com/products/productdetail?partno=GRM155R61H104KE14%23"
			(at 0 0 90)
			(layer "B.Fab")
			(hide yes)
			(effects
				(font
					(size 1.27 1.27)
					(thickness 0.15)
				)
				(justify mirror)
			)
		)
		(property "Description" "SMD Multilayer Ceramic Capacitor, 0.1 µF, 50 V, 0402 [1005 Metric], ± 10%, X5R, GRM Series"
			(at 0 0 90)
			(layer "B.Fab")
			(hide yes)
			(effects
				(font
					(size 1.27 1.27)
					(thickness 0.15)
				)
				(justify mirror)
			)
		)
		(property "Manufacturer" "Murata"
			(at 0 0 90)
			(unlocked yes)
			(layer "B.Fab")
			(hide yes)
			(effects
				(font
					(size 1 1)
					(thickness 0.15)
				)
				(justify mirror)
			)
		)
		(property "MPN" "GRM155R61H104KE14D"
			(at 0 0 90)
			(unlocked yes)
			(layer "B.Fab")
			(hide yes)
			(effects
				(font
					(size 1 1)
					(thickness 0.15)
				)
				(justify mirror)
			)
		)
		(property "Val" "100n"
			(at 0 0 90)
			(unlocked yes)
			(layer "B.Fab")
			(hide yes)
			(effects
				(font
					(size 1 1)
					(thickness 0.15)
				)
				(justify mirror)
			)
		)
		(property "License" "Apache-2.0"
			(at 0 0 90)
			(unlocked yes)
			(layer "B.Fab")
			(hide yes)
			(effects
				(font
					(size 1 1)
					(thickness 0.15)
				)
				(justify mirror)
			)
		)
		(property "Author" "Antmicro"
			(at 0 0 90)
			(unlocked yes)
			(layer "B.Fab")
			(hide yes)
			(effects
				(font
					(size 1 1)
					(thickness 0.15)
				)
				(justify mirror)
			)
		)
		(property "Voltage" "50V"
			(at 0 0 90)
			(unlocked yes)
			(layer "B.Fab")
			(hide yes)
			(effects
				(font
					(size 1 1)
					(thickness 0.15)
				)
				(justify mirror)
			)
		)
		(property "Dielectric" "X5R"
			(at 0 0 90)
			(unlocked yes)
			(layer "B.Fab")
			(hide yes)
			(effects
				(font
					(size 1 1)
					(thickness 0.15)
				)
				(justify mirror)
			)
		)
		(sheetname "/USB Debug, PD/")
		(sheetfile "usb_debug_pd.kicad_sch")
		(attr smd)
		(fp_poly
			(pts
				(xy -0.925 0.47) (xy 0.925 0.47) (xy 0.925 -0.47) (xy -0.925 -0.47)
			)
			(stroke
				(width 0.05)
				(type default)
			)
			(fill no)
			(layer "B.CrtYd")
		)
		(fp_line
			(start -0.494 0.25)
			(end 0.504 0.25)
			(stroke
				(width 0.15)
				(type solid)
			)
			(layer "B.Fab")
		)
		(fp_line
			(start 0.504 0.25)
			(end 0.504 -0.248)
			(stroke
				(width 0.15)
				(type solid)
			)
			(layer "B.Fab")
		)
		(fp_line
			(start -0.494 -0.248)
			(end -0.494 0.25)
			(stroke
				(width 0.15)
				(type solid)
			)
			(layer "B.Fab")
		)
		(fp_line
			(start 0.504 -0.248)
			(end -0.494 -0.248)
			(stroke
				(width 0.15)
				(type solid)
			)
			(layer "B.Fab")
		)
		(fp_text user "License: Apache-2.0"
			(at -0.939 -5.799 90)
			(layer "B.Fab")
			(effects
				(font
					(size 0.7 0.7)
					(thickness 0.15)
				)
				(justify left bottom mirror)
			)
		)
		(fp_text user "${REFERENCE}"
			(at -0.939 -4.599 90)
			(layer "B.Fab")
			(effects
				(font
					(size 0.7 0.7)
					(thickness 0.15)
				)
				(justify left bottom mirror)
			)
		)
		(fp_text user "Author: Antmicro"
			(at -0.939 -3.399 90)
			(layer "B.Fab")
			(effects
				(font
					(size 0.7 0.7)
					(thickness 0.15)
				)
				(justify left bottom mirror)
			)
		)
		(pad "1" smd roundrect
			(at -0.48 0 270)
			(size 0.59 0.64)
			(layers "B.Cu" "B.Mask" "B.Paste")
			(roundrect_rratio 0.25)
			(net 334 "/USB Debug, PD/FTDI_3V3")
			(pintype "passive")
		)
		(pad "2" smd roundrect
			(at 0.48 0 270)
			(size 0.59 0.64)
			(layers "B.Cu" "B.Mask" "B.Paste")
			(roundrect_rratio 0.25)
			(net 1 "GND")
			(pintype "passive")
		)
	)
	(footprint "antmicro-footprints:C_0603_1608Metric_EIA"
		(layer "B.Cu")
		(at 112.11 69.49 180)
		(descr "Capacitor SMD 0603, IPC-7351 Density Level A")
		(tags "Capacitor 0603")
		(property "Reference" "C19"
			(at -1.09 0.89 0)
			(layer "B.SilkS")
			(effects
				(font
					(size 0.7 0.7)
					(thickness 0.15)
				)
				(justify left bottom mirror)
			)
		)
		(property "Value" "C_22u_16V_0603"
			(at -1.42757 -1.770288 0)
			(layer "B.Fab")
			(effects
				(font
					(size 0.7 0.7)
					(thickness 0.15)
				)
				(justify left bottom mirror)
			)
		)
		(property "Datasheet" "https://product.samsungsem.com/mlcc/CL10A226MO7JZN.do"
			(at 0 0 0)
			(layer "B.Fab")
			(hide yes)
			(effects
				(font
					(size 1.27 1.27)
					(thickness 0.15)
				)
				(justify mirror)
			)
		)
		(property "Description" "SMD Multilayer Ceramic Capacitor"
			(at 0 0 0)
			(layer "B.Fab")
			(hide yes)
			(effects
				(font
					(size 1.27 1.27)
					(thickness 0.15)
				)
				(justify mirror)
			)
		)
		(property "MPN" "CL10A226MO7JZNC"
			(at 0 0 180)
			(unlocked yes)
			(layer "B.Fab")
			(hide yes)
			(effects
				(font
					(size 1 1)
					(thickness 0.15)
				)
				(justify mirror)
			)
		)
		(property "Manufacturer" "Samsung Electro-Mechanics"
			(at 0 0 180)
			(unlocked yes)
			(layer "B.Fab")
			(hide yes)
			(effects
				(font
					(size 1 1)
					(thickness 0.15)
				)
				(justify mirror)
			)
		)
		(property "License" "Apache-2.0"
			(at 0 0 180)
			(unlocked yes)
			(layer "B.Fab")
			(hide yes)
			(effects
				(font
					(size 1 1)
					(thickness 0.15)
				)
				(justify mirror)
			)
		)
		(property "Author" "Antmicro"
			(at 0 0 180)
			(unlocked yes)
			(layer "B.Fab")
			(hide yes)
			(effects
				(font
					(size 1 1)
					(thickness 0.15)
				)
				(justify mirror)
			)
		)
		(property "Val" "22u"
			(at 0 0 180)
			(unlocked yes)
			(layer "B.Fab")
			(hide yes)
			(effects
				(font
					(size 1 1)
					(thickness 0.15)
				)
				(justify mirror)
			)
		)
		(property "Voltage" "16V"
			(at 0 0 180)
			(unlocked yes)
			(layer "B.Fab")
			(hide yes)
			(effects
				(font
					(size 1 1)
					(thickness 0.15)
				)
				(justify mirror)
			)
		)
		(property "Dielectric" "X7R"
			(at 0 0 180)
			(unlocked yes)
			(layer "B.Fab")
			(hide yes)
			(effects
				(font
					(size 1 1)
					(thickness 0.15)
				)
				(justify mirror)
			)
		)
		(property "Public" "False"
			(at 0 0 180)
			(unlocked yes)
			(layer "B.Fab")
			(hide yes)
			(effects
				(font
					(size 1 1)
					(thickness 0.15)
				)
				(justify mirror)
			)
		)
		(sheetname "/SoM_Power/")
		(sheetfile "som_power.kicad_sch")
		(attr smd)
		(fp_line
			(start -0.15 0.55)
			(end 0.15 0.55)
			(stroke
				(width 0.15)
				(type solid)
			)
			(layer "B.SilkS")
		)
		(fp_line
			(start -0.15 -0.55)
			(end 0.15 -0.55)
			(stroke
				(width 0.15)
				(type solid)
			)
			(layer "B.SilkS")
		)
		(fp_rect
			(start -1.25 0.65)
			(end 1.25 -0.65)
			(stroke
				(width 0.05)
				(type solid)
			)
			(fill no)
			(layer "B.CrtYd")
		)
		(fp_rect
			(start -0.8 0.45)
			(end 0.8 -0.45)
			(stroke
				(width 0.15)
				(type solid)
			)
			(fill no)
			(layer "B.Fab")
		)
		(fp_text user "${REFERENCE}"
			(at -1.682 -3.895 0)
			(layer "B.Fab")
			(effects
				(font
					(size 0.7 0.7)
					(thickness 0.15)
				)
				(justify left bottom mirror)
			)
		)
		(fp_text user "Author: Antmicro"
			(at -1.682 -4.894 0)
			(layer "B.Fab")
			(effects
				(font
					(size 0.7 0.7)
					(thickness 0.15)
				)
				(justify left bottom mirror)
			)
		)
		(fp_text user "License: Apache-2.0"
			(at -1.682 -5.895 0)
			(layer "B.Fab")
			(effects
				(font
					(size 0.7 0.7)
					(thickness 0.15)
				)
				(justify left bottom mirror)
			)
		)
		(pad "1" smd roundrect
			(at -0.7 0 180)
			(size 0.8 1.1)
			(layers "B.Cu" "B.Mask" "B.Paste")
			(roundrect_rratio 0.2)
			(net 1 "GND")
			(pintype "passive")
		)
		(pad "2" smd roundrect
			(at 0.7 0 180)
			(size 0.8 1.1)
			(layers "B.Cu" "B.Mask" "B.Paste")
			(roundrect_rratio 0.2)
			(net 213 "+5V_SOM")
			(pintype "passive")
		)
	)
	(footprint "antmicro-footprints:Fiducial_1mm_Mask3mm"
		(layer "B.Cu")
		(at 65.9 55.63 180)
		(descr "Circular Fiducial, 1.5mm bare copper, 3mm soldermask opening")
		(tags "fiducial")
		(property "Reference" "FD8"
			(at 1.52 -0.43 0)
			(layer "B.SilkS")
			(effects
				(font
					(size 0.7 0.7)
					(thickness 0.15)
				)
				(justify left bottom mirror)
			)
		)
		(property "Value" "Fiducial_1mm_Mask3mm"
			(at 0 -2.603 0)
			(layer "B.Fab")
			(effects
				(font
					(size 0.7 0.7)
					(thickness 0.15)
				)
				(justify left bottom mirror)
			)
		)
		(property "Description" "Fiducial mask"
			(at 0 0 0)
			(layer "B.Fab")
			(hide yes)
			(effects
				(font
					(size 1.27 1.27)
					(thickness 0.15)
				)
				(justify mirror)
			)
		)
		(property "Author" "Antmicro"
			(at 0 0 0)
			(unlocked yes)
			(layer "B.Fab")
			(hide yes)
			(effects
				(font
					(size 1 1)
					(thickness 0.15)
				)
				(justify mirror)
			)
		)
		(property "License" "Apache-2.0"
			(at 0 0 0)
			(unlocked yes)
			(layer "B.Fab")
			(hide yes)
			(effects
				(font
					(size 1 1)
					(thickness 0.15)
				)
				(justify mirror)
			)
		)
		(sheetname "/")
		(sheetfile "jetson-agx-thor-baseboard.kicad_sch")
		(attr exclude_from_pos_files exclude_from_bom)
		(fp_circle
			(center 0 0)
			(end 1.5 0)
			(stroke
				(width 0.05)
				(type solid)
			)
			(fill no)
			(layer "B.CrtYd")
		)
		(fp_circle
			(center 0 0)
			(end 1.5 0)
			(stroke
				(width 0.15)
				(type solid)
			)
			(fill no)
			(layer "B.Fab")
		)
		(fp_text user "License: Apache-2.0"
			(at -1.25 -7.003 0)
			(layer "B.Fab")
			(effects
				(font
					(size 0.7 0.7)
					(thickness 0.15)
				)
				(justify left bottom mirror)
			)
		)
		(fp_text user "${REFERENCE}"
			(at -1.25 -4.603 0)
			(layer "B.Fab")
			(effects
				(font
					(size 0.7 0.7)
					(thickness 0.15)
				)
				(justify left bottom mirror)
			)
		)
		(fp_text user "Author: Antmicro"
			(at -1.25 -5.803 0)
			(layer "B.Fab")
			(effects
				(font
					(size 0.7 0.7)
					(thickness 0.15)
				)
				(justify left bottom mirror)
			)
		)
		(pad "" smd circle
			(at 0 0 180)
			(size 1 1)
			(layers "B.Cu" "B.Mask")
			(solder_mask_margin 1)
			(clearance 1)
		)
	)
	(footprint "antmicro-footprints:TP_SMD_0.75mm"
		(layer "B.Cu")
		(at 88 65.9)
		(property "Reference" "TP103"
			(at -2.2 -1.3 0)
			(layer "B.SilkS")
			(effects
				(font
					(size 0.7 0.7)
					(thickness 0.15)
				)
				(justify right top mirror)
			)
		)
		(property "Value" "TP_0.75mm_SMD"
			(at 0 -1.2 0)
			(layer "B.Fab")
			(effects
				(font
					(size 0.7 0.7)
					(thickness 0.15)
				)
				(justify right top mirror)
			)
		)
		(property "Description" "SMT test point"
			(at 0 0 0)
			(layer "B.Fab")
			(hide yes)
			(effects
				(font
					(size 1.27 1.27)
					(thickness 0.15)
				)
				(justify mirror)
			)
		)
		(property "MPN" ""
			(at 0 0 180)
			(unlocked yes)
			(layer "B.Fab")
			(hide yes)
			(effects
				(font
					(size 1 1)
					(thickness 0.15)
				)
				(justify mirror)
			)
		)
		(property "Manufacturer" ""
			(at 0 0 180)
			(unlocked yes)
			(layer "B.Fab")
			(hide yes)
			(effects
				(font
					(size 1 1)
					(thickness 0.15)
				)
				(justify mirror)
			)
		)
		(property "Author" "Antmicro"
			(at 0 0 180)
			(unlocked yes)
			(layer "B.Fab")
			(hide yes)
			(effects
				(font
					(size 1 1)
					(thickness 0.15)
				)
				(justify mirror)
			)
		)
		(property "License" "Apache-2.0"
			(at 0 0 180)
			(unlocked yes)
			(layer "B.Fab")
			(hide yes)
			(effects
				(font
					(size 1 1)
					(thickness 0.15)
				)
				(justify mirror)
			)
		)
		(sheetname "/SoM_IO/")
		(sheetfile "som_io.kicad_sch")
		(attr exclude_from_pos_files exclude_from_bom)
		(fp_circle
			(center 0 0)
			(end 0.475 0)
			(stroke
				(width 0.05)
				(type default)
			)
			(fill no)
			(layer "B.CrtYd")
		)
		(fp_text user "${REFERENCE}"
			(at -0.4 -2.7 0)
			(layer "B.Fab")
			(effects
				(font
					(size 0.7 0.7)
					(thickness 0.15)
				)
				(justify right top mirror)
			)
		)
		(fp_text user "Author: Antmicro"
			(at -0.4 -3.901 0)
			(layer "B.Fab")
			(effects
				(font
					(size 0.7 0.7)
					(thickness 0.15)
				)
				(justify right top mirror)
			)
		)
		(fp_text user "License: Apache-2.0"
			(at -0.4 -5.101 0)
			(layer "B.Fab")
			(effects
				(font
					(size 0.7 0.7)
					(thickness 0.15)
				)
				(justify right top mirror)
			)
		)
		(pad "1" smd circle
			(at 0 0)
			(size 0.75 0.75)
			(layers "B.Cu" "B.Mask")
			(net 48 "/SoM_IO/I2C1_SCL_1V8")
			(pinfunction "1")
			(pintype "passive")
		)
	)
	(footprint "antmicro-footprints:R_0402_1005Metric"
		(layer "B.Cu")
		(at 61.2 66.5 -90)
		(descr "Resistor SMD 0402")
		(tags "resistor SMD 0402")
		(property "Reference" "R391"
			(at -9.7 0 90)
			(layer "B.SilkS")
			(effects
				(font
					(size 0.7 0.7)
					(thickness 0.15)
				)
				(justify left bottom mirror)
			)
		)
		(property "Value" "R_2k2_0402"
			(at -1.011843 -1.772047 90)
			(layer "B.Fab")
			(effects
				(font
					(size 0.7 0.7)
					(thickness 0.15)
				)
				(justify left bottom mirror)
			)
		)
		(property "Datasheet" "https://www.bourns.com/docs/product-datasheets/cr.pdf"
			(at 0 0 90)
			(layer "B.Fab")
			(hide yes)
			(effects
				(font
					(size 1.27 1.27)
					(thickness 0.15)
				)
				(justify mirror)
			)
		)
		(property "Description" "SMD Chip Resistor, 2.2 kohm, ± 1%, 62.5 mW, 0402 [1005 Metric], Thick Film, General Purpose"
			(at 0 0 90)
			(layer "B.Fab")
			(hide yes)
			(effects
				(font
					(size 1.27 1.27)
					(thickness 0.15)
				)
				(justify mirror)
			)
		)
		(property "MPN" "CR0402-FX-2201GLF"
			(at 0 0 90)
			(unlocked yes)
			(layer "B.Fab")
			(hide yes)
			(effects
				(font
					(size 1 1)
					(thickness 0.15)
				)
				(justify mirror)
			)
		)
		(property "Manufacturer" "Bourns"
			(at 0 0 90)
			(unlocked yes)
			(layer "B.Fab")
			(hide yes)
			(effects
				(font
					(size 1 1)
					(thickness 0.15)
				)
				(justify mirror)
			)
		)
		(property "License" "Apache-2.0"
			(at 0 0 90)
			(unlocked yes)
			(layer "B.Fab")
			(hide yes)
			(effects
				(font
					(size 1 1)
					(thickness 0.15)
				)
				(justify mirror)
			)
		)
		(property "Author" "Antmicro"
			(at 0 0 90)
			(unlocked yes)
			(layer "B.Fab")
			(hide yes)
			(effects
				(font
					(size 1 1)
					(thickness 0.15)
				)
				(justify mirror)
			)
		)
		(property "Val" "2k2"
			(at 0 0 90)
			(unlocked yes)
			(layer "B.Fab")
			(hide yes)
			(effects
				(font
					(size 1 1)
					(thickness 0.15)
				)
				(justify mirror)
			)
		)
		(property "Tolerance" "1%"
			(at 0 0 90)
			(unlocked yes)
			(layer "B.Fab")
			(hide yes)
			(effects
				(font
					(size 1 1)
					(thickness 0.15)
				)
				(justify mirror)
			)
		)
		(sheetname "/CSI/")
		(sheetfile "csi.kicad_sch")
		(attr smd)
		(fp_rect
			(start -0.925 0.47)
			(end 0.925 -0.47)
			(stroke
				(width 0.05)
				(type default)
			)
			(fill no)
			(layer "B.CrtYd")
		)
		(fp_rect
			(start -0.5 0.25)
			(end 0.5 -0.25)
			(stroke
				(width 0.15)
				(type solid)
			)
			(fill no)
			(layer "B.Fab")
		)
		(fp_text user "Author: Antmicro"
			(at -0.95 -4.169 90)
			(layer "B.Fab")
			(effects
				(font
					(size 0.7 0.7)
					(thickness 0.15)
				)
				(justify left bottom mirror)
			)
		)
		(fp_text user "${REFERENCE}"
			(at -0.95 -3.168 90)
			(layer "B.Fab")
			(effects
				(font
					(size 0.7 0.7)
					(thickness 0.15)
				)
				(justify left bottom mirror)
			)
		)
		(fp_text user "License: Apache-2.0"
			(at -0.95 -5.169 90)
			(layer "B.Fab")
			(effects
				(font
					(size 0.7 0.7)
					(thickness 0.15)
				)
				(justify left bottom mirror)
			)
		)
		(pad "1" smd roundrect
			(at -0.48 0 270)
			(size 0.59 0.64)
			(layers "B.Cu" "B.Mask" "B.Paste")
			(roundrect_rratio 0.25)
			(net 979 "/CSI/CSIA_I2C_VCC")
			(pintype "passive")
		)
		(pad "2" smd roundrect
			(at 0.48 0 270)
			(size 0.59 0.64)
			(layers "B.Cu" "B.Mask" "B.Paste")
			(roundrect_rratio 0.25)
			(net 987 "/CSI/SDA_CAM0")
			(pintype "passive")
		)
	)
	(footprint "antmicro-footprints:Tag-Connect_TC2050-IDC-NL_2x5_P1.27mm"
		(locked yes)
		(layer "B.Cu")
		(at 165 65.25 -90)
		(property "Reference" "J20"
			(at 2.89 -3.13 90)
			(layer "B.SilkS")
			(effects
				(font
					(size 0.7 0.7)
					(thickness 0.15)
				)
				(justify left bottom mirror)
			)
		)
		(property "Value" "Tag-Connect_TC2050-IDC-NL_2x5_P1.27mm"
			(at 0 -4.4 90)
			(layer "B.Fab")
			(effects
				(font
					(size 0.7 0.7)
					(thickness 0.15)
				)
				(justify left bottom mirror)
			)
		)
		(property "Datasheet" "https://www.tag-connect.com/wp-content/uploads/bsk-pdf-manager/TC2050-IDC-NL_Datasheet_8.pdf"
			(at 0 0 90)
			(layer "B.Fab")
			(hide yes)
			(effects
				(font
					(size 1.27 1.27)
					(thickness 0.15)
				)
				(justify mirror)
			)
		)
		(property "Description" "Tag Connect 2x5 1.27mm terminal"
			(at 0 0 90)
			(layer "B.Fab")
			(hide yes)
			(effects
				(font
					(size 1.27 1.27)
					(thickness 0.15)
				)
				(justify mirror)
			)
		)
		(property "MPN" "TC2050-IDC-NL"
			(at 0 0 90)
			(unlocked yes)
			(layer "B.Fab")
			(hide yes)
			(effects
				(font
					(size 1 1)
					(thickness 0.15)
				)
				(justify mirror)
			)
		)
		(property "Manufacturer" "Tag Connect"
			(at 0 0 90)
			(unlocked yes)
			(layer "B.Fab")
			(hide yes)
			(effects
				(font
					(size 1 1)
					(thickness 0.15)
				)
				(justify mirror)
			)
		)
		(property "Author" "Antmicro"
			(at 0 0 90)
			(unlocked yes)
			(layer "B.Fab")
			(hide yes)
			(effects
				(font
					(size 1 1)
					(thickness 0.15)
				)
				(justify mirror)
			)
		)
		(property "License" "Apache-2.0"
			(at 0 0 90)
			(unlocked yes)
			(layer "B.Fab")
			(hide yes)
			(effects
				(font
					(size 1 1)
					(thickness 0.15)
				)
				(justify mirror)
			)
		)
		(sheetname "/SoM_IO2/")
		(sheetfile "som_io2.kicad_sch")
		(attr exclude_from_bom)
		(fp_line
			(start -2.2 2.05)
			(end 4.7 2.05)
			(stroke
				(width 0.15)
				(type solid)
			)
			(layer "B.SilkS")
		)
		(fp_line
			(start 4.7 2.05)
			(end 5.1 1.7)
			(stroke
				(width 0.15)
				(type solid)
			)
			(layer "B.SilkS")
		)
		(fp_line
			(start 5.1 1.7)
			(end 5.1 -1.7)
			(stroke
				(width 0.15)
				(type solid)
			)
			(layer "B.SilkS")
		)
		(fp_line
			(start -5.08 0.900001)
			(end -2.2 2.05)
			(stroke
				(width 0.15)
				(type solid)
			)
			(layer "B.SilkS")
		)
		(fp_line
			(start -5.08 -0.8)
			(end -5.08 0.900001)
			(stroke
				(width 0.15)
				(type solid)
			)
			(layer "B.SilkS")
		)
		(fp_line
			(start -3.101001 -1.269)
			(end -3.101 -0.4)
			(stroke
				(width 0.15)
				(type solid)
			)
			(layer "B.SilkS")
		)
		(fp_line
			(start -2.3 -2.049)
			(end -5.08 -0.8)
			(stroke
				(width 0.15)
				(type solid)
			)
			(layer "B.SilkS")
		)
		(fp_line
			(start 4.7 -2.049)
			(end 5.1 -1.7)
			(stroke
				(width 0.15)
				(type solid)
			)
			(layer "B.SilkS")
		)
		(fp_line
			(start 4.7 -2.049)
			(end -2.3 -2.049)
			(stroke
				(width 0.15)
				(type solid)
			)
			(layer "B.SilkS")
		)
		(fp_line
			(start -2.3 2.3)
			(end 4.8 2.3)
			(stroke
				(width 0.05)
				(type solid)
			)
			(layer "B.CrtYd")
		)
		(fp_line
			(start 4.8 2.3)
			(end 5.32 1.8)
			(stroke
				(width 0.05)
				(type solid)
			)
			(layer "B.CrtYd")
		)
		(fp_line
			(start 5.32 1.8)
			(end 5.32 -1.8)
			(stroke
				(width 0.05)
				(type solid)
			)
			(layer "B.CrtYd")
		)
		(fp_line
			(start -5.330001 1.1)
			(end -2.3 2.3)
			(stroke
				(width 0.05)
				(type solid)
			)
			(layer "B.CrtYd")
		)
		(fp_line
			(start -5.33 -1)
			(end -5.330001 1.1)
			(stroke
				(width 0.05)
				(type solid)
			)
			(layer "B.CrtYd")
		)
		(fp_line
			(start -2.4 -2.29)
			(end -5.33 -1)
			(stroke
				(width 0.05)
				(type solid)
			)
			(layer "B.CrtYd")
		)
		(fp_line
			(start 4.8 -2.29)
			(end 5.32 -1.8)
			(stroke
				(width 0.05)
				(type solid)
			)
			(layer "B.CrtYd")
		)
		(fp_line
			(start 4.8 -2.29)
			(end -2.4 -2.29)
			(stroke
				(width 0.05)
				(type solid)
			)
			(layer "B.CrtYd")
		)
		(fp_text user "Author: Antmicro"
			(at -6.223 -7.249001 90)
			(layer "B.Fab")
			(effects
				(font
					(size 0.7 0.7)
					(thickness 0.15)
				)
				(justify left bottom mirror)
			)
		)
		(fp_text user "License: Apache-2.0"
			(at -6.223 -8.449 90)
			(layer "B.Fab")
			(effects
				(font
					(size 0.7 0.7)
					(thickness 0.15)
				)
				(justify left bottom mirror)
			)
		)
		(fp_text user "${REFERENCE}"
			(at -6.223 -6.048999 90)
			(layer "B.Fab")
			(effects
				(font
					(size 0.7 0.7)
					(thickness 0.15)
				)
				(justify left bottom mirror)
			)
		)
		(pad "" np_thru_hole circle
			(at -3.81 0 270)
			(size 0.9906 0.9906)
			(drill 0.9906)
			(layers "*.Cu" "*.Mask")
		)
		(pad "" np_thru_hole circle
			(at 3.809 -1.015 270)
			(size 0.9906 0.9906)
			(drill 0.9906)
			(layers "*.Cu" "*.Mask")
		)
		(pad "" np_thru_hole circle
			(at 3.809 1.016 270)
			(size 0.9906 0.9906)
			(drill 0.9906)
			(layers "*.Cu" "*.Mask")
		)
		(pad "1" connect circle
			(at -2.54 -0.634 270)
			(size 0.7874 0.7874)
			(layers "B.Cu" "B.Mask")
			(net 269 "/SoM_IO2/TC_VCC")
			(pinfunction "1")
			(pintype "passive")
		)
		(pad "2" connect circle
			(at -1.27 -0.634 270)
			(size 0.7874 0.7874)
			(layers "B.Cu" "B.Mask")
			(net 869 "/SoM_IO2/TC_JTAG_TMS")
			(pinfunction "2")
			(pintype "passive")
		)
		(pad "3" connect circle
			(at 0 -0.634 270)
			(size 0.7874 0.7874)
			(layers "B.Cu" "B.Mask")
			(net 1 "GND")
			(pinfunction "3")
			(pintype "passive")
		)
		(pad "4" connect circle
			(at 1.269 -0.634 270)
			(size 0.7874 0.7874)
			(layers "B.Cu" "B.Mask")
			(net 871 "/SoM_IO2/TC_JTAG_TCK")
			(pinfunction "4")
			(pintype "passive")
		)
		(pad "5" connect circle
			(at 2.539 -0.634 270)
			(size 0.7874 0.7874)
			(layers "B.Cu" "B.Mask")
			(net 1 "GND")
			(pinfunction "5")
			(pintype "passive")
		)
		(pad "6" connect circle
			(at 2.539 0.635 270)
			(size 0.7874 0.7874)
			(layers "B.Cu" "B.Mask")
			(net 872 "/SoM_IO2/TC_JTAG_TDO")
			(pinfunction "6")
			(pintype "passive")
		)
		(pad "7" connect circle
			(at 1.269 0.635 270)
			(size 0.7874 0.7874)
			(layers "B.Cu" "B.Mask")
			(net 867 "unconnected-(J20-Pad7)")
			(pinfunction "7")
			(pintype "passive+no_connect")
		)
		(pad "8" connect circle
			(at 0 0.635 270)
			(size 0.7874 0.7874)
			(layers "B.Cu" "B.Mask")
			(net 868 "/SoM_IO2/TC_JTAG_TDI")
			(pinfunction "8")
			(pintype "passive")
		)
		(pad "9" connect circle
			(at -1.27 0.635 270)
			(size 0.7874 0.7874)
			(layers "B.Cu" "B.Mask")
			(net 1 "GND")
			(pinfunction "9")
			(pintype "passive")
		)
		(pad "10" connect circle
			(at -2.54 0.635 270)
			(size 0.7874 0.7874)
			(layers "B.Cu" "B.Mask")
			(net 870 "/SoM_IO2/TC_JTAG_TRST_N")
			(pinfunction "10")
			(pintype "passive")
		)
	)
	(footprint "antmicro-footprints:R_0402_1005Metric"
		(layer "B.Cu")
		(at 177.5 57.5 -90)
		(descr "Resistor SMD 0402")
		(tags "resistor SMD 0402")
		(property "Reference" "R372"
			(at -3.602484 -0.415532 90)
			(layer "B.SilkS")
			(effects
				(font
					(size 0.7 0.7)
					(thickness 0.15)
				)
				(justify left bottom mirror)
			)
		)
		(property "Value" "R_1k_0402"
			(at -1.011843 -1.772047 90)
			(layer "B.Fab")
			(effects
				(font
					(size 0.7 0.7)
					(thickness 0.15)
				)
				(justify left bottom mirror)
			)
		)
		(property "Datasheet" "https://www.bourns.com/docs/product-datasheets/cr.pdf"
			(at 0 0 90)
			(layer "B.Fab")
			(hide yes)
			(effects
				(font
					(size 1.27 1.27)
					(thickness 0.15)
				)
				(justify mirror)
			)
		)
		(property "Description" "SMD Chip Resistor, 1 kohm, ± 1%, 63 mW, 0402 [1005 Metric], Thick Film, General Purpose"
			(at 0 0 90)
			(layer "B.Fab")
			(hide yes)
			(effects
				(font
					(size 1.27 1.27)
					(thickness 0.15)
				)
				(justify mirror)
			)
		)
		(property "MPN" "CR0402-FX-1001GLF"
			(at 0 0 90)
			(unlocked yes)
			(layer "B.Fab")
			(hide yes)
			(effects
				(font
					(size 1 1)
					(thickness 0.15)
				)
				(justify mirror)
			)
		)
		(property "Manufacturer" "Bourns"
			(at 0 0 90)
			(unlocked yes)
			(layer "B.Fab")
			(hide yes)
			(effects
				(font
					(size 1 1)
					(thickness 0.15)
				)
				(justify mirror)
			)
		)
		(property "License" "Apache-2.0"
			(at 0 0 90)
			(unlocked yes)
			(layer "B.Fab")
			(hide yes)
			(effects
				(font
					(size 1 1)
					(thickness 0.15)
				)
				(justify mirror)
			)
		)
		(property "Author" "Antmicro"
			(at 0 0 90)
			(unlocked yes)
			(layer "B.Fab")
			(hide yes)
			(effects
				(font
					(size 1 1)
					(thickness 0.15)
				)
				(justify mirror)
			)
		)
		(property "Val" "1k"
			(at 0 0 90)
			(unlocked yes)
			(layer "B.Fab")
			(hide yes)
			(effects
				(font
					(size 1 1)
					(thickness 0.15)
				)
				(justify mirror)
			)
		)
		(property "Tolerance" "1%"
			(at 0 0 90)
			(unlocked yes)
			(layer "B.Fab")
			(hide yes)
			(effects
				(font
					(size 1 1)
					(thickness 0.15)
				)
				(justify mirror)
			)
		)
		(sheetname "/Power/")
		(sheetfile "power.kicad_sch")
		(attr smd)
		(fp_rect
			(start -0.925 0.47)
			(end 0.925 -0.47)
			(stroke
				(width 0.05)
				(type default)
			)
			(fill no)
			(layer "B.CrtYd")
		)
		(fp_rect
			(start -0.5 0.25)
			(end 0.5 -0.25)
			(stroke
				(width 0.15)
				(type solid)
			)
			(fill no)
			(layer "B.Fab")
		)
		(fp_text user "Author: Antmicro"
			(at -0.95 -4.169 90)
			(layer "B.Fab")
			(effects
				(font
					(size 0.7 0.7)
					(thickness 0.15)
				)
				(justify left bottom mirror)
			)
		)
		(fp_text user "License: Apache-2.0"
			(at -0.95 -5.169 90)
			(layer "B.Fab")
			(effects
				(font
					(size 0.7 0.7)
					(thickness 0.15)
				)
				(justify left bottom mirror)
			)
		)
		(fp_text user "${REFERENCE}"
			(at -0.95 -3.168 90)
			(layer "B.Fab")
			(effects
				(font
					(size 0.7 0.7)
					(thickness 0.15)
				)
				(justify left bottom mirror)
			)
		)
		(pad "1" smd roundrect
			(at -0.48 0 270)
			(size 0.59 0.64)
			(layers "B.Cu" "B.Mask" "B.Paste")
			(roundrect_rratio 0.25)
			(net 46 "Net-(D63-A)")
			(pintype "passive")
		)
		(pad "2" smd roundrect
			(at 0.48 0 270)
			(size 0.59 0.64)
			(layers "B.Cu" "B.Mask" "B.Paste")
			(roundrect_rratio 0.25)
			(net 634 "+12V")
			(pintype "passive")
		)
	)
	(footprint "antmicro-footprints:SOT-523"
		(layer "B.Cu")
		(at 173.9 62.385002 -90)
		(property "Reference" "Q14"
			(at -0.982 1.362 90)
			(layer "B.SilkS")
			(effects
				(font
					(size 0.7 0.7)
					(thickness 0.15)
				)
				(justify left bottom mirror)
			)
		)
		(property "Value" "DMG1012T-7"
			(at 0.1 -1.824 90)
			(layer "B.Fab")
			(effects
				(font
					(size 0.7 0.7)
					(thickness 0.15)
				)
				(justify left bottom mirror)
			)
		)
		(property "Datasheet" "https://www.diodes.com/assets/Datasheets/ds31783.pdf"
			(at 0 0 90)
			(layer "B.Fab")
			(hide yes)
			(effects
				(font
					(size 1.27 1.27)
					(thickness 0.15)
				)
				(justify mirror)
			)
		)
		(property "Description" "Power MOSFET, N Channel, 20 V, 630 mA, 0.3 ohm, SOT-523, Surface Mount"
			(at 0 0 90)
			(layer "B.Fab")
			(hide yes)
			(effects
				(font
					(size 1.27 1.27)
					(thickness 0.15)
				)
				(justify mirror)
			)
		)
		(property "MPN" "DMG1012T-7"
			(at 0 0 90)
			(unlocked yes)
			(layer "B.Fab")
			(hide yes)
			(effects
				(font
					(size 1 1)
					(thickness 0.15)
				)
				(justify mirror)
			)
		)
		(property "Manufacturer" "Diodes Incorporated"
			(at 0 0 90)
			(unlocked yes)
			(layer "B.Fab")
			(hide yes)
			(effects
				(font
					(size 1 1)
					(thickness 0.15)
				)
				(justify mirror)
			)
		)
		(property "Author" "Antmicro"
			(at 0 0 90)
			(unlocked yes)
			(layer "B.Fab")
			(hide yes)
			(effects
				(font
					(size 1 1)
					(thickness 0.15)
				)
				(justify mirror)
			)
		)
		(property "License" "Apache-2.0"
			(at 0 0 90)
			(unlocked yes)
			(layer "B.Fab")
			(hide yes)
			(effects
				(font
					(size 1 1)
					(thickness 0.15)
				)
				(justify mirror)
			)
		)
		(sheetname "/Peripherals/")
		(sheetfile "peripherals.kicad_sch")
		(attr smd)
		(fp_line
			(start -0.725 0.551)
			(end -0.277 0.551)
			(stroke
				(width 0.15)
				(type solid)
			)
			(layer "B.SilkS")
		)
		(fp_line
			(start -0.277 0.551)
			(end -0.277 0.75)
			(stroke
				(width 0.15)
				(type solid)
			)
			(layer "B.SilkS")
		)
		(fp_line
			(start -0.927 0.351)
			(end -0.725 0.551)
			(stroke
				(width 0.15)
				(type solid)
			)
			(layer "B.SilkS")
		)
		(fp_line
			(start -0.927 0.051)
			(end -0.927 0.351)
			(stroke
				(width 0.15)
				(type solid)
			)
			(layer "B.SilkS")
		)
		(fp_circle
			(center -0.9652 -0.9652)
			(end -0.9152 -0.9652)
			(stroke
				(width 0.15)
				(type solid)
			)
			(fill yes)
			(layer "B.SilkS")
		)
		(fp_line
			(start -1.12 1.16)
			(end 1.1 1.16)
			(stroke
				(width 0.05)
				(type solid)
			)
			(layer "B.CrtYd")
		)
		(fp_line
			(start -1.12 1.16)
			(end -1.12 -1.15)
			(stroke
				(width 0.05)
				(type solid)
			)
			(layer "B.CrtYd")
		)
		(fp_line
			(start 1.1 1.16)
			(end 1.1 -1.15)
			(stroke
				(width 0.05)
				(type solid)
			)
			(layer "B.CrtYd")
		)
		(fp_line
			(start -1.12 -1.15)
			(end 1.1 -1.15)
			(stroke
				(width 0.05)
				(type solid)
			)
			(layer "B.CrtYd")
		)
		(fp_line
			(start -0.652 0.425)
			(end -0.802 0.276)
			(stroke
				(width 0.15)
				(type solid)
			)
			(layer "B.Fab")
		)
		(fp_line
			(start 0.8 0.425)
			(end -0.652 0.425)
			(stroke
				(width 0.15)
				(type solid)
			)
			(layer "B.Fab")
		)
		(fp_line
			(start 0.8 0.425)
			(end 0.8 -0.424)
			(stroke
				(width 0.15)
				(type solid)
			)
			(layer "B.Fab")
		)
		(fp_line
			(start -0.802 0.276)
			(end -0.802 -0.424)
			(stroke
				(width 0.15)
				(type solid)
			)
			(layer "B.Fab")
		)
		(fp_line
			(start 0.8 -0.424)
			(end -0.802 -0.424)
			(stroke
				(width 0.15)
				(type solid)
			)
			(layer "B.Fab")
		)
		(fp_circle
			(center -0.9652 -0.9652)
			(end -0.9144 -0.9652)
			(stroke
				(width 0.15)
				(type solid)
			)
			(fill no)
			(layer "B.Fab")
		)
		(fp_text user "License: Apache-2.0"
			(at -1.12 -5.024 90)
			(layer "B.Fab")
			(effects
				(font
					(size 0.7 0.7)
					(thickness 0.15)
				)
				(justify left bottom mirror)
			)
		)
		(fp_text user "Author: Antmicro"
			(at -1.12 -6.224 90)
			(layer "B.Fab")
			(effects
				(font
					(size 0.7 0.7)
					(thickness 0.15)
				)
				(justify left bottom mirror)
			)
		)
		(fp_text user "${REFERENCE}"
			(at -1.12 -3.824 90)
			(layer "B.Fab")
			(effects
				(font
					(size 0.7 0.7)
					(thickness 0.15)
				)
				(justify left bottom mirror)
			)
		)
		(pad "1" smd rect
			(at -0.5 -0.65 270)
			(size 0.4 0.51)
			(layers "B.Cu" "B.Mask" "B.Paste")
			(net 371 "/Expansion connector/GPIO.USER_LED1")
			(pinfunction "G")
			(pintype "input")
		)
		(pad "2" smd rect
			(at 0.498 -0.65 270)
			(size 0.4 0.51)
			(layers "B.Cu" "B.Mask" "B.Paste")
			(net 1 "GND")
			(pinfunction "S")
			(pintype "passive")
		)
		(pad "3" smd rect
			(at 0 0.652 270)
			(size 0.4 0.51)
			(layers "B.Cu" "B.Mask" "B.Paste")
			(net 39 "Net-(D36-C)")
			(pinfunction "D")
			(pintype "passive")
		)
	)
	(footprint "antmicro-footprints:R_0402_1005Metric"
		(layer "B.Cu")
		(at 208.716532 141 180)
		(descr "Resistor SMD 0402")
		(tags "resistor SMD 0402")
		(property "Reference" "R199"
			(at -3.809468 -0.5 0)
			(layer "B.SilkS")
			(effects
				(font
					(size 0.7 0.7)
					(thickness 0.15)
				)
				(justify left bottom mirror)
			)
		)
		(property "Value" "R_0R_0402"
			(at -1.011843 -1.772047 0)
			(layer "B.Fab")
			(effects
				(font
					(size 0.7 0.7)
					(thickness 0.15)
				)
				(justify left bottom mirror)
			)
		)
		(property "Datasheet" "https://industrial.panasonic.com/cdbs/www-data/pdf/RDA0000/AOA0000C301.pdf"
			(at 0 0 0)
			(layer "B.Fab")
			(hide yes)
			(effects
				(font
					(size 1.27 1.27)
					(thickness 0.15)
				)
				(justify mirror)
			)
		)
		(property "Description" "SMD Chip Resistor, Jumper, 0 ohm, 100 mW, 0402 [1005 Metric], Thick Film, General Purpose"
			(at 0 0 0)
			(layer "B.Fab")
			(hide yes)
			(effects
				(font
					(size 1.27 1.27)
					(thickness 0.15)
				)
				(justify mirror)
			)
		)
		(property "MPN" "ERJ2GE0R00X"
			(at 0 0 0)
			(unlocked yes)
			(layer "B.Fab")
			(hide yes)
			(effects
				(font
					(size 1 1)
					(thickness 0.15)
				)
				(justify mirror)
			)
		)
		(property "Manufacturer" "Panasonic"
			(at 0 0 0)
			(unlocked yes)
			(layer "B.Fab")
			(hide yes)
			(effects
				(font
					(size 1 1)
					(thickness 0.15)
				)
				(justify mirror)
			)
		)
		(property "License" "Apache-2.0"
			(at 0 0 0)
			(unlocked yes)
			(layer "B.Fab")
			(hide yes)
			(effects
				(font
					(size 1 1)
					(thickness 0.15)
				)
				(justify mirror)
			)
		)
		(property "Author" "Antmicro"
			(at 0 0 0)
			(unlocked yes)
			(layer "B.Fab")
			(hide yes)
			(effects
				(font
					(size 1 1)
					(thickness 0.15)
				)
				(justify mirror)
			)
		)
		(property "Val" "0R"
			(at 0 0 0)
			(unlocked yes)
			(layer "B.Fab")
			(hide yes)
			(effects
				(font
					(size 1 1)
					(thickness 0.15)
				)
				(justify mirror)
			)
		)
		(property "Tolerance" "~"
			(at 0 0 0)
			(unlocked yes)
			(layer "B.Fab")
			(hide yes)
			(effects
				(font
					(size 1 1)
					(thickness 0.15)
				)
				(justify mirror)
			)
		)
		(property "Current" "1A"
			(at 0 0 0)
			(unlocked yes)
			(layer "B.Fab")
			(hide yes)
			(effects
				(font
					(size 1 1)
					(thickness 0.15)
				)
				(justify mirror)
			)
		)
		(sheetname "/SFP/")
		(sheetfile "sfp.kicad_sch")
		(attr smd)
		(fp_rect
			(start -0.925 0.47)
			(end 0.925 -0.47)
			(stroke
				(width 0.05)
				(type default)
			)
			(fill no)
			(layer "B.CrtYd")
		)
		(fp_rect
			(start -0.5 0.25)
			(end 0.5 -0.25)
			(stroke
				(width 0.15)
				(type solid)
			)
			(fill no)
			(layer "B.Fab")
		)
		(fp_text user "${REFERENCE}"
			(at -0.95 -3.168 0)
			(layer "B.Fab")
			(effects
				(font
					(size 0.7 0.7)
					(thickness 0.15)
				)
				(justify left bottom mirror)
			)
		)
		(fp_text user "Author: Antmicro"
			(at -0.95 -4.169 0)
			(layer "B.Fab")
			(effects
				(font
					(size 0.7 0.7)
					(thickness 0.15)
				)
				(justify left bottom mirror)
			)
		)
		(fp_text user "License: Apache-2.0"
			(at -0.95 -5.169 0)
			(layer "B.Fab")
			(effects
				(font
					(size 0.7 0.7)
					(thickness 0.15)
				)
				(justify left bottom mirror)
			)
		)
		(pad "1" smd roundrect
			(at -0.48 0 180)
			(size 0.59 0.64)
			(layers "B.Cu" "B.Mask" "B.Paste")
			(roundrect_rratio 0.25)
			(net 1 "GND")
			(pintype "passive")
		)
		(pad "2" smd roundrect
			(at 0.48 0 180)
			(size 0.59 0.64)
			(layers "B.Cu" "B.Mask" "B.Paste")
			(roundrect_rratio 0.25)
			(net 1369 "Net-(J12-RS1)")
			(pintype "passive")
		)
	)
	(footprint "antmicro-footprints:R_0402_1005Metric"
		(layer "B.Cu")
		(at 170.75 57.5 -90)
		(descr "Resistor SMD 0402")
		(tags "resistor SMD 0402")
		(property "Reference" "R64"
			(at -3.58 -0.365532 90)
			(layer "B.SilkS")
			(effects
				(font
					(size 0.7 0.7)
					(thickness 0.15)
				)
				(justify left bottom mirror)
			)
		)
		(property "Value" "R_470R_0402"
			(at -1.011843 -1.772047 90)
			(layer "B.Fab")
			(effects
				(font
					(size 0.7 0.7)
					(thickness 0.15)
				)
				(justify left bottom mirror)
			)
		)
		(property "Datasheet" "https://www.bourns.com/docs/product-datasheets/cr.pdf"
			(at 0 0 90)
			(layer "B.Fab")
			(hide yes)
			(effects
				(font
					(size 1.27 1.27)
					(thickness 0.15)
				)
				(justify mirror)
			)
		)
		(property "Description" "SMD Chip Resistor, 470 ohm, ± 1%, 62.5 mW, 0402 [1005 Metric], Thick Film, General Purpose"
			(at 0 0 90)
			(layer "B.Fab")
			(hide yes)
			(effects
				(font
					(size 1.27 1.27)
					(thickness 0.15)
				)
				(justify mirror)
			)
		)
		(property "MPN" "CR0402-FX-4700GLF"
			(at 0 0 90)
			(unlocked yes)
			(layer "B.Fab")
			(hide yes)
			(effects
				(font
					(size 1 1)
					(thickness 0.15)
				)
				(justify mirror)
			)
		)
		(property "Manufacturer" "Bourns"
			(at 0 0 90)
			(unlocked yes)
			(layer "B.Fab")
			(hide yes)
			(effects
				(font
					(size 1 1)
					(thickness 0.15)
				)
				(justify mirror)
			)
		)
		(property "License" "Apache-2.0"
			(at 0 0 90)
			(unlocked yes)
			(layer "B.Fab")
			(hide yes)
			(effects
				(font
					(size 1 1)
					(thickness 0.15)
				)
				(justify mirror)
			)
		)
		(property "Author" "Antmicro"
			(at 0 0 90)
			(unlocked yes)
			(layer "B.Fab")
			(hide yes)
			(effects
				(font
					(size 1 1)
					(thickness 0.15)
				)
				(justify mirror)
			)
		)
		(property "Val" "470R"
			(at 0 0 90)
			(unlocked yes)
			(layer "B.Fab")
			(hide yes)
			(effects
				(font
					(size 1 1)
					(thickness 0.15)
				)
				(justify mirror)
			)
		)
		(property "Tolerance" "1%"
			(at 0 0 90)
			(unlocked yes)
			(layer "B.Fab")
			(hide yes)
			(effects
				(font
					(size 1 1)
					(thickness 0.15)
				)
				(justify mirror)
			)
		)
		(sheetname "/Power/")
		(sheetfile "power.kicad_sch")
		(attr smd)
		(fp_rect
			(start -0.925 0.47)
			(end 0.925 -0.47)
			(stroke
				(width 0.05)
				(type default)
			)
			(fill no)
			(layer "B.CrtYd")
		)
		(fp_rect
			(start -0.5 0.25)
			(end 0.5 -0.25)
			(stroke
				(width 0.15)
				(type solid)
			)
			(fill no)
			(layer "B.Fab")
		)
		(fp_text user "License: Apache-2.0"
			(at -0.95 -5.169 90)
			(layer "B.Fab")
			(effects
				(font
					(size 0.7 0.7)
					(thickness 0.15)
				)
				(justify left bottom mirror)
			)
		)
		(fp_text user "${REFERENCE}"
			(at -0.95 -3.168 90)
			(layer "B.Fab")
			(effects
				(font
					(size 0.7 0.7)
					(thickness 0.15)
				)
				(justify left bottom mirror)
			)
		)
		(fp_text user "Author: Antmicro"
			(at -0.95 -4.169 90)
			(layer "B.Fab")
			(effects
				(font
					(size 0.7 0.7)
					(thickness 0.15)
				)
				(justify left bottom mirror)
			)
		)
		(pad "1" smd roundrect
			(at -0.48 0 270)
			(size 0.59 0.64)
			(layers "B.Cu" "B.Mask" "B.Paste")
			(roundrect_rratio 0.25)
			(net 490 "Net-(D12-A)")
			(pintype "passive")
		)
		(pad "2" smd roundrect
			(at 0.48 0 270)
			(size 0.59 0.64)
			(layers "B.Cu" "B.Mask" "B.Paste")
			(roundrect_rratio 0.25)
			(net 5 "+5V")
			(pintype "passive")
		)
	)
	(footprint "antmicro-footprints:TP_SMD_0.75mm"
		(layer "B.Cu")
		(at 183.14 58 180)
		(property "Reference" "TP127"
			(at -0.43 4.04 90)
			(layer "B.SilkS")
			(effects
				(font
					(size 0.7 0.7)
					(thickness 0.15)
				)
				(justify left bottom mirror)
			)
		)
		(property "Value" "TP_0.75mm_SMD"
			(at 0 -1.2 0)
			(layer "B.Fab")
			(effects
				(font
					(size 0.7 0.7)
					(thickness 0.15)
				)
				(justify left bottom mirror)
			)
		)
		(property "Description" "SMT test point"
			(at 0 0 0)
			(layer "B.Fab")
			(hide yes)
			(effects
				(font
					(size 1.27 1.27)
					(thickness 0.15)
				)
				(justify mirror)
			)
		)
		(property "MPN" ""
			(at 0 0 0)
			(unlocked yes)
			(layer "B.Fab")
			(hide yes)
			(effects
				(font
					(size 1 1)
					(thickness 0.15)
				)
				(justify mirror)
			)
		)
		(property "Manufacturer" ""
			(at 0 0 0)
			(unlocked yes)
			(layer "B.Fab")
			(hide yes)
			(effects
				(font
					(size 1 1)
					(thickness 0.15)
				)
				(justify mirror)
			)
		)
		(property "Author" "Antmicro"
			(at 0 0 0)
			(unlocked yes)
			(layer "B.Fab")
			(hide yes)
			(effects
				(font
					(size 1 1)
					(thickness 0.15)
				)
				(justify mirror)
			)
		)
		(property "License" "Apache-2.0"
			(at 0 0 0)
			(unlocked yes)
			(layer "B.Fab")
			(hide yes)
			(effects
				(font
					(size 1 1)
					(thickness 0.15)
				)
				(justify mirror)
			)
		)
		(sheetname "/Power/")
		(sheetfile "power.kicad_sch")
		(attr exclude_from_pos_files exclude_from_bom)
		(fp_circle
			(center 0 0)
			(end 0.475 0)
			(stroke
				(width 0.05)
				(type default)
			)
			(fill no)
			(layer "B.CrtYd")
		)
		(fp_text user "License: Apache-2.0"
			(at -0.4 -5.101 0)
			(layer "B.Fab")
			(effects
				(font
					(size 0.7 0.7)
					(thickness 0.15)
				)
				(justify left bottom mirror)
			)
		)
		(fp_text user "${REFERENCE}"
			(at -0.4 -2.7 0)
			(layer "B.Fab")
			(effects
				(font
					(size 0.7 0.7)
					(thickness 0.15)
				)
				(justify left bottom mirror)
			)
		)
		(fp_text user "Author: Antmicro"
			(at -0.4 -3.901 0)
			(layer "B.Fab")
			(effects
				(font
					(size 0.7 0.7)
					(thickness 0.15)
				)
				(justify left bottom mirror)
			)
		)
		(pad "1" smd circle
			(at 0 0 180)
			(size 0.75 0.75)
			(layers "B.Cu" "B.Mask")
			(net 904 "+20V")
			(pinfunction "1")
			(pintype "passive")
		)
	)
	(footprint "antmicro-footprints:TP_SMD_0.75mm"
		(layer "B.Cu")
		(at 63 76.6 -90)
		(property "Reference" "TP113"
			(at 0.4 -0.4 90)
			(layer "B.SilkS")
			(effects
				(font
					(size 0.7 0.7)
					(thickness 0.15)
				)
				(justify left bottom mirror)
			)
		)
		(property "Value" "TP_0.75mm_SMD"
			(at 0 -1.2 90)
			(layer "B.Fab")
			(effects
				(font
					(size 0.7 0.7)
					(thickness 0.15)
				)
				(justify left bottom mirror)
			)
		)
		(property "Description" "SMT test point"
			(at 0 0 90)
			(layer "B.Fab")
			(hide yes)
			(effects
				(font
					(size 1.27 1.27)
					(thickness 0.15)
				)
				(justify mirror)
			)
		)
		(property "MPN" ""
			(at 0 0 90)
			(unlocked yes)
			(layer "B.Fab")
			(hide yes)
			(effects
				(font
					(size 1 1)
					(thickness 0.15)
				)
				(justify mirror)
			)
		)
		(property "Manufacturer" ""
			(at 0 0 90)
			(unlocked yes)
			(layer "B.Fab")
			(hide yes)
			(effects
				(font
					(size 1 1)
					(thickness 0.15)
				)
				(justify mirror)
			)
		)
		(property "Author" "Antmicro"
			(at 0 0 90)
			(unlocked yes)
			(layer "B.Fab")
			(hide yes)
			(effects
				(font
					(size 1 1)
					(thickness 0.15)
				)
				(justify mirror)
			)
		)
		(property "License" "Apache-2.0"
			(at 0 0 90)
			(unlocked yes)
			(layer "B.Fab")
			(hide yes)
			(effects
				(font
					(size 1 1)
					(thickness 0.15)
				)
				(justify mirror)
			)
		)
		(sheetname "/Expansion connector/")
		(sheetfile "expansion_connector.kicad_sch")
		(attr exclude_from_pos_files exclude_from_bom)
		(fp_circle
			(center 0 0)
			(end 0.475 0)
			(stroke
				(width 0.05)
				(type default)
			)
			(fill no)
			(layer "B.CrtYd")
		)
		(fp_text user "License: Apache-2.0"
			(at -0.4 -5.101 90)
			(layer "B.Fab")
			(effects
				(font
					(size 0.7 0.7)
					(thickness 0.15)
				)
				(justify left bottom mirror)
			)
		)
		(fp_text user "Author: Antmicro"
			(at -0.4 -3.901 90)
			(layer "B.Fab")
			(effects
				(font
					(size 0.7 0.7)
					(thickness 0.15)
				)
				(justify left bottom mirror)
			)
		)
		(fp_text user "${REFERENCE}"
			(at -0.4 -2.7 90)
			(layer "B.Fab")
			(effects
				(font
					(size 0.7 0.7)
					(thickness 0.15)
				)
				(justify left bottom mirror)
			)
		)
		(pad "1" smd circle
			(at 0 0 270)
			(size 0.75 0.75)
			(layers "B.Cu" "B.Mask")
			(net 717 "Net-(J18-PadL01)")
			(pinfunction "1")
			(pintype "passive")
		)
	)
	(footprint "antmicro-footprints:R_0402_1005Metric"
		(layer "B.Cu")
		(at 236.689002 93.424001)
		(descr "Resistor SMD 0402")
		(tags "resistor SMD 0402")
		(property "Reference" "R144"
			(at -2.689002 -2.624001 0)
			(layer "B.SilkS")
			(effects
				(font
					(size 0.7 0.7)
					(thickness 0.15)
				)
				(justify right top mirror)
			)
		)
		(property "Value" "R_10k_0402"
			(at -1.011843 -1.772046 0)
			(layer "B.Fab")
			(effects
				(font
					(size 0.7 0.7)
					(thickness 0.15)
				)
				(justify right top mirror)
			)
		)
		(property "Datasheet" "https://www.bourns.com/docs/product-datasheets/cr.pdf"
			(at 0 0 0)
			(layer "B.Fab")
			(hide yes)
			(effects
				(font
					(size 1.27 1.27)
					(thickness 0.15)
				)
				(justify mirror)
			)
		)
		(property "Description" "SMD Chip Resistor, 10 kohm, ± 1%, 62.5 mW, 0402 [1005 Metric], Thick Film, General Purpose"
			(at 0 0 0)
			(layer "B.Fab")
			(hide yes)
			(effects
				(font
					(size 1.27 1.27)
					(thickness 0.15)
				)
				(justify mirror)
			)
		)
		(property "Manufacturer" "Bourns"
			(at 0 0 180)
			(unlocked yes)
			(layer "B.Fab")
			(hide yes)
			(effects
				(font
					(size 1 1)
					(thickness 0.15)
				)
				(justify mirror)
			)
		)
		(property "MPN" "CR0402-FX-1002GLF"
			(at 0 0 180)
			(unlocked yes)
			(layer "B.Fab")
			(hide yes)
			(effects
				(font
					(size 1 1)
					(thickness 0.15)
				)
				(justify mirror)
			)
		)
		(property "Val" "10k"
			(at 0 0 180)
			(unlocked yes)
			(layer "B.Fab")
			(hide yes)
			(effects
				(font
					(size 1 1)
					(thickness 0.15)
				)
				(justify mirror)
			)
		)
		(property "License" "Apache-2.0"
			(at 0 0 180)
			(unlocked yes)
			(layer "B.Fab")
			(hide yes)
			(effects
				(font
					(size 1 1)
					(thickness 0.15)
				)
				(justify mirror)
			)
		)
		(property "Author" "Antmicro"
			(at 0 0 180)
			(unlocked yes)
			(layer "B.Fab")
			(hide yes)
			(effects
				(font
					(size 1 1)
					(thickness 0.15)
				)
				(justify mirror)
			)
		)
		(property "Tolerance" "1%"
			(at 0 0 180)
			(unlocked yes)
			(layer "B.Fab")
			(hide yes)
			(effects
				(font
					(size 1 1)
					(thickness 0.15)
				)
				(justify mirror)
			)
		)
		(sheetname "/USB DP Alt mode/")
		(sheetfile "usb_dp.kicad_sch")
		(attr smd)
		(fp_poly
			(pts
				(xy -0.925 0.47) (xy -0.925 -0.47) (xy 0.925 -0.47) (xy 0.925 0.47)
			)
			(stroke
				(width 0.05)
				(type default)
			)
			(fill no)
			(layer "B.CrtYd")
		)
		(fp_poly
			(pts
				(xy -0.5 0.25) (xy -0.5 -0.25) (xy 0.5 -0.25) (xy 0.5 0.25)
			)
			(stroke
				(width 0.15)
				(type solid)
			)
			(fill no)
			(layer "B.Fab")
		)
		(fp_text user "Author: Antmicro"
			(at -0.95 -4.169 0)
			(layer "B.Fab")
			(effects
				(font
					(size 0.7 0.7)
					(thickness 0.15)
				)
				(justify right top mirror)
			)
		)
		(fp_text user "License: Apache-2.0"
			(at -0.949999 -5.169 0)
			(layer "B.Fab")
			(effects
				(font
					(size 0.7 0.7)
					(thickness 0.15)
				)
				(justify right top mirror)
			)
		)
		(fp_text user "${REFERENCE}"
			(at -0.95 -3.168 0)
			(layer "B.Fab")
			(effects
				(font
					(size 0.7 0.7)
					(thickness 0.15)
				)
				(justify right top mirror)
			)
		)
		(pad "1" smd roundrect
			(at -0.48 0)
			(size 0.59 0.64)
			(layers "B.Cu" "B.Mask" "B.Paste")
			(roundrect_rratio 0.25)
			(net 1 "GND")
			(pintype "passive")
		)
		(pad "2" smd roundrect
			(at 0.48 0)
			(size 0.59 0.64)
			(layers "B.Cu" "B.Mask" "B.Paste")
			(roundrect_rratio 0.25)
			(net 971 "Net-(U35-EN)")
			(pintype "passive")
		)
	)
	(footprint "antmicro-footprints:R_0402_1005Metric"
		(layer "B.Cu")
		(at 124.6 131.85)
		(descr "Resistor SMD 0402")
		(tags "resistor SMD 0402")
		(property "Reference" "R203"
			(at -1.19 -5.32 0)
			(layer "B.SilkS")
			(effects
				(font
					(size 0.7 0.7)
					(thickness 0.15)
				)
				(justify right top mirror)
			)
		)
		(property "Value" "R_47k_0402"
			(at -1.011843 -1.772046 0)
			(layer "B.Fab")
			(effects
				(font
					(size 0.7 0.7)
					(thickness 0.15)
				)
				(justify right top mirror)
			)
		)
		(property "Datasheet" "https://www.bourns.com/docs/product-datasheets/cr.pdf"
			(at 0 0 0)
			(layer "B.Fab")
			(hide yes)
			(effects
				(font
					(size 1.27 1.27)
					(thickness 0.15)
				)
				(justify mirror)
			)
		)
		(property "Description" "SMD Chip Resistor, 47 kohm, ± 1%, 62.5 mW, 0402 [1005 Metric], Thick Film, General Purpose"
			(at 0 0 0)
			(layer "B.Fab")
			(hide yes)
			(effects
				(font
					(size 1.27 1.27)
					(thickness 0.15)
				)
				(justify mirror)
			)
		)
		(property "MPN" "CR0402-FX-4702GLF"
			(at 0 0 180)
			(unlocked yes)
			(layer "B.Fab")
			(hide yes)
			(effects
				(font
					(size 1 1)
					(thickness 0.15)
				)
				(justify mirror)
			)
		)
		(property "Manufacturer" "Bourns"
			(at 0 0 180)
			(unlocked yes)
			(layer "B.Fab")
			(hide yes)
			(effects
				(font
					(size 1 1)
					(thickness 0.15)
				)
				(justify mirror)
			)
		)
		(property "License" "Apache-2.0"
			(at 0 0 180)
			(unlocked yes)
			(layer "B.Fab")
			(hide yes)
			(effects
				(font
					(size 1 1)
					(thickness 0.15)
				)
				(justify mirror)
			)
		)
		(property "Author" "Antmicro"
			(at 0 0 180)
			(unlocked yes)
			(layer "B.Fab")
			(hide yes)
			(effects
				(font
					(size 1 1)
					(thickness 0.15)
				)
				(justify mirror)
			)
		)
		(property "Val" "47k"
			(at 0 0 180)
			(unlocked yes)
			(layer "B.Fab")
			(hide yes)
			(effects
				(font
					(size 1 1)
					(thickness 0.15)
				)
				(justify mirror)
			)
		)
		(property "Tolerance" "1%"
			(at 0 0 180)
			(unlocked yes)
			(layer "B.Fab")
			(hide yes)
			(effects
				(font
					(size 1 1)
					(thickness 0.15)
				)
				(justify mirror)
			)
		)
		(sheetname "/M.2/")
		(sheetfile "m2.kicad_sch")
		(attr smd)
		(fp_poly
			(pts
				(xy -0.925 0.47) (xy 0.925 0.47) (xy 0.925 -0.47) (xy -0.925 -0.47)
			)
			(stroke
				(width 0.05)
				(type default)
			)
			(fill no)
			(layer "B.CrtYd")
		)
		(fp_poly
			(pts
				(xy -0.5 0.25) (xy 0.5 0.25) (xy 0.5 -0.25) (xy -0.5 -0.25)
			)
			(stroke
				(width 0.15)
				(type solid)
			)
			(fill no)
			(layer "B.Fab")
		)
		(fp_text user "License: Apache-2.0"
			(at -0.949999 -5.169 0)
			(layer "B.Fab")
			(effects
				(font
					(size 0.7 0.7)
					(thickness 0.15)
				)
				(justify right top mirror)
			)
		)
		(fp_text user "${REFERENCE}"
			(at -0.95 -3.168 0)
			(layer "B.Fab")
			(effects
				(font
					(size 0.7 0.7)
					(thickness 0.15)
				)
				(justify right top mirror)
			)
		)
		(fp_text user "Author: Antmicro"
			(at -0.95 -4.169 0)
			(layer "B.Fab")
			(effects
				(font
					(size 0.7 0.7)
					(thickness 0.15)
				)
				(justify right top mirror)
			)
		)
		(pad "1" smd roundrect
			(at -0.48 0)
			(size 0.59 0.64)
			(layers "B.Cu" "B.Mask" "B.Paste")
			(roundrect_rratio 0.25)
			(net 831 "/M.2/~{PERST_E}")
			(pintype "passive")
		)
		(pad "2" smd roundrect
			(at 0.48 0)
			(size 0.59 0.64)
			(layers "B.Cu" "B.Mask" "B.Paste")
			(roundrect_rratio 0.25)
			(net 2 "+3V3")
			(pintype "passive")
		)
	)
	(footprint "antmicro-footprints:TP_SMD_0.75mm"
		(layer "B.Cu")
		(at 120.51 72.11 90)
		(property "Reference" "TP56"
			(at -2.79 0.79 90)
			(layer "B.SilkS")
			(effects
				(font
					(size 0.7 0.7)
					(thickness 0.15)
				)
				(justify right top mirror)
			)
		)
		(property "Value" "TP_0.75mm_SMD"
			(at 0 -1.2 90)
			(layer "B.Fab")
			(effects
				(font
					(size 0.7 0.7)
					(thickness 0.15)
				)
				(justify right top mirror)
			)
		)
		(property "Description" "SMT test point"
			(at 0 0 90)
			(layer "B.Fab")
			(hide yes)
			(effects
				(font
					(size 1.27 1.27)
					(thickness 0.15)
				)
				(justify mirror)
			)
		)
		(property "MPN" ""
			(at 0 0 270)
			(unlocked yes)
			(layer "B.Fab")
			(hide yes)
			(effects
				(font
					(size 1 1)
					(thickness 0.15)
				)
				(justify mirror)
			)
		)
		(property "Manufacturer" ""
			(at 0 0 270)
			(unlocked yes)
			(layer "B.Fab")
			(hide yes)
			(effects
				(font
					(size 1 1)
					(thickness 0.15)
				)
				(justify mirror)
			)
		)
		(property "Author" "Antmicro"
			(at 0 0 270)
			(unlocked yes)
			(layer "B.Fab")
			(hide yes)
			(effects
				(font
					(size 1 1)
					(thickness 0.15)
				)
				(justify mirror)
			)
		)
		(property "License" "Apache-2.0"
			(at 0 0 270)
			(unlocked yes)
			(layer "B.Fab")
			(hide yes)
			(effects
				(font
					(size 1 1)
					(thickness 0.15)
				)
				(justify mirror)
			)
		)
		(sheetname "/SoM_Power/")
		(sheetfile "som_power.kicad_sch")
		(attr exclude_from_pos_files exclude_from_bom)
		(fp_circle
			(center 0 0)
			(end 0.475 0)
			(stroke
				(width 0.05)
				(type default)
			)
			(fill no)
			(layer "B.CrtYd")
		)
		(fp_text user "License: Apache-2.0"
			(at -0.4 -5.101 90)
			(layer "B.Fab")
			(effects
				(font
					(size 0.7 0.7)
					(thickness 0.15)
				)
				(justify right top mirror)
			)
		)
		(fp_text user "${REFERENCE}"
			(at -0.4 -2.7 90)
			(layer "B.Fab")
			(effects
				(font
					(size 0.7 0.7)
					(thickness 0.15)
				)
				(justify right top mirror)
			)
		)
		(fp_text user "Author: Antmicro"
			(at -0.4 -3.901 90)
			(layer "B.Fab")
			(effects
				(font
					(size 0.7 0.7)
					(thickness 0.15)
				)
				(justify right top mirror)
			)
		)
		(pad "1" smd circle
			(at 0 0 90)
			(size 0.75 0.75)
			(layers "B.Cu" "B.Mask")
			(net 875 "Net-(J1A-FSI_GPIO03)")
			(pinfunction "1")
			(pintype "passive")
		)
	)
	(footprint "antmicro-footprints:TP_SMD_0.75mm"
		(layer "B.Cu")
		(at 169.64 58 180)
		(property "Reference" "TP133"
			(at -0.43 4.05 90)
			(layer "B.SilkS")
			(effects
				(font
					(size 0.7 0.7)
					(thickness 0.15)
				)
				(justify left bottom mirror)
			)
		)
		(property "Value" "TP_0.75mm_SMD"
			(at 0 -1.2 0)
			(layer "B.Fab")
			(effects
				(font
					(size 0.7 0.7)
					(thickness 0.15)
				)
				(justify left bottom mirror)
			)
		)
		(property "Description" "SMT test point"
			(at 0 0 0)
			(layer "B.Fab")
			(hide yes)
			(effects
				(font
					(size 1.27 1.27)
					(thickness 0.15)
				)
				(justify mirror)
			)
		)
		(property "MPN" ""
			(at 0 0 0)
			(unlocked yes)
			(layer "B.Fab")
			(hide yes)
			(effects
				(font
					(size 1 1)
					(thickness 0.15)
				)
				(justify mirror)
			)
		)
		(property "Manufacturer" ""
			(at 0 0 0)
			(unlocked yes)
			(layer "B.Fab")
			(hide yes)
			(effects
				(font
					(size 1 1)
					(thickness 0.15)
				)
				(justify mirror)
			)
		)
		(property "Author" "Antmicro"
			(at 0 0 0)
			(unlocked yes)
			(layer "B.Fab")
			(hide yes)
			(effects
				(font
					(size 1 1)
					(thickness 0.15)
				)
				(justify mirror)
			)
		)
		(property "License" "Apache-2.0"
			(at 0 0 0)
			(unlocked yes)
			(layer "B.Fab")
			(hide yes)
			(effects
				(font
					(size 1 1)
					(thickness 0.15)
				)
				(justify mirror)
			)
		)
		(sheetname "/Power/")
		(sheetfile "power.kicad_sch")
		(attr exclude_from_pos_files exclude_from_bom)
		(fp_circle
			(center 0 0)
			(end 0.475 0)
			(stroke
				(width 0.05)
				(type default)
			)
			(fill no)
			(layer "B.CrtYd")
		)
		(fp_text user "${REFERENCE}"
			(at -0.4 -2.7 0)
			(layer "B.Fab")
			(effects
				(font
					(size 0.7 0.7)
					(thickness 0.15)
				)
				(justify left bottom mirror)
			)
		)
		(fp_text user "License: Apache-2.0"
			(at -0.4 -5.101 0)
			(layer "B.Fab")
			(effects
				(font
					(size 0.7 0.7)
					(thickness 0.15)
				)
				(justify left bottom mirror)
			)
		)
		(fp_text user "Author: Antmicro"
			(at -0.4 -3.901 0)
			(layer "B.Fab")
			(effects
				(font
					(size 0.7 0.7)
					(thickness 0.15)
				)
				(justify left bottom mirror)
			)
		)
		(pad "1" smd circle
			(at 0 0 180)
			(size 0.75 0.75)
			(layers "B.Cu" "B.Mask")
			(net 4 "+3V3_AON")
			(pinfunction "1")
			(pintype "passive")
		)
	)
	(footprint "antmicro-footprints:TP_SMD_0.75mm"
		(layer "B.Cu")
		(at 193.28 80.6815)
		(property "Reference" "TP15"
			(at 0.52 -3.2315 90)
			(layer "B.SilkS")
			(effects
				(font
					(size 0.7 0.7)
					(thickness 0.15)
				)
				(justify left bottom mirror)
			)
		)
		(property "Value" "TP_0.75mm_SMD"
			(at 0 -1.2 180)
			(layer "B.Fab")
			(effects
				(font
					(size 0.7 0.7)
					(thickness 0.15)
				)
				(justify left bottom mirror)
			)
		)
		(property "Description" "SMT test point"
			(at 0 0 180)
			(layer "B.Fab")
			(hide yes)
			(effects
				(font
					(size 1.27 1.27)
					(thickness 0.15)
				)
				(justify mirror)
			)
		)
		(property "MPN" ""
			(at 0 0 180)
			(unlocked yes)
			(layer "B.Fab")
			(hide yes)
			(effects
				(font
					(size 1 1)
					(thickness 0.15)
				)
				(justify mirror)
			)
		)
		(property "Manufacturer" ""
			(at 0 0 180)
			(unlocked yes)
			(layer "B.Fab")
			(hide yes)
			(effects
				(font
					(size 1 1)
					(thickness 0.15)
				)
				(justify mirror)
			)
		)
		(property "Author" "Antmicro"
			(at 0 0 180)
			(unlocked yes)
			(layer "B.Fab")
			(hide yes)
			(effects
				(font
					(size 1 1)
					(thickness 0.15)
				)
				(justify mirror)
			)
		)
		(property "License" "Apache-2.0"
			(at 0 0 180)
			(unlocked yes)
			(layer "B.Fab")
			(hide yes)
			(effects
				(font
					(size 1 1)
					(thickness 0.15)
				)
				(justify mirror)
			)
		)
		(sheetname "/USB Debug, PD/")
		(sheetfile "usb_debug_pd.kicad_sch")
		(attr exclude_from_pos_files exclude_from_bom)
		(fp_circle
			(center 0 0)
			(end 0.475 0)
			(stroke
				(width 0.05)
				(type default)
			)
			(fill no)
			(layer "B.CrtYd")
		)
		(fp_text user "License: Apache-2.0"
			(at -0.4 -5.101 180)
			(layer "B.Fab")
			(effects
				(font
					(size 0.7 0.7)
					(thickness 0.15)
				)
				(justify left bottom mirror)
			)
		)
		(fp_text user "Author: Antmicro"
			(at -0.4 -3.901 180)
			(layer "B.Fab")
			(effects
				(font
					(size 0.7 0.7)
					(thickness 0.15)
				)
				(justify left bottom mirror)
			)
		)
		(fp_text user "${REFERENCE}"
			(at -0.4 -2.7 180)
			(layer "B.Fab")
			(effects
				(font
					(size 0.7 0.7)
					(thickness 0.15)
				)
				(justify left bottom mirror)
			)
		)
		(pad "1" smd circle
			(at 0 0)
			(size 0.75 0.75)
			(layers "B.Cu" "B.Mask")
			(net 950 "/USB Debug, PD/PDC_I2C2_SDA")
			(pinfunction "1")
			(pintype "passive")
		)
	)
	(footprint "antmicro-footprints:R_0402_1005Metric"
		(layer "B.Cu")
		(at 213.789 81.225 180)
		(descr "Resistor SMD 0402")
		(tags "resistor SMD 0402")
		(property "Reference" "R114"
			(at 0.189 -2.375 0)
			(layer "B.SilkS")
			(effects
				(font
					(size 0.7 0.7)
					(thickness 0.15)
				)
				(justify left bottom mirror)
			)
		)
		(property "Value" "R_1k_0402"
			(at -1.011843 -1.772046 0)
			(layer "B.Fab")
			(effects
				(font
					(size 0.7 0.7)
					(thickness 0.15)
				)
				(justify left bottom mirror)
			)
		)
		(property "Datasheet" "https://www.bourns.com/docs/product-datasheets/cr.pdf"
			(at 0 0 0)
			(layer "B.Fab")
			(hide yes)
			(effects
				(font
					(size 1.27 1.27)
					(thickness 0.15)
				)
				(justify mirror)
			)
		)
		(property "Description" "SMD Chip Resistor, 1 kohm, ± 1%, 63 mW, 0402 [1005 Metric], Thick Film, General Purpose"
			(at 0 0 0)
			(layer "B.Fab")
			(hide yes)
			(effects
				(font
					(size 1.27 1.27)
					(thickness 0.15)
				)
				(justify mirror)
			)
		)
		(property "MPN" "CR0402-FX-1001GLF"
			(at 0 0 0)
			(unlocked yes)
			(layer "B.Fab")
			(hide yes)
			(effects
				(font
					(size 1 1)
					(thickness 0.15)
				)
				(justify mirror)
			)
		)
		(property "Manufacturer" "Bourns"
			(at 0 0 0)
			(unlocked yes)
			(layer "B.Fab")
			(hide yes)
			(effects
				(font
					(size 1 1)
					(thickness 0.15)
				)
				(justify mirror)
			)
		)
		(property "License" "Apache-2.0"
			(at 0 0 0)
			(unlocked yes)
			(layer "B.Fab")
			(hide yes)
			(effects
				(font
					(size 1 1)
					(thickness 0.15)
				)
				(justify mirror)
			)
		)
		(property "Author" "Antmicro"
			(at 0 0 0)
			(unlocked yes)
			(layer "B.Fab")
			(hide yes)
			(effects
				(font
					(size 1 1)
					(thickness 0.15)
				)
				(justify mirror)
			)
		)
		(property "Val" "1k"
			(at 0 0 0)
			(unlocked yes)
			(layer "B.Fab")
			(hide yes)
			(effects
				(font
					(size 1 1)
					(thickness 0.15)
				)
				(justify mirror)
			)
		)
		(property "Tolerance" "1%"
			(at 0 0 0)
			(unlocked yes)
			(layer "B.Fab")
			(hide yes)
			(effects
				(font
					(size 1 1)
					(thickness 0.15)
				)
				(justify mirror)
			)
		)
		(sheetname "/USB Debug, PD/")
		(sheetfile "usb_debug_pd.kicad_sch")
		(attr smd)
		(fp_poly
			(pts
				(xy -0.925 0.47) (xy -0.925 -0.47) (xy 0.925 -0.47) (xy 0.925 0.47)
			)
			(stroke
				(width 0.05)
				(type default)
			)
			(fill no)
			(layer "B.CrtYd")
		)
		(fp_poly
			(pts
				(xy -0.5 0.25) (xy -0.5 -0.25) (xy 0.5 -0.25) (xy 0.5 0.25)
			)
			(stroke
				(width 0.15)
				(type solid)
			)
			(fill no)
			(layer "B.Fab")
		)
		(fp_text user "${REFERENCE}"
			(at -0.95 -3.168 0)
			(layer "B.Fab")
			(effects
				(font
					(size 0.7 0.7)
					(thickness 0.15)
				)
				(justify left bottom mirror)
			)
		)
		(fp_text user "License: Apache-2.0"
			(at -0.949999 -5.169 0)
			(layer "B.Fab")
			(effects
				(font
					(size 0.7 0.7)
					(thickness 0.15)
				)
				(justify left bottom mirror)
			)
		)
		(fp_text user "Author: Antmicro"
			(at -0.95 -4.169 0)
			(layer "B.Fab")
			(effects
				(font
					(size 0.7 0.7)
					(thickness 0.15)
				)
				(justify left bottom mirror)
			)
		)
		(pad "1" smd roundrect
			(at -0.48 0 180)
			(size 0.59 0.64)
			(layers "B.Cu" "B.Mask" "B.Paste")
			(roundrect_rratio 0.25)
			(net 956 "/USB Debug, PD/FTDI_CBUS0{slash}SDA")
			(pintype "passive")
		)
		(pad "2" smd roundrect
			(at 0.48 0 180)
			(size 0.59 0.64)
			(layers "B.Cu" "B.Mask" "B.Paste")
			(roundrect_rratio 0.25)
			(net 334 "/USB Debug, PD/FTDI_3V3")
			(pintype "passive")
		)
	)
	(footprint "antmicro-footprints:R_0402_1005Metric"
		(layer "B.Cu")
		(at 223.56 124.4)
		(descr "Resistor SMD 0402")
		(tags "resistor SMD 0402")
		(property "Reference" "R336"
			(at 0.94 -0.6 0)
			(layer "B.SilkS")
			(effects
				(font
					(size 0.7 0.7)
					(thickness 0.15)
				)
				(justify right top mirror)
			)
		)
		(property "Value" "R_2R2_0402"
			(at -1.011843 -1.772047 0)
			(layer "B.Fab")
			(effects
				(font
					(size 0.7 0.7)
					(thickness 0.15)
				)
				(justify right top mirror)
			)
		)
		(property "Datasheet" "https://www.bourns.com/docs/product-datasheets/cr.pdf"
			(at 0 0 0)
			(layer "B.Fab")
			(hide yes)
			(effects
				(font
					(size 1.27 1.27)
					(thickness 0.15)
				)
				(justify mirror)
			)
		)
		(property "Description" "SMD Chip Resistor, 2.2 ohm, ± 1%, 62.5 mW, 0402 [1005 Metric], Thick Film, General Purpose"
			(at 0 0 0)
			(layer "B.Fab")
			(hide yes)
			(effects
				(font
					(size 1.27 1.27)
					(thickness 0.15)
				)
				(justify mirror)
			)
		)
		(property "MPN" "CR0402-FX-2R20GLF"
			(at 0 0 180)
			(unlocked yes)
			(layer "B.Fab")
			(hide yes)
			(effects
				(font
					(size 1 1)
					(thickness 0.15)
				)
				(justify mirror)
			)
		)
		(property "Manufacturer" "Bourns"
			(at 0 0 180)
			(unlocked yes)
			(layer "B.Fab")
			(hide yes)
			(effects
				(font
					(size 1 1)
					(thickness 0.15)
				)
				(justify mirror)
			)
		)
		(property "License" "Apache-2.0"
			(at 0 0 180)
			(unlocked yes)
			(layer "B.Fab")
			(hide yes)
			(effects
				(font
					(size 1 1)
					(thickness 0.15)
				)
				(justify mirror)
			)
		)
		(property "Author" "Antmicro"
			(at 0 0 180)
			(unlocked yes)
			(layer "B.Fab")
			(hide yes)
			(effects
				(font
					(size 1 1)
					(thickness 0.15)
				)
				(justify mirror)
			)
		)
		(property "Val" "2R2"
			(at 0 0 180)
			(unlocked yes)
			(layer "B.Fab")
			(hide yes)
			(effects
				(font
					(size 1 1)
					(thickness 0.15)
				)
				(justify mirror)
			)
		)
		(property "Tolerance" "1%"
			(at 0 0 180)
			(unlocked yes)
			(layer "B.Fab")
			(hide yes)
			(effects
				(font
					(size 1 1)
					(thickness 0.15)
				)
				(justify mirror)
			)
		)
		(sheetname "/USB Hub/")
		(sheetfile "usb_hub.kicad_sch")
		(attr smd)
		(fp_rect
			(start -0.925 0.47)
			(end 0.925 -0.47)
			(stroke
				(width 0.05)
				(type default)
			)
			(fill no)
			(layer "B.CrtYd")
		)
		(fp_rect
			(start -0.5 0.25)
			(end 0.5 -0.25)
			(stroke
				(width 0.15)
				(type solid)
			)
			(fill no)
			(layer "B.Fab")
		)
		(fp_text user "License: Apache-2.0"
			(at -0.95 -5.169 0)
			(layer "B.Fab")
			(effects
				(font
					(size 0.7 0.7)
					(thickness 0.15)
				)
				(justify right top mirror)
			)
		)
		(fp_text user "${REFERENCE}"
			(at -0.95 -3.168 0)
			(layer "B.Fab")
			(effects
				(font
					(size 0.7 0.7)
					(thickness 0.15)
				)
				(justify right top mirror)
			)
		)
		(fp_text user "Author: Antmicro"
			(at -0.95 -4.169 0)
			(layer "B.Fab")
			(effects
				(font
					(size 0.7 0.7)
					(thickness 0.15)
				)
				(justify right top mirror)
			)
		)
		(pad "1" smd roundrect
			(at -0.48 0)
			(size 0.59 0.64)
			(layers "B.Cu" "B.Mask" "B.Paste")
			(roundrect_rratio 0.25)
			(net 1238 "Net-(D59-C)")
			(pintype "passive")
		)
		(pad "2" smd roundrect
			(at 0.48 0)
			(size 0.59 0.64)
			(layers "B.Cu" "B.Mask" "B.Paste")
			(roundrect_rratio 0.25)
			(net 503 "/USB Hub/USBC4_CC_{1}")
			(pintype "passive")
		)
	)
	(footprint "antmicro-footprints:R_0402_1005Metric"
		(layer "B.Cu")
		(at 207 62.483)
		(descr "Resistor SMD 0402")
		(tags "resistor SMD 0402")
		(property "Reference" "R180"
			(at -3.77 -0.48 0)
			(layer "B.SilkS")
			(effects
				(font
					(size 0.7 0.7)
					(thickness 0.15)
				)
				(justify right top mirror)
			)
		)
		(property "Value" "R_4k7_0402"
			(at -1.011843 -1.772046 0)
			(layer "B.Fab")
			(effects
				(font
					(size 0.7 0.7)
					(thickness 0.15)
				)
				(justify right top mirror)
			)
		)
		(property "Datasheet" "https://www.bourns.com/docs/product-datasheets/cr.pdf"
			(at 0 0 0)
			(layer "B.Fab")
			(hide yes)
			(effects
				(font
					(size 1.27 1.27)
					(thickness 0.15)
				)
				(justify mirror)
			)
		)
		(property "Description" "SMD Chip Resistor, 4.7 kohm, ± 1%, 62.5 mW, 0402 [1005 Metric], Thick Film, General Purpose"
			(at 0 0 0)
			(layer "B.Fab")
			(hide yes)
			(effects
				(font
					(size 1.27 1.27)
					(thickness 0.15)
				)
				(justify mirror)
			)
		)
		(property "Manufacturer" "Bourns"
			(at 0 0 180)
			(unlocked yes)
			(layer "B.Fab")
			(hide yes)
			(effects
				(font
					(size 1 1)
					(thickness 0.15)
				)
				(justify mirror)
			)
		)
		(property "MPN" "CR0402-FX-4701GLF"
			(at 0 0 180)
			(unlocked yes)
			(layer "B.Fab")
			(hide yes)
			(effects
				(font
					(size 1 1)
					(thickness 0.15)
				)
				(justify mirror)
			)
		)
		(property "Val" "4k7"
			(at 0 0 180)
			(unlocked yes)
			(layer "B.Fab")
			(hide yes)
			(effects
				(font
					(size 1 1)
					(thickness 0.15)
				)
				(justify mirror)
			)
		)
		(property "License" "Apache-2.0"
			(at 0 0 180)
			(unlocked yes)
			(layer "B.Fab")
			(hide yes)
			(effects
				(font
					(size 1 1)
					(thickness 0.15)
				)
				(justify mirror)
			)
		)
		(property "Author" "Antmicro"
			(at 0 0 180)
			(unlocked yes)
			(layer "B.Fab")
			(hide yes)
			(effects
				(font
					(size 1 1)
					(thickness 0.15)
				)
				(justify mirror)
			)
		)
		(property "Tolerance" "1%"
			(at 0 0 180)
			(unlocked yes)
			(layer "B.Fab")
			(hide yes)
			(effects
				(font
					(size 1 1)
					(thickness 0.15)
				)
				(justify mirror)
			)
		)
		(sheetname "/CSI/")
		(sheetfile "csi.kicad_sch")
		(attr smd)
		(fp_poly
			(pts
				(xy -0.925 0.47) (xy -0.925 -0.47) (xy 0.925 -0.47) (xy 0.925 0.47)
			)
			(stroke
				(width 0.05)
				(type default)
			)
			(fill no)
			(layer "B.CrtYd")
		)
		(fp_poly
			(pts
				(xy -0.5 0.25) (xy -0.5 -0.25) (xy 0.5 -0.25) (xy 0.5 0.25)
			)
			(stroke
				(width 0.15)
				(type solid)
			)
			(fill no)
			(layer "B.Fab")
		)
		(fp_text user "License: Apache-2.0"
			(at -0.949999 -5.169 0)
			(layer "B.Fab")
			(effects
				(font
					(size 0.7 0.7)
					(thickness 0.15)
				)
				(justify right top mirror)
			)
		)
		(fp_text user "${REFERENCE}"
			(at -0.95 -3.168 0)
			(layer "B.Fab")
			(effects
				(font
					(size 0.7 0.7)
					(thickness 0.15)
				)
				(justify right top mirror)
			)
		)
		(fp_text user "Author: Antmicro"
			(at -0.95 -4.169 0)
			(layer "B.Fab")
			(effects
				(font
					(size 0.7 0.7)
					(thickness 0.15)
				)
				(justify right top mirror)
			)
		)
		(pad "1" smd roundrect
			(at -0.48 0)
			(size 0.59 0.64)
			(layers "B.Cu" "B.Mask" "B.Paste")
			(roundrect_rratio 0.25)
			(net 1 "GND")
			(pintype "passive")
		)
		(pad "2" smd roundrect
			(at 0.48 0)
			(size 0.59 0.64)
			(layers "B.Cu" "B.Mask" "B.Paste")
			(roundrect_rratio 0.25)
			(net 998 "/CSI/CSIB_3V3_ISET")
			(pintype "passive")
		)
	)
	(footprint "antmicro-footprints:SOT-523"
		(layer "B.Cu")
		(at 99.15 65.51 -90)
		(property "Reference" "Q37"
			(at -0.91 1.25 90)
			(layer "B.SilkS")
			(effects
				(font
					(size 0.7 0.7)
					(thickness 0.15)
				)
				(justify left bottom mirror)
			)
		)
		(property "Value" "DMG1012T-7"
			(at 0.1 -1.824 90)
			(layer "B.Fab")
			(effects
				(font
					(size 0.7 0.7)
					(thickness 0.15)
				)
				(justify left bottom mirror)
			)
		)
		(property "Datasheet" "https://www.diodes.com/assets/Datasheets/ds31783.pdf"
			(at 0 0 90)
			(layer "B.Fab")
			(hide yes)
			(effects
				(font
					(size 1.27 1.27)
					(thickness 0.15)
				)
				(justify mirror)
			)
		)
		(property "Description" "Power MOSFET, N Channel, 20 V, 630 mA, 0.3 ohm, SOT-523, Surface Mount"
			(at 0 0 90)
			(layer "B.Fab")
			(hide yes)
			(effects
				(font
					(size 1.27 1.27)
					(thickness 0.15)
				)
				(justify mirror)
			)
		)
		(property "MPN" "DMG1012T-7"
			(at 0 0 90)
			(unlocked yes)
			(layer "B.Fab")
			(hide yes)
			(effects
				(font
					(size 1 1)
					(thickness 0.15)
				)
				(justify mirror)
			)
		)
		(property "Manufacturer" "Diodes Incorporated"
			(at 0 0 90)
			(unlocked yes)
			(layer "B.Fab")
			(hide yes)
			(effects
				(font
					(size 1 1)
					(thickness 0.15)
				)
				(justify mirror)
			)
		)
		(property "Author" "Antmicro"
			(at 0 0 90)
			(unlocked yes)
			(layer "B.Fab")
			(hide yes)
			(effects
				(font
					(size 1 1)
					(thickness 0.15)
				)
				(justify mirror)
			)
		)
		(property "License" "Apache-2.0"
			(at 0 0 90)
			(unlocked yes)
			(layer "B.Fab")
			(hide yes)
			(effects
				(font
					(size 1 1)
					(thickness 0.15)
				)
				(justify mirror)
			)
		)
		(sheetname "/SoM_Power/")
		(sheetfile "som_power.kicad_sch")
		(attr smd)
		(fp_line
			(start -0.725 0.551)
			(end -0.277 0.551)
			(stroke
				(width 0.15)
				(type solid)
			)
			(layer "B.SilkS")
		)
		(fp_line
			(start -0.277 0.551)
			(end -0.277 0.75)
			(stroke
				(width 0.15)
				(type solid)
			)
			(layer "B.SilkS")
		)
		(fp_line
			(start -0.927 0.351)
			(end -0.725 0.551)
			(stroke
				(width 0.15)
				(type solid)
			)
			(layer "B.SilkS")
		)
		(fp_line
			(start -0.927 0.051)
			(end -0.927 0.351)
			(stroke
				(width 0.15)
				(type solid)
			)
			(layer "B.SilkS")
		)
		(fp_circle
			(center -0.9652 -0.9652)
			(end -0.9152 -0.9652)
			(stroke
				(width 0.15)
				(type solid)
			)
			(fill yes)
			(layer "B.SilkS")
		)
		(fp_line
			(start -1.12 1.16)
			(end 1.1 1.16)
			(stroke
				(width 0.05)
				(type solid)
			)
			(layer "B.CrtYd")
		)
		(fp_line
			(start -1.12 1.16)
			(end -1.12 -1.15)
			(stroke
				(width 0.05)
				(type solid)
			)
			(layer "B.CrtYd")
		)
		(fp_line
			(start 1.1 1.16)
			(end 1.1 -1.15)
			(stroke
				(width 0.05)
				(type solid)
			)
			(layer "B.CrtYd")
		)
		(fp_line
			(start -1.12 -1.15)
			(end 1.1 -1.15)
			(stroke
				(width 0.05)
				(type solid)
			)
			(layer "B.CrtYd")
		)
		(fp_line
			(start -0.652 0.425)
			(end -0.802 0.276)
			(stroke
				(width 0.15)
				(type solid)
			)
			(layer "B.Fab")
		)
		(fp_line
			(start 0.8 0.425)
			(end -0.652 0.425)
			(stroke
				(width 0.15)
				(type solid)
			)
			(layer "B.Fab")
		)
		(fp_line
			(start 0.8 0.425)
			(end 0.8 -0.424)
			(stroke
				(width 0.15)
				(type solid)
			)
			(layer "B.Fab")
		)
		(fp_line
			(start -0.802 0.276)
			(end -0.802 -0.424)
			(stroke
				(width 0.15)
				(type solid)
			)
			(layer "B.Fab")
		)
		(fp_line
			(start 0.8 -0.424)
			(end -0.802 -0.424)
			(stroke
				(width 0.15)
				(type solid)
			)
			(layer "B.Fab")
		)
		(fp_circle
			(center -0.9652 -0.9652)
			(end -0.9144 -0.9652)
			(stroke
				(width 0.15)
				(type solid)
			)
			(fill no)
			(layer "B.Fab")
		)
		(fp_text user "License: Apache-2.0"
			(at -1.12 -5.024 90)
			(layer "B.Fab")
			(effects
				(font
					(size 0.7 0.7)
					(thickness 0.15)
				)
				(justify left bottom mirror)
			)
		)
		(fp_text user "Author: Antmicro"
			(at -1.12 -6.224 90)
			(layer "B.Fab")
			(effects
				(font
					(size 0.7 0.7)
					(thickness 0.15)
				)
				(justify left bottom mirror)
			)
		)
		(fp_text user "${REFERENCE}"
			(at -1.12 -3.824 90)
			(layer "B.Fab")
			(effects
				(font
					(size 0.7 0.7)
					(thickness 0.15)
				)
				(justify left bottom mirror)
			)
		)
		(pad "1" smd rect
			(at -0.5 -0.65 270)
			(size 0.4 0.51)
			(layers "B.Cu" "B.Mask" "B.Paste")
			(net 1298 "Net-(Q37-G)")
			(pinfunction "G")
			(pintype "input")
		)
		(pad "2" smd rect
			(at 0.498 -0.65 270)
			(size 0.4 0.51)
			(layers "B.Cu" "B.Mask" "B.Paste")
			(net 1 "GND")
			(pinfunction "S")
			(pintype "passive")
		)
		(pad "3" smd rect
			(at 0 0.652 270)
			(size 0.4 0.51)
			(layers "B.Cu" "B.Mask" "B.Paste")
			(net 1302 "Net-(Q37-D)")
			(pinfunction "D")
			(pintype "passive")
		)
	)
	(footprint "antmicro-footprints:TP_SMD_0.75mm"
		(layer "B.Cu")
		(at 142.830532 75.81 90)
		(property "Reference" "TP34"
			(at -1.49 1.669468 0)
			(layer "B.SilkS")
			(effects
				(font
					(size 0.7 0.7)
					(thickness 0.15)
				)
				(justify left bottom mirror)
			)
		)
		(property "Value" "TP_0.75mm_SMD"
			(at 0 -1.2 90)
			(layer "B.Fab")
			(effects
				(font
					(size 0.7 0.7)
					(thickness 0.15)
				)
				(justify right top mirror)
			)
		)
		(property "Description" "SMT test point"
			(at 0 0 90)
			(layer "B.Fab")
			(hide yes)
			(effects
				(font
					(size 1.27 1.27)
					(thickness 0.15)
				)
				(justify mirror)
			)
		)
		(property "MPN" ""
			(at 0 0 270)
			(unlocked yes)
			(layer "B.Fab")
			(hide yes)
			(effects
				(font
					(size 1 1)
					(thickness 0.15)
				)
				(justify mirror)
			)
		)
		(property "Manufacturer" ""
			(at 0 0 270)
			(unlocked yes)
			(layer "B.Fab")
			(hide yes)
			(effects
				(font
					(size 1 1)
					(thickness 0.15)
				)
				(justify mirror)
			)
		)
		(property "Author" "Antmicro"
			(at 0 0 270)
			(unlocked yes)
			(layer "B.Fab")
			(hide yes)
			(effects
				(font
					(size 1 1)
					(thickness 0.15)
				)
				(justify mirror)
			)
		)
		(property "License" "Apache-2.0"
			(at 0 0 270)
			(unlocked yes)
			(layer "B.Fab")
			(hide yes)
			(effects
				(font
					(size 1 1)
					(thickness 0.15)
				)
				(justify mirror)
			)
		)
		(sheetname "/SoM_Power/")
		(sheetfile "som_power.kicad_sch")
		(attr exclude_from_pos_files exclude_from_bom)
		(fp_circle
			(center 0 0)
			(end 0.475 0)
			(stroke
				(width 0.05)
				(type default)
			)
			(fill no)
			(layer "B.CrtYd")
		)
		(fp_text user "License: Apache-2.0"
			(at -0.4 -5.101 90)
			(layer "B.Fab")
			(effects
				(font
					(size 0.7 0.7)
					(thickness 0.15)
				)
				(justify right top mirror)
			)
		)
		(fp_text user "${REFERENCE}"
			(at -0.4 -2.7 90)
			(layer "B.Fab")
			(effects
				(font
					(size 0.7 0.7)
					(thickness 0.15)
				)
				(justify right top mirror)
			)
		)
		(fp_text user "Author: Antmicro"
			(at -0.4 -3.901 90)
			(layer "B.Fab")
			(effects
				(font
					(size 0.7 0.7)
					(thickness 0.15)
				)
				(justify right top mirror)
			)
		)
		(pad "1" smd circle
			(at 0 0 90)
			(size 0.75 0.75)
			(layers "B.Cu" "B.Mask")
			(net 758 "Net-(J1A-GPIO31)")
			(pinfunction "1")
			(pintype "passive")
		)
	)
	(footprint "antmicro-footprints:C_0603_1608Metric_EIA"
		(layer "B.Cu")
		(at 200.226 145.25 90)
		(descr "Capacitor SMD 0603, IPC-7351 Density Level A")
		(tags "Capacitor 0603")
		(property "Reference" "C168"
			(at 4.15 0.5 270)
			(layer "B.SilkS")
			(effects
				(font
					(size 0.7 0.7)
					(thickness 0.15)
				)
				(justify left bottom mirror)
			)
		)
		(property "Value" "C_22u_16V_0603"
			(at -1.42757 -1.770288 270)
			(layer "B.Fab")
			(effects
				(font
					(size 0.7 0.7)
					(thickness 0.15)
				)
				(justify left bottom mirror)
			)
		)
		(property "Datasheet" "https://product.samsungsem.com/mlcc/CL10A226MO7JZN.do"
			(at 0 0 270)
			(layer "B.Fab")
			(hide yes)
			(effects
				(font
					(size 1.27 1.27)
					(thickness 0.15)
				)
				(justify mirror)
			)
		)
		(property "Description" "SMD Multilayer Ceramic Capacitor"
			(at 0 0 270)
			(layer "B.Fab")
			(hide yes)
			(effects
				(font
					(size 1.27 1.27)
					(thickness 0.15)
				)
				(justify mirror)
			)
		)
		(property "MPN" "CL10A226MO7JZNC"
			(at 0 0 90)
			(unlocked yes)
			(layer "B.Fab")
			(hide yes)
			(effects
				(font
					(size 1 1)
					(thickness 0.15)
				)
				(justify mirror)
			)
		)
		(property "Manufacturer" "Samsung Electro-Mechanics"
			(at 0 0 90)
			(unlocked yes)
			(layer "B.Fab")
			(hide yes)
			(effects
				(font
					(size 1 1)
					(thickness 0.15)
				)
				(justify mirror)
			)
		)
		(property "License" "Apache-2.0"
			(at 0 0 90)
			(unlocked yes)
			(layer "B.Fab")
			(hide yes)
			(effects
				(font
					(size 1 1)
					(thickness 0.15)
				)
				(justify mirror)
			)
		)
		(property "Author" "Antmicro"
			(at 0 0 90)
			(unlocked yes)
			(layer "B.Fab")
			(hide yes)
			(effects
				(font
					(size 1 1)
					(thickness 0.15)
				)
				(justify mirror)
			)
		)
		(property "Val" "22u"
			(at 0 0 90)
			(unlocked yes)
			(layer "B.Fab")
			(hide yes)
			(effects
				(font
					(size 1 1)
					(thickness 0.15)
				)
				(justify mirror)
			)
		)
		(property "Voltage" "16V"
			(at 0 0 90)
			(unlocked yes)
			(layer "B.Fab")
			(hide yes)
			(effects
				(font
					(size 1 1)
					(thickness 0.15)
				)
				(justify mirror)
			)
		)
		(property "Dielectric" ""
			(at 0 0 90)
			(unlocked yes)
			(layer "B.Fab")
			(hide yes)
			(effects
				(font
					(size 1 1)
					(thickness 0.15)
				)
				(justify mirror)
			)
		)
		(sheetname "/SFP/")
		(sheetfile "sfp.kicad_sch")
		(attr smd)
		(fp_line
			(start -0.15 -0.55)
			(end 0.15 -0.55)
			(stroke
				(width 0.15)
				(type solid)
			)
			(layer "B.SilkS")
		)
		(fp_line
			(start -0.15 0.55)
			(end 0.15 0.55)
			(stroke
				(width 0.15)
				(type solid)
			)
			(layer "B.SilkS")
		)
		(fp_rect
			(start -1.25 0.65)
			(end 1.25 -0.65)
			(stroke
				(width 0.05)
				(type solid)
			)
			(fill no)
			(layer "B.CrtYd")
		)
		(fp_rect
			(start -0.8 0.45)
			(end 0.8 -0.45)
			(stroke
				(width 0.15)
				(type solid)
			)
			(fill no)
			(layer "B.Fab")
		)
		(fp_text user "License: Apache-2.0"
			(at -1.682 -5.895 270)
			(layer "B.Fab")
			(effects
				(font
					(size 0.7 0.7)
					(thickness 0.15)
				)
				(justify left bottom mirror)
			)
		)
		(fp_text user "Author: Antmicro"
			(at -1.682 -4.894 270)
			(layer "B.Fab")
			(effects
				(font
					(size 0.7 0.7)
					(thickness 0.15)
				)
				(justify left bottom mirror)
			)
		)
		(fp_text user "${REFERENCE}"
			(at -1.682 -3.895 270)
			(layer "B.Fab")
			(effects
				(font
					(size 0.7 0.7)
					(thickness 0.15)
				)
				(justify left bottom mirror)
			)
		)
		(pad "1" smd roundrect
			(at -0.7 0 90)
			(size 0.8 1.1)
			(layers "B.Cu" "B.Mask" "B.Paste")
			(roundrect_rratio 0.2)
			(net 1 "GND")
			(pintype "passive")
		)
		(pad "2" smd roundrect
			(at 0.7 0 90)
			(size 0.8 1.1)
			(layers "B.Cu" "B.Mask" "B.Paste")
			(roundrect_rratio 0.2)
			(net 2 "+3V3")
			(pintype "passive")
		)
	)
	(footprint "antmicro-footprints:TSOT23-6"
		(layer "B.Cu")
		(at 232.4 108.654)
		(property "Reference" "U23"
			(at -0.9 -2.654 0)
			(layer "B.SilkS")
			(effects
				(font
					(size 0.7 0.7)
					(thickness 0.15)
				)
				(justify right top mirror)
			)
		)
		(property "Value" "AP22615A_TSOT26"
			(at 0 -2.600001 0)
			(layer "B.Fab")
			(effects
				(font
					(size 0.7 0.7)
					(thickness 0.15)
				)
				(justify right top mirror)
			)
		)
		(property "Datasheet" "https://www.mouser.com/datasheet/2/115/DIOD_S_A0008958405_1-2543193.pdf"
			(at 0 0 0)
			(layer "B.Fab")
			(hide yes)
			(effects
				(font
					(size 1.27 1.27)
					(thickness 0.15)
				)
				(justify mirror)
			)
		)
		(property "Description" "Power Load Distribution Switch, High Side, Active High, 1 Output, 5.5 V, 3.6 A, 0.04 ohm, TSOT-26-6"
			(at 0 0 0)
			(layer "B.Fab")
			(hide yes)
			(effects
				(font
					(size 1.27 1.27)
					(thickness 0.15)
				)
				(justify mirror)
			)
		)
		(property "MPN" "AP22615AWU-7"
			(at 0 0 180)
			(unlocked yes)
			(layer "B.Fab")
			(hide yes)
			(effects
				(font
					(size 1 1)
					(thickness 0.15)
				)
				(justify mirror)
			)
		)
		(property "Manufacturer" "Diodes Incorporated"
			(at 0 0 180)
			(unlocked yes)
			(layer "B.Fab")
			(hide yes)
			(effects
				(font
					(size 1 1)
					(thickness 0.15)
				)
				(justify mirror)
			)
		)
		(property "Author" "Antmicro"
			(at 0 0 180)
			(unlocked yes)
			(layer "B.Fab")
			(hide yes)
			(effects
				(font
					(size 1 1)
					(thickness 0.15)
				)
				(justify mirror)
			)
		)
		(property "License" "Apache-2.0"
			(at 0 0 180)
			(unlocked yes)
			(layer "B.Fab")
			(hide yes)
			(effects
				(font
					(size 1 1)
					(thickness 0.15)
				)
				(justify mirror)
			)
		)
		(sheetname "/Recovery USB/")
		(sheetfile "recovery_usb.kicad_sch")
		(attr smd)
		(fp_line
			(start -1 -1.55)
			(end -1 -1.4)
			(stroke
				(width 0.15)
				(type solid)
			)
			(layer "B.SilkS")
		)
		(fp_line
			(start -1 1.5)
			(end -1 1.375)
			(stroke
				(width 0.15)
				(type solid)
			)
			(layer "B.SilkS")
		)
		(fp_line
			(start 1 -1.55)
			(end -1 -1.55)
			(stroke
				(width 0.15)
				(type solid)
			)
			(layer "B.SilkS")
		)
		(fp_line
			(start 1 -1.55)
			(end 1 -1.4)
			(stroke
				(width 0.15)
				(type solid)
			)
			(layer "B.SilkS")
		)
		(fp_line
			(start 1 1.497)
			(end -1 1.5)
			(stroke
				(width 0.15)
				(type solid)
			)
			(layer "B.SilkS")
		)
		(fp_line
			(start 1 1.497)
			(end 1 1.375)
			(stroke
				(width 0.15)
				(type solid)
			)
			(layer "B.SilkS")
		)
		(fp_circle
			(center -1.44 1.5)
			(end -1.39 1.5)
			(stroke
				(width 0.15)
				(type solid)
			)
			(fill yes)
			(layer "B.SilkS")
		)
		(fp_poly
			(pts
				(xy 1.930001 1.7) (xy 1.930001 -1.7) (xy -1.930001 -1.7) (xy -1.930001 1.7)
			)
			(stroke
				(width 0.05)
				(type solid)
			)
			(fill no)
			(layer "B.CrtYd")
		)
		(fp_line
			(start -0.45 1.520999)
			(end -0.876001 1.096)
			(stroke
				(width 0.15)
				(type solid)
			)
			(layer "B.Fab")
		)
		(fp_poly
			(pts
				(xy 0.875 -1.528) (xy 0.875 1.525) (xy -0.875 1.525) (xy -0.875 -1.528)
			)
			(stroke
				(width 0.15)
				(type solid)
			)
			(fill no)
			(layer "B.Fab")
		)
		(fp_text user "${REFERENCE}"
			(at -1.93 -3.8 0)
			(layer "B.Fab")
			(effects
				(font
					(size 0.7 0.7)
					(thickness 0.15)
				)
				(justify right top mirror)
			)
		)
		(fp_text user "Author: Antmicro"
			(at -1.93 -5 0)
			(layer "B.Fab")
			(effects
				(font
					(size 0.7 0.7)
					(thickness 0.15)
				)
				(justify right top mirror)
			)
		)
		(fp_text user "License: Apache-2.0"
			(at -1.93 -6.199 0)
			(layer "B.Fab")
			(effects
				(font
					(size 0.7 0.7)
					(thickness 0.15)
				)
				(justify right top mirror)
			)
		)
		(pad "1" smd rect
			(at -1.301 0.947 90)
			(size 0.7 1.2)
			(layers "B.Cu" "B.Mask" "B.Paste")
			(net 287 "/Recovery USB/USBC2_VBUS")
			(pinfunction "OUT")
			(pintype "power_out")
		)
		(pad "2" smd rect
			(at -1.300999 -0.004 90)
			(size 0.7 1.2)
			(layers "B.Cu" "B.Mask" "B.Paste")
			(net 1 "GND")
			(pinfunction "GND")
			(pintype "power_in")
		)
		(pad "3" smd rect
			(at -1.301 -0.954 90)
			(size 0.7 1.2)
			(layers "B.Cu" "B.Mask" "B.Paste")
			(net 1243 "Net-(U23-FLG)")
			(pinfunction "FLG")
			(pintype "output")
		)
		(pad "4" smd rect
			(at 1.299 -0.954 90)
			(size 0.7 1.2)
			(layers "B.Cu" "B.Mask" "B.Paste")
			(net 890 "Net-(Q19-D)")
			(pinfunction "EN")
			(pintype "input")
		)
		(pad "5" smd rect
			(at 1.299 -0.004 90)
			(size 0.7 1.2)
			(layers "B.Cu" "B.Mask" "B.Paste")
			(net 1020 "/Recovery USB/USBC2_ISET")
			(pinfunction "ISET")
			(pintype "passive")
		)
		(pad "6" smd rect
			(at 1.299 0.947 90)
			(size 0.7 1.2)
			(layers "B.Cu" "B.Mask" "B.Paste")
			(net 5 "+5V")
			(pinfunction "IN")
			(pintype "power_in")
		)
	)
	(footprint "antmicro-footprints:TP_SMD_0.75mm"
		(layer "B.Cu")
		(at 94.9 84.6 90)
		(property "Reference" "TP35"
			(at -3.2 -0.3 90)
			(layer "B.SilkS")
			(effects
				(font
					(size 0.7 0.7)
					(thickness 0.15)
				)
				(justify right top mirror)
			)
		)
		(property "Value" "TP_0.75mm_SMD"
			(at 0 -1.2 90)
			(layer "B.Fab")
			(effects
				(font
					(size 0.7 0.7)
					(thickness 0.15)
				)
				(justify right top mirror)
			)
		)
		(property "Description" "SMT test point"
			(at 0 0 90)
			(layer "B.Fab")
			(hide yes)
			(effects
				(font
					(size 1.27 1.27)
					(thickness 0.15)
				)
				(justify mirror)
			)
		)
		(property "MPN" ""
			(at 0 0 270)
			(unlocked yes)
			(layer "B.Fab")
			(hide yes)
			(effects
				(font
					(size 1 1)
					(thickness 0.15)
				)
				(justify mirror)
			)
		)
		(property "Manufacturer" ""
			(at 0 0 270)
			(unlocked yes)
			(layer "B.Fab")
			(hide yes)
			(effects
				(font
					(size 1 1)
					(thickness 0.15)
				)
				(justify mirror)
			)
		)
		(property "Author" "Antmicro"
			(at 0 0 270)
			(unlocked yes)
			(layer "B.Fab")
			(hide yes)
			(effects
				(font
					(size 1 1)
					(thickness 0.15)
				)
				(justify mirror)
			)
		)
		(property "License" "Apache-2.0"
			(at 0 0 270)
			(unlocked yes)
			(layer "B.Fab")
			(hide yes)
			(effects
				(font
					(size 1 1)
					(thickness 0.15)
				)
				(justify mirror)
			)
		)
		(sheetname "/SoM_Power/")
		(sheetfile "som_power.kicad_sch")
		(attr exclude_from_pos_files exclude_from_bom)
		(fp_circle
			(center 0 0)
			(end 0.475 0)
			(stroke
				(width 0.05)
				(type default)
			)
			(fill no)
			(layer "B.CrtYd")
		)
		(fp_text user "Author: Antmicro"
			(at -0.4 -3.901 90)
			(layer "B.Fab")
			(effects
				(font
					(size 0.7 0.7)
					(thickness 0.15)
				)
				(justify right top mirror)
			)
		)
		(fp_text user "${REFERENCE}"
			(at -0.4 -2.7 90)
			(layer "B.Fab")
			(effects
				(font
					(size 0.7 0.7)
					(thickness 0.15)
				)
				(justify right top mirror)
			)
		)
		(fp_text user "License: Apache-2.0"
			(at -0.4 -5.101 90)
			(layer "B.Fab")
			(effects
				(font
					(size 0.7 0.7)
					(thickness 0.15)
				)
				(justify right top mirror)
			)
		)
		(pad "1" smd circle
			(at 0 0 90)
			(size 0.75 0.75)
			(layers "B.Cu" "B.Mask")
			(net 795 "Net-(J1A-POWER_INT_N)")
			(pinfunction "1")
			(pintype "passive")
		)
	)
	(footprint "antmicro-footprints:C_0402_1005Metric"
		(layer "B.Cu")
		(at 145.7 81.2)
		(descr "Capacitor SMD 0402")
		(tags "capacitor SMD 0402")
		(property "Reference" "C84"
			(at 1.1 1.5 180)
			(layer "B.SilkS")
			(effects
				(font
					(size 0.7 0.7)
					(thickness 0.15)
				)
				(justify left bottom mirror)
			)
		)
		(property "Value" "C_1u_25V_0402"
			(at -1.022927 -2.155213 180)
			(layer "B.Fab")
			(effects
				(font
					(size 0.7 0.7)
					(thickness 0.15)
				)
				(justify left bottom mirror)
			)
		)
		(property "Datasheet" "https://www.murata.com/products/productdetail?partno=GRM155R61E105KE11%23"
			(at 0 0 180)
			(layer "B.Fab")
			(hide yes)
			(effects
				(font
					(size 1.27 1.27)
					(thickness 0.15)
				)
				(justify mirror)
			)
		)
		(property "Description" "SMD Multilayer Ceramic Capacitor, 1 µF, 25 V, 0402 [1005 Metric], ± 10%, X5R, GRM Series"
			(at 0 0 180)
			(layer "B.Fab")
			(hide yes)
			(effects
				(font
					(size 1.27 1.27)
					(thickness 0.15)
				)
				(justify mirror)
			)
		)
		(property "MPN" "GRM155R61E105KE11J"
			(at 0 0 180)
			(unlocked yes)
			(layer "B.Fab")
			(hide yes)
			(effects
				(font
					(size 1 1)
					(thickness 0.15)
				)
				(justify mirror)
			)
		)
		(property "Manufacturer" "Murata"
			(at 0 0 180)
			(unlocked yes)
			(layer "B.Fab")
			(hide yes)
			(effects
				(font
					(size 1 1)
					(thickness 0.15)
				)
				(justify mirror)
			)
		)
		(property "License" "Apache-2.0"
			(at 0 0 180)
			(unlocked yes)
			(layer "B.Fab")
			(hide yes)
			(effects
				(font
					(size 1 1)
					(thickness 0.15)
				)
				(justify mirror)
			)
		)
		(property "Author" "Antmicro"
			(at 0 0 180)
			(unlocked yes)
			(layer "B.Fab")
			(hide yes)
			(effects
				(font
					(size 1 1)
					(thickness 0.15)
				)
				(justify mirror)
			)
		)
		(property "Val" "1u"
			(at 0 0 180)
			(unlocked yes)
			(layer "B.Fab")
			(hide yes)
			(effects
				(font
					(size 1 1)
					(thickness 0.15)
				)
				(justify mirror)
			)
		)
		(property "Voltage" "25V"
			(at 0 0 180)
			(unlocked yes)
			(layer "B.Fab")
			(hide yes)
			(effects
				(font
					(size 1 1)
					(thickness 0.15)
				)
				(justify mirror)
			)
		)
		(property "Dielectric" "X5R"
			(at 0 0 180)
			(unlocked yes)
			(layer "B.Fab")
			(hide yes)
			(effects
				(font
					(size 1 1)
					(thickness 0.15)
				)
				(justify mirror)
			)
		)
		(sheetname "/SoM_Power/")
		(sheetfile "som_power.kicad_sch")
		(attr smd)
		(fp_rect
			(start -0.925 0.47)
			(end 0.925 -0.47)
			(stroke
				(width 0.05)
				(type default)
			)
			(fill no)
			(layer "B.CrtYd")
		)
		(fp_line
			(start -0.494 -0.248)
			(end -0.494 0.25)
			(stroke
				(width 0.15)
				(type solid)
			)
			(layer "B.Fab")
		)
		(fp_line
			(start -0.494 0.25)
			(end 0.504 0.25)
			(stroke
				(width 0.15)
				(type solid)
			)
			(layer "B.Fab")
		)
		(fp_line
			(start 0.504 -0.248)
			(end -0.494 -0.248)
			(stroke
				(width 0.15)
				(type solid)
			)
			(layer "B.Fab")
		)
		(fp_line
			(start 0.504 0.25)
			(end 0.504 -0.248)
			(stroke
				(width 0.15)
				(type solid)
			)
			(layer "B.Fab")
		)
		(fp_text user "Author: Antmicro"
			(at -0.939 -3.399 180)
			(layer "B.Fab")
			(effects
				(font
					(size 0.7 0.7)
					(thickness 0.15)
				)
				(justify left bottom mirror)
			)
		)
		(fp_text user "${REFERENCE}"
			(at -0.939 -4.599 180)
			(layer "B.Fab")
			(effects
				(font
					(size 0.7 0.7)
					(thickness 0.15)
				)
				(justify left bottom mirror)
			)
		)
		(fp_text user "License: Apache-2.0"
			(at -0.939 -5.799 180)
			(layer "B.Fab")
			(effects
				(font
					(size 0.7 0.7)
					(thickness 0.15)
				)
				(justify left bottom mirror)
			)
		)
		(pad "1" smd roundrect
			(at -0.48 0)
			(size 0.59 0.64)
			(layers "B.Cu" "B.Mask" "B.Paste")
			(roundrect_rratio 0.25)
			(net 1 "GND")
			(pintype "passive")
		)
		(pad "2" smd roundrect
			(at 0.48 0)
			(size 0.59 0.64)
			(layers "B.Cu" "B.Mask" "B.Paste")
			(roundrect_rratio 0.25)
			(net 12 "SYS_VIN_HV")
			(pintype "passive")
		)
	)
	(footprint "antmicro-footprints:C_0603_1608Metric_EIA"
		(layer "B.Cu")
		(at 197.45 127.05)
		(descr "Capacitor SMD 0603, IPC-7351 Density Level A")
		(tags "Capacitor 0603")
		(property "Reference" "C312"
			(at -1.45 -1.65 0)
			(layer "B.SilkS")
			(effects
				(font
					(size 0.7 0.7)
					(thickness 0.15)
				)
				(justify right top mirror)
			)
		)
		(property "Value" "C_22u_16V_0603"
			(at -1.42757 -1.770288 0)
			(layer "B.Fab")
			(effects
				(font
					(size 0.7 0.7)
					(thickness 0.15)
				)
				(justify right top mirror)
			)
		)
		(property "Datasheet" "https://product.samsungsem.com/mlcc/CL10A226MO7JZN.do"
			(at 0 0 0)
			(layer "B.Fab")
			(hide yes)
			(effects
				(font
					(size 1.27 1.27)
					(thickness 0.15)
				)
				(justify mirror)
			)
		)
		(property "Description" "SMD Multilayer Ceramic Capacitor"
			(at 0 0 0)
			(layer "B.Fab")
			(hide yes)
			(effects
				(font
					(size 1.27 1.27)
					(thickness 0.15)
				)
				(justify mirror)
			)
		)
		(property "Manufacturer" "Samsung Electro-Mechanics"
			(at 0 0 180)
			(unlocked yes)
			(layer "B.Fab")
			(hide yes)
			(effects
				(font
					(size 1 1)
					(thickness 0.15)
				)
				(justify mirror)
			)
		)
		(property "MPN" "CL10A226MO7JZNC"
			(at 0 0 180)
			(unlocked yes)
			(layer "B.Fab")
			(hide yes)
			(effects
				(font
					(size 1 1)
					(thickness 0.15)
				)
				(justify mirror)
			)
		)
		(property "Val" "22u"
			(at 0 0 180)
			(unlocked yes)
			(layer "B.Fab")
			(hide yes)
			(effects
				(font
					(size 1 1)
					(thickness 0.15)
				)
				(justify mirror)
			)
		)
		(property "License" "Apache-2.0"
			(at 0 0 180)
			(unlocked yes)
			(layer "B.Fab")
			(hide yes)
			(effects
				(font
					(size 1 1)
					(thickness 0.15)
				)
				(justify mirror)
			)
		)
		(property "Author" "Antmicro"
			(at 0 0 180)
			(unlocked yes)
			(layer "B.Fab")
			(hide yes)
			(effects
				(font
					(size 1 1)
					(thickness 0.15)
				)
				(justify mirror)
			)
		)
		(property "Voltage" "16V"
			(at 0 0 180)
			(unlocked yes)
			(layer "B.Fab")
			(hide yes)
			(effects
				(font
					(size 1 1)
					(thickness 0.15)
				)
				(justify mirror)
			)
		)
		(property "Dielectric" ""
			(at 0 0 180)
			(unlocked yes)
			(layer "B.Fab")
			(hide yes)
			(effects
				(font
					(size 1 1)
					(thickness 0.15)
				)
				(justify mirror)
			)
		)
		(sheetname "/USB Hub/")
		(sheetfile "usb_hub.kicad_sch")
		(attr smd)
		(fp_line
			(start -0.15 -0.55)
			(end 0.15 -0.55)
			(stroke
				(width 0.15)
				(type solid)
			)
			(layer "B.SilkS")
		)
		(fp_line
			(start -0.15 0.55)
			(end 0.15 0.55)
			(stroke
				(width 0.15)
				(type solid)
			)
			(layer "B.SilkS")
		)
		(fp_rect
			(start -1.25 0.65)
			(end 1.25 -0.65)
			(stroke
				(width 0.05)
				(type solid)
			)
			(fill no)
			(layer "B.CrtYd")
		)
		(fp_rect
			(start -0.8 0.45)
			(end 0.8 -0.45)
			(stroke
				(width 0.15)
				(type solid)
			)
			(fill no)
			(layer "B.Fab")
		)
		(fp_text user "${REFERENCE}"
			(at -1.682 -3.895 0)
			(layer "B.Fab")
			(effects
				(font
					(size 0.7 0.7)
					(thickness 0.15)
				)
				(justify right top mirror)
			)
		)
		(fp_text user "License: Apache-2.0"
			(at -1.682 -5.895 0)
			(layer "B.Fab")
			(effects
				(font
					(size 0.7 0.7)
					(thickness 0.15)
				)
				(justify right top mirror)
			)
		)
		(fp_text user "Author: Antmicro"
			(at -1.682 -4.894 0)
			(layer "B.Fab")
			(effects
				(font
					(size 0.7 0.7)
					(thickness 0.15)
				)
				(justify right top mirror)
			)
		)
		(pad "1" smd roundrect
			(at -0.7 0)
			(size 0.8 1.1)
			(layers "B.Cu" "B.Mask" "B.Paste")
			(roundrect_rratio 0.2)
			(net 1 "GND")
			(pintype "passive")
		)
		(pad "2" smd roundrect
			(at 0.7 0)
			(size 0.8 1.1)
			(layers "B.Cu" "B.Mask" "B.Paste")
			(roundrect_rratio 0.2)
			(net 2 "+3V3")
			(pintype "passive")
		)
	)
	(footprint "antmicro-footprints:R_0402_1005Metric"
		(layer "B.Cu")
		(at 233.7 79.6)
		(descr "Resistor SMD 0402")
		(tags "resistor SMD 0402")
		(property "Reference" "R150"
			(at -1.9 -1.3 0)
			(layer "B.SilkS")
			(effects
				(font
					(size 0.7 0.7)
					(thickness 0.15)
				)
				(justify right top mirror)
			)
		)
		(property "Value" "R_10k_0402"
			(at -1.011843 -1.772046 0)
			(layer "B.Fab")
			(effects
				(font
					(size 0.7 0.7)
					(thickness 0.15)
				)
				(justify right top mirror)
			)
		)
		(property "Datasheet" "https://www.bourns.com/docs/product-datasheets/cr.pdf"
			(at 0 0 0)
			(layer "B.Fab")
			(hide yes)
			(effects
				(font
					(size 1.27 1.27)
					(thickness 0.15)
				)
				(justify mirror)
			)
		)
		(property "Description" "SMD Chip Resistor, 10 kohm, ± 1%, 62.5 mW, 0402 [1005 Metric], Thick Film, General Purpose"
			(at 0 0 0)
			(layer "B.Fab")
			(hide yes)
			(effects
				(font
					(size 1.27 1.27)
					(thickness 0.15)
				)
				(justify mirror)
			)
		)
		(property "Manufacturer" "Bourns"
			(at 0 0 180)
			(unlocked yes)
			(layer "B.Fab")
			(hide yes)
			(effects
				(font
					(size 1 1)
					(thickness 0.15)
				)
				(justify mirror)
			)
		)
		(property "MPN" "CR0402-FX-1002GLF"
			(at 0 0 180)
			(unlocked yes)
			(layer "B.Fab")
			(hide yes)
			(effects
				(font
					(size 1 1)
					(thickness 0.15)
				)
				(justify mirror)
			)
		)
		(property "Val" "10k"
			(at 0 0 180)
			(unlocked yes)
			(layer "B.Fab")
			(hide yes)
			(effects
				(font
					(size 1 1)
					(thickness 0.15)
				)
				(justify mirror)
			)
		)
		(property "License" "Apache-2.0"
			(at 0 0 180)
			(unlocked yes)
			(layer "B.Fab")
			(hide yes)
			(effects
				(font
					(size 1 1)
					(thickness 0.15)
				)
				(justify mirror)
			)
		)
		(property "Author" "Antmicro"
			(at 0 0 180)
			(unlocked yes)
			(layer "B.Fab")
			(hide yes)
			(effects
				(font
					(size 1 1)
					(thickness 0.15)
				)
				(justify mirror)
			)
		)
		(property "Tolerance" "1%"
			(at 0 0 180)
			(unlocked yes)
			(layer "B.Fab")
			(hide yes)
			(effects
				(font
					(size 1 1)
					(thickness 0.15)
				)
				(justify mirror)
			)
		)
		(sheetname "/USB Debug, PD/")
		(sheetfile "usb_debug_pd.kicad_sch")
		(attr smd)
		(fp_poly
			(pts
				(xy -0.925 0.47) (xy -0.925 -0.47) (xy 0.925 -0.47) (xy 0.925 0.47)
			)
			(stroke
				(width 0.05)
				(type default)
			)
			(fill no)
			(layer "B.CrtYd")
		)
		(fp_poly
			(pts
				(xy -0.5 0.25) (xy -0.5 -0.25) (xy 0.5 -0.25) (xy 0.5 0.25)
			)
			(stroke
				(width 0.15)
				(type solid)
			)
			(fill no)
			(layer "B.Fab")
		)
		(fp_text user "Author: Antmicro"
			(at -0.95 -4.169 0)
			(layer "B.Fab")
			(effects
				(font
					(size 0.7 0.7)
					(thickness 0.15)
				)
				(justify right top mirror)
			)
		)
		(fp_text user "${REFERENCE}"
			(at -0.95 -3.168 0)
			(layer "B.Fab")
			(effects
				(font
					(size 0.7 0.7)
					(thickness 0.15)
				)
				(justify right top mirror)
			)
		)
		(fp_text user "License: Apache-2.0"
			(at -0.949999 -5.169 0)
			(layer "B.Fab")
			(effects
				(font
					(size 0.7 0.7)
					(thickness 0.15)
				)
				(justify right top mirror)
			)
		)
		(pad "1" smd roundrect
			(at -0.48 0)
			(size 0.59 0.64)
			(layers "B.Cu" "B.Mask" "B.Paste")
			(roundrect_rratio 0.25)
			(net 976 "/USB Debug, PD/USBC0_FLG")
			(pintype "passive")
		)
		(pad "2" smd roundrect
			(at 0.48 0)
			(size 0.59 0.64)
			(layers "B.Cu" "B.Mask" "B.Paste")
			(roundrect_rratio 0.25)
			(net 5 "+5V")
			(pintype "passive")
		)
	)
	(footprint "antmicro-footprints:C_0402_1005Metric"
		(layer "B.Cu")
		(at 199.41 68.02 180)
		(descr "Capacitor SMD 0402")
		(tags "capacitor SMD 0402")
		(property "Reference" "C163"
			(at -1.35 -1.43 0)
			(layer "B.SilkS")
			(effects
				(font
					(size 0.7 0.7)
					(thickness 0.15)
				)
				(justify left bottom mirror)
			)
		)
		(property "Value" "C_100n_0402"
			(at -1.022927 -2.155213 0)
			(layer "B.Fab")
			(effects
				(font
					(size 0.7 0.7)
					(thickness 0.15)
				)
				(justify left bottom mirror)
			)
		)
		(property "Datasheet" "https://www.murata.com/products/productdetail?partno=GRM155R61H104KE14%23"
			(at 0 0 0)
			(layer "B.Fab")
			(hide yes)
			(effects
				(font
					(size 1.27 1.27)
					(thickness 0.15)
				)
				(justify mirror)
			)
		)
		(property "Description" "SMD Multilayer Ceramic Capacitor, 0.1 µF, 50 V, 0402 [1005 Metric], ± 10%, X5R, GRM Series"
			(at 0 0 0)
			(layer "B.Fab")
			(hide yes)
			(effects
				(font
					(size 1.27 1.27)
					(thickness 0.15)
				)
				(justify mirror)
			)
		)
		(property "Manufacturer" "Murata"
			(at 0 0 0)
			(unlocked yes)
			(layer "B.Fab")
			(hide yes)
			(effects
				(font
					(size 1 1)
					(thickness 0.15)
				)
				(justify mirror)
			)
		)
		(property "MPN" "GRM155R61H104KE14D"
			(at 0 0 0)
			(unlocked yes)
			(layer "B.Fab")
			(hide yes)
			(effects
				(font
					(size 1 1)
					(thickness 0.15)
				)
				(justify mirror)
			)
		)
		(property "Val" "100n"
			(at 0 0 0)
			(unlocked yes)
			(layer "B.Fab")
			(hide yes)
			(effects
				(font
					(size 1 1)
					(thickness 0.15)
				)
				(justify mirror)
			)
		)
		(property "License" "Apache-2.0"
			(at 0 0 0)
			(unlocked yes)
			(layer "B.Fab")
			(hide yes)
			(effects
				(font
					(size 1 1)
					(thickness 0.15)
				)
				(justify mirror)
			)
		)
		(property "Author" "Antmicro"
			(at 0 0 0)
			(unlocked yes)
			(layer "B.Fab")
			(hide yes)
			(effects
				(font
					(size 1 1)
					(thickness 0.15)
				)
				(justify mirror)
			)
		)
		(property "Voltage" "50V"
			(at 0 0 0)
			(unlocked yes)
			(layer "B.Fab")
			(hide yes)
			(effects
				(font
					(size 1 1)
					(thickness 0.15)
				)
				(justify mirror)
			)
		)
		(property "Dielectric" "X5R"
			(at 0 0 0)
			(unlocked yes)
			(layer "B.Fab")
			(hide yes)
			(effects
				(font
					(size 1 1)
					(thickness 0.15)
				)
				(justify mirror)
			)
		)
		(sheetname "/CSI/")
		(sheetfile "csi.kicad_sch")
		(attr smd)
		(fp_poly
			(pts
				(xy -0.925 0.47) (xy -0.925 -0.47) (xy 0.925 -0.47) (xy 0.925 0.47)
			)
			(stroke
				(width 0.05)
				(type default)
			)
			(fill no)
			(layer "B.CrtYd")
		)
		(fp_line
			(start 0.504 0.25)
			(end 0.504 -0.248)
			(stroke
				(width 0.15)
				(type solid)
			)
			(layer "B.Fab")
		)
		(fp_line
			(start 0.504 -0.248)
			(end -0.494 -0.248)
			(stroke
				(width 0.15)
				(type solid)
			)
			(layer "B.Fab")
		)
		(fp_line
			(start -0.494 0.25)
			(end 0.504 0.25)
			(stroke
				(width 0.15)
				(type solid)
			)
			(layer "B.Fab")
		)
		(fp_line
			(start -0.494 -0.248)
			(end -0.494 0.25)
			(stroke
				(width 0.15)
				(type solid)
			)
			(layer "B.Fab")
		)
		(fp_text user "${REFERENCE}"
			(at -0.939 -4.599 0)
			(layer "B.Fab")
			(effects
				(font
					(size 0.7 0.7)
					(thickness 0.15)
				)
				(justify left bottom mirror)
			)
		)
		(fp_text user "License: Apache-2.0"
			(at -0.939 -5.799 0)
			(layer "B.Fab")
			(effects
				(font
					(size 0.7 0.7)
					(thickness 0.15)
				)
				(justify left bottom mirror)
			)
		)
		(fp_text user "Author: Antmicro"
			(at -0.939 -3.399 0)
			(layer "B.Fab")
			(effects
				(font
					(size 0.7 0.7)
					(thickness 0.15)
				)
				(justify left bottom mirror)
			)
		)
		(pad "1" smd roundrect
			(at -0.48 0 180)
			(size 0.59 0.64)
			(layers "B.Cu" "B.Mask" "B.Paste")
			(roundrect_rratio 0.25)
			(net 1 "GND")
			(pintype "passive")
		)
		(pad "2" smd roundrect
			(at 0.48 0 180)
			(size 0.59 0.64)
			(layers "B.Cu" "B.Mask" "B.Paste")
			(roundrect_rratio 0.25)
			(net 11 "+1V8")
			(pintype "passive")
		)
	)
	(footprint "antmicro-footprints:R_0402_1005Metric"
		(layer "B.Cu")
		(at 235.7 106.814)
		(descr "Resistor SMD 0402")
		(tags "resistor SMD 0402")
		(property "Reference" "R268"
			(at -2.9 3.786 0)
			(layer "B.SilkS")
			(effects
				(font
					(size 0.7 0.7)
					(thickness 0.15)
				)
				(justify right top mirror)
			)
		)
		(property "Value" "R_0R_0402"
			(at -1.011843 -1.772046 0)
			(layer "B.Fab")
			(effects
				(font
					(size 0.7 0.7)
					(thickness 0.15)
				)
				(justify right top mirror)
			)
		)
		(property "Datasheet" "https://industrial.panasonic.com/cdbs/www-data/pdf/RDA0000/AOA0000C301.pdf"
			(at 0 0 0)
			(layer "B.Fab")
			(hide yes)
			(effects
				(font
					(size 1.27 1.27)
					(thickness 0.15)
				)
				(justify mirror)
			)
		)
		(property "Description" "SMD Chip Resistor, Jumper, 0 ohm, 100 mW, 0402 [1005 Metric], Thick Film, General Purpose"
			(at 0 0 0)
			(layer "B.Fab")
			(hide yes)
			(effects
				(font
					(size 1.27 1.27)
					(thickness 0.15)
				)
				(justify mirror)
			)
		)
		(property "Manufacturer" "Panasonic"
			(at 0 0 180)
			(unlocked yes)
			(layer "B.Fab")
			(hide yes)
			(effects
				(font
					(size 1 1)
					(thickness 0.15)
				)
				(justify mirror)
			)
		)
		(property "MPN" "ERJ2GE0R00X"
			(at 0 0 180)
			(unlocked yes)
			(layer "B.Fab")
			(hide yes)
			(effects
				(font
					(size 1 1)
					(thickness 0.15)
				)
				(justify mirror)
			)
		)
		(property "Val" "0R"
			(at 0 0 180)
			(unlocked yes)
			(layer "B.Fab")
			(hide yes)
			(effects
				(font
					(size 1 1)
					(thickness 0.15)
				)
				(justify mirror)
			)
		)
		(property "License" "Apache-2.0"
			(at 0 0 180)
			(unlocked yes)
			(layer "B.Fab")
			(hide yes)
			(effects
				(font
					(size 1 1)
					(thickness 0.15)
				)
				(justify mirror)
			)
		)
		(property "Author" "Antmicro"
			(at 0 0 180)
			(unlocked yes)
			(layer "B.Fab")
			(hide yes)
			(effects
				(font
					(size 1 1)
					(thickness 0.15)
				)
				(justify mirror)
			)
		)
		(property "Tolerance" "~"
			(at 0 0 180)
			(unlocked yes)
			(layer "B.Fab")
			(hide yes)
			(effects
				(font
					(size 1 1)
					(thickness 0.15)
				)
				(justify mirror)
			)
		)
		(property "Current" "1A"
			(at 0 0 0)
			(unlocked yes)
			(layer "B.Fab")
			(hide yes)
			(effects
				(font
					(size 1 1)
					(thickness 0.15)
				)
				(justify mirror)
			)
		)
		(sheetname "/Recovery USB/")
		(sheetfile "recovery_usb.kicad_sch")
		(attr smd)
		(fp_poly
			(pts
				(xy -0.925 0.47) (xy -0.925 -0.47) (xy 0.925 -0.47) (xy 0.925 0.47)
			)
			(stroke
				(width 0.05)
				(type default)
			)
			(fill no)
			(layer "B.CrtYd")
		)
		(fp_poly
			(pts
				(xy -0.5 0.25) (xy -0.5 -0.25) (xy 0.5 -0.25) (xy 0.5 0.25)
			)
			(stroke
				(width 0.15)
				(type solid)
			)
			(fill no)
			(layer "B.Fab")
		)
		(fp_text user "${REFERENCE}"
			(at -0.95 -3.168 0)
			(layer "B.Fab")
			(effects
				(font
					(size 0.7 0.7)
					(thickness 0.15)
				)
				(justify right top mirror)
			)
		)
		(fp_text user "Author: Antmicro"
			(at -0.95 -4.169 0)
			(layer "B.Fab")
			(effects
				(font
					(size 0.7 0.7)
					(thickness 0.15)
				)
				(justify right top mirror)
			)
		)
		(fp_text user "License: Apache-2.0"
			(at -0.949999 -5.169 0)
			(layer "B.Fab")
			(effects
				(font
					(size 0.7 0.7)
					(thickness 0.15)
				)
				(justify right top mirror)
			)
		)
		(pad "1" smd roundrect
			(at -0.48 0)
			(size 0.59 0.64)
			(layers "B.Cu" "B.Mask" "B.Paste")
			(roundrect_rratio 0.25)
			(net 890 "Net-(Q19-D)")
			(pintype "passive")
		)
		(pad "2" smd roundrect
			(at 0.48 0)
			(size 0.59 0.64)
			(layers "B.Cu" "B.Mask" "B.Paste")
			(roundrect_rratio 0.25)
			(net 1243 "Net-(U23-FLG)")
			(pintype "passive")
		)
	)
	(footprint "antmicro-footprints:ASP-208571-01_mounting_holes"
		(locked yes)
		(layer "B.Cu")
		(at 77.680532 103.71 90)
		(property "Reference" "J18"
			(at -25.89 11.119468 270)
			(layer "B.SilkS")
			(effects
				(font
					(size 0.7 0.7)
					(thickness 0.15)
				)
				(justify left bottom mirror)
			)
		)
		(property "Value" "ASP-208571-01_mounting_holes"
			(at -15.05 -10.885 270)
			(layer "B.Fab")
			(effects
				(font
					(size 0.7 0.7)
					(thickness 0.15)
				)
				(justify left bottom mirror)
			)
		)
		(property "Datasheet" "https://suddendocs.samtec.com/prints/asp-208571-01-mkt.pdf"
			(at 0 0 270)
			(layer "B.Fab")
			(hide yes)
			(effects
				(font
					(size 1.27 1.27)
					(thickness 0.15)
				)
				(justify mirror)
			)
		)
		(property "Description" "FMC connector"
			(at 0 0 270)
			(layer "B.Fab")
			(hide yes)
			(effects
				(font
					(size 1.27 1.27)
					(thickness 0.15)
				)
				(justify mirror)
			)
		)
		(property "MPN" "ASP-208571-01"
			(at 0 0 90)
			(unlocked yes)
			(layer "B.Fab")
			(hide yes)
			(effects
				(font
					(size 1 1)
					(thickness 0.15)
				)
				(justify mirror)
			)
		)
		(property "Manufacturer" "Samtec"
			(at 0 0 90)
			(unlocked yes)
			(layer "B.Fab")
			(hide yes)
			(effects
				(font
					(size 1 1)
					(thickness 0.15)
				)
				(justify mirror)
			)
		)
		(property "Author" "Antmicro"
			(at 0 0 90)
			(unlocked yes)
			(layer "B.Fab")
			(hide yes)
			(effects
				(font
					(size 1 1)
					(thickness 0.15)
				)
				(justify mirror)
			)
		)
		(property "License" "Apache-2.0"
			(at 0 0 90)
			(unlocked yes)
			(layer "B.Fab")
			(hide yes)
			(effects
				(font
					(size 1 1)
					(thickness 0.15)
				)
				(justify mirror)
			)
		)
		(sheetname "/Expansion connector/")
		(sheetfile "expansion_connector.kicad_sch")
		(attr smd)
		(fp_line
			(start 27.889 -9.88)
			(end -27.889 -9.88)
			(stroke
				(width 0.15)
				(type solid)
			)
			(layer "B.SilkS")
		)
		(fp_line
			(start -27.889 -9.88)
			(end -27.889 -4.005)
			(stroke
				(width 0.15)
				(type solid)
			)
			(layer "B.SilkS")
		)
		(fp_line
			(start -27.889 -2.095)
			(end -27.889 9.88)
			(stroke
				(width 0.15)
				(type solid)
			)
			(layer "B.SilkS")
		)
		(fp_line
			(start 28.779 -0.76)
			(end 27.889 -0.76)
			(stroke
				(width 0.15)
				(type solid)
			)
			(layer "B.SilkS")
		)
		(fp_line
			(start 27.889 -0.76)
			(end 27.889 -9.88)
			(stroke
				(width 0.15)
				(type solid)
			)
			(layer "B.SilkS")
		)
		(fp_line
			(start 28.779 0.76)
			(end 28.779 -0.76)
			(stroke
				(width 0.15)
				(type solid)
			)
			(layer "B.SilkS")
		)
		(fp_line
			(start 27.889 0.76)
			(end 28.779 0.76)
			(stroke
				(width 0.15)
				(type solid)
			)
			(layer "B.SilkS")
		)
		(fp_line
			(start 27.889 9.88)
			(end 27.889 0.76)
			(stroke
				(width 0.15)
				(type solid)
			)
			(layer "B.SilkS")
		)
		(fp_line
			(start -27.889 9.88)
			(end 27.889 9.88)
			(stroke
				(width 0.15)
				(type solid)
			)
			(layer "B.SilkS")
		)
		(fp_circle
			(center 28.5 8.255)
			(end 28.6 8.255)
			(stroke
				(width 0.15)
				(type solid)
			)
			(fill no)
			(layer "B.SilkS")
		)
		(fp_circle
			(center 24.765 -8.255)
			(end 24.987 -8.255)
			(stroke
				(width 0.4445)
				(type solid)
			)
			(fill no)
			(layer "B.Paste")
		)
		(fp_circle
			(center 23.495 -8.255)
			(end 23.717 -8.255)
			(stroke
				(width 0.4445)
				(type solid)
			)
			(fill no)
			(layer "B.Paste")
		)
		(fp_circle
			(center 22.225 -8.255)
			(end 22.447 -8.255)
			(stroke
				(width 0.4445)
				(type solid)
			)
			(fill no)
			(layer "B.Paste")
		)
		(fp_circle
			(center 20.955 -8.255)
			(end 21.177 -8.255)
			(stroke
				(width 0.4445)
				(type solid)
			)
			(fill no)
			(layer "B.Paste")
		)
		(fp_circle
			(center 19.685 -8.255)
			(end 19.907 -8.255)
			(stroke
				(width 0.4445)
				(type solid)
			)
			(fill no)
			(layer "B.Paste")
		)
		(fp_circle
			(center 18.415 -8.255)
			(end 18.637 -8.255)
			(stroke
				(width 0.4445)
				(type solid)
			)
			(fill no)
			(layer "B.Paste")
		)
		(fp_circle
			(center 17.145 -8.255)
			(end 17.367 -8.255)
			(stroke
				(width 0.4445)
				(type solid)
			)
			(fill no)
			(layer "B.Paste")
		)
		(fp_circle
			(center 15.875 -8.255)
			(end 16.097 -8.255)
			(stroke
				(width 0.4445)
				(type solid)
			)
			(fill no)
			(layer "B.Paste")
		)
		(fp_circle
			(center 14.605 -8.255)
			(end 14.827 -8.255)
			(stroke
				(width 0.4445)
				(type solid)
			)
			(fill no)
			(layer "B.Paste")
		)
		(fp_circle
			(center 13.335 -8.255)
			(end 13.557 -8.255)
			(stroke
				(width 0.4445)
				(type solid)
			)
			(fill no)
			(layer "B.Paste")
		)
		(fp_circle
			(center 12.065 -8.255)
			(end 12.287 -8.255)
			(stroke
				(width 0.4445)
				(type solid)
			)
			(fill no)
			(layer "B.Paste")
		)
		(fp_circle
			(center 10.795 -8.255)
			(end 11.017 -8.255)
			(stroke
				(width 0.4445)
				(type solid)
			)
			(fill no)
			(layer "B.Paste")
		)
		(fp_circle
			(center 9.525 -8.255)
			(end 9.747 -8.255)
			(stroke
				(width 0.4445)
				(type solid)
			)
			(fill no)
			(layer "B.Paste")
		)
		(fp_circle
			(center 8.255 -8.255)
			(end 8.477 -8.255)
			(stroke
				(width 0.4445)
				(type solid)
			)
			(fill no)
			(layer "B.Paste")
		)
		(fp_circle
			(center 6.985 -8.255)
			(end 7.207 -8.255)
			(stroke
				(width 0.4445)
				(type solid)
			)
			(fill no)
			(layer "B.Paste")
		)
		(fp_circle
			(center 5.715 -8.255)
			(end 5.937 -8.255)
			(stroke
				(width 0.4445)
				(type solid)
			)
			(fill no)
			(layer "B.Paste")
		)
		(fp_circle
			(center 4.445 -8.255)
			(end 4.667 -8.255)
			(stroke
				(width 0.4445)
				(type solid)
			)
			(fill no)
			(layer "B.Paste")
		)
		(fp_circle
			(center 3.175 -8.255)
			(end 3.397 -8.255)
			(stroke
				(width 0.4445)
				(type solid)
			)
			(fill no)
			(layer "B.Paste")
		)
		(fp_circle
			(center 1.905 -8.255)
			(end 2.127 -8.255)
			(stroke
				(width 0.4445)
				(type solid)
			)
			(fill no)
			(layer "B.Paste")
		)
		(fp_circle
			(center 0.635 -8.255)
			(end 0.857 -8.255)
			(stroke
				(width 0.4445)
				(type solid)
			)
			(fill no)
			(layer "B.Paste")
		)
		(fp_circle
			(center -0.635 -8.255)
			(end -0.413 -8.255)
			(stroke
				(width 0.4445)
				(type solid)
			)
			(fill no)
			(layer "B.Paste")
		)
		(fp_circle
			(center -1.905 -8.255)
			(end -1.683 -8.255)
			(stroke
				(width 0.4445)
				(type solid)
			)
			(fill no)
			(layer "B.Paste")
		)
		(fp_circle
			(center -3.175 -8.255)
			(end -2.953 -8.255)
			(stroke
				(width 0.4445)
				(type solid)
			)
			(fill no)
			(layer "B.Paste")
		)
		(fp_circle
			(center -4.445 -8.255)
			(end -4.223 -8.255)
			(stroke
				(width 0.4445)
				(type solid)
			)
			(fill no)
			(layer "B.Paste")
		)
		(fp_circle
			(center -5.715 -8.255)
			(end -5.493 -8.255)
			(stroke
				(width 0.4445)
				(type solid)
			)
			(fill no)
			(layer "B.Paste")
		)
		(fp_circle
			(center -6.985 -8.255)
			(end -6.763 -8.255)
			(stroke
				(width 0.4445)
				(type solid)
			)
			(fill no)
			(layer "B.Paste")
		)
		(fp_circle
			(center -8.255 -8.255)
			(end -8.033 -8.255)
			(stroke
				(width 0.4445)
				(type solid)
			)
			(fill no)
			(layer "B.Paste")
		)
		(fp_circle
			(center -9.525 -8.255)
			(end -9.303 -8.255)
			(stroke
				(width 0.4445)
				(type solid)
			)
			(fill no)
			(layer "B.Paste")
		)
		(fp_circle
			(center -10.795 -8.255)
			(end -10.573 -8.255)
			(stroke
				(width 0.4445)
				(type solid)
			)
			(fill no)
			(layer "B.Paste")
		)
		(fp_circle
			(center -12.065 -8.255)
			(end -11.843 -8.255)
			(stroke
				(width 0.4445)
				(type solid)
			)
			(fill no)
			(layer "B.Paste")
		)
		(fp_circle
			(center -13.335 -8.255)
			(end -13.113 -8.255)
			(stroke
				(width 0.4445)
				(type solid)
			)
			(fill no)
			(layer "B.Paste")
		)
		(fp_circle
			(center -14.605 -8.255)
			(end -14.383 -8.255)
			(stroke
				(width 0.4445)
				(type solid)
			)
			(fill no)
			(layer "B.Paste")
		)
		(fp_circle
			(center -15.875 -8.255)
			(end -15.653 -8.255)
			(stroke
				(width 0.4445)
				(type solid)
			)
			(fill no)
			(layer "B.Paste")
		)
		(fp_circle
			(center -17.145 -8.255)
			(end -16.923 -8.255)
			(stroke
				(width 0.4445)
				(type solid)
			)
			(fill no)
			(layer "B.Paste")
		)
		(fp_circle
			(center -18.415 -8.255)
			(end -18.193 -8.255)
			(stroke
				(width 0.4445)
				(type solid)
			)
			(fill no)
			(layer "B.Paste")
		)
		(fp_circle
			(center -19.685 -8.255)
			(end -19.463 -8.255)
			(stroke
				(width 0.4445)
				(type solid)
			)
			(fill no)
			(layer "B.Paste")
		)
		(fp_circle
			(center -20.955 -8.255)
			(end -20.733 -8.255)
			(stroke
				(width 0.4445)
				(type solid)
			)
			(fill no)
			(layer "B.Paste")
		)
		(fp_circle
			(center -22.225 -8.255)
			(end -22.003 -8.255)
			(stroke
				(width 0.4445)
				(type solid)
			)
			(fill no)
			(layer "B.Paste")
		)
		(fp_circle
			(center -23.495 -8.255)
			(end -23.273 -8.255)
			(stroke
				(width 0.4445)
				(type solid)
			)
			(fill no)
			(layer "B.Paste")
		)
		(fp_circle
			(center -24.765 -8.255)
			(end -24.543 -8.255)
			(stroke
				(width 0.4445)
				(type solid)
			)
			(fill no)
			(layer "B.Paste")
		)
		(fp_circle
			(center 24.765 -6.985)
			(end 24.987 -6.985)
			(stroke
				(width 0.4445)
				(type solid)
			)
			(fill no)
			(layer "B.Paste")
		)
		(fp_circle
			(center 23.495 -6.985)
			(end 23.717 -6.985)
			(stroke
				(width 0.4445)
				(type solid)
			)
			(fill no)
			(layer "B.Paste")
		)
		(fp_circle
			(center 22.225 -6.985)
			(end 22.447 -6.985)
			(stroke
				(width 0.4445)
				(type solid)
			)
			(fill no)
			(layer "B.Paste")
		)
		(fp_circle
			(center 20.955 -6.985)
			(end 21.177 -6.985)
			(stroke
				(width 0.4445)
				(type solid)
			)
			(fill no)
			(layer "B.Paste")
		)
		(fp_circle
			(center 19.685 -6.985)
			(end 19.907 -6.985)
			(stroke
				(width 0.4445)
				(type solid)
			)
			(fill no)
			(layer "B.Paste")
		)
		(fp_circle
			(center 18.415 -6.985)
			(end 18.637 -6.985)
			(stroke
				(width 0.4445)
				(type solid)
			)
			(fill no)
			(layer "B.Paste")
		)
		(fp_circle
			(center 17.145 -6.985)
			(end 17.367 -6.985)
			(stroke
				(width 0.4445)
				(type solid)
			)
			(fill no)
			(layer "B.Paste")
		)
		(fp_circle
			(center 15.875 -6.985)
			(end 16.097 -6.985)
			(stroke
				(width 0.4445)
				(type solid)
			)
			(fill no)
			(layer "B.Paste")
		)
		(fp_circle
			(center 14.605 -6.985)
			(end 14.827 -6.985)
			(stroke
				(width 0.4445)
				(type solid)
			)
			(fill no)
			(layer "B.Paste")
		)
		(fp_circle
			(center 13.335 -6.985)
			(end 13.557 -6.985)
			(stroke
				(width 0.4445)
				(type solid)
			)
			(fill no)
			(layer "B.Paste")
		)
		(fp_circle
			(center 12.065 -6.985)
			(end 12.287 -6.985)
			(stroke
				(width 0.4445)
				(type solid)
			)
			(fill no)
			(layer "B.Paste")
		)
		(fp_circle
			(center 10.795 -6.985)
			(end 11.017 -6.985)
			(stroke
				(width 0.4445)
				(type solid)
			)
			(fill no)
			(layer "B.Paste")
		)
		(fp_circle
			(center 9.525 -6.985)
			(end 9.747 -6.985)
			(stroke
				(width 0.4445)
				(type solid)
			)
			(fill no)
			(layer "B.Paste")
		)
		(fp_circle
			(center 8.255 -6.985)
			(end 8.477 -6.985)
			(stroke
				(width 0.4445)
				(type solid)
			)
			(fill no)
			(layer "B.Paste")
		)
		(fp_circle
			(center 6.985 -6.985)
			(end 7.207 -6.985)
			(stroke
				(width 0.4445)
				(type solid)
			)
			(fill no)
			(layer "B.Paste")
		)
		(fp_circle
			(center 5.715 -6.985)
			(end 5.937 -6.985)
			(stroke
				(width 0.4445)
				(type solid)
			)
			(fill no)
			(layer "B.Paste")
		)
		(fp_circle
			(center 4.445 -6.985)
			(end 4.667 -6.985)
			(stroke
				(width 0.4445)
				(type solid)
			)
			(fill no)
			(layer "B.Paste")
		)
		(fp_circle
			(center 3.175 -6.985)
			(end 3.397 -6.985)
			(stroke
				(width 0.4445)
				(type solid)
			)
			(fill no)
			(layer "B.Paste")
		)
		(fp_circle
			(center 1.905 -6.985)
			(end 2.127 -6.985)
			(stroke
				(width 0.4445)
				(type solid)
			)
			(fill no)
			(layer "B.Paste")
		)
		(fp_circle
			(center 0.635 -6.985)
			(end 0.857 -6.985)
			(stroke
				(width 0.4445)
				(type solid)
			)
			(fill no)
			(layer "B.Paste")
		)
		(fp_circle
			(center -0.635 -6.985)
			(end -0.413 -6.985)
			(stroke
				(width 0.4445)
				(type solid)
			)
			(fill no)
			(layer "B.Paste")
		)
		(fp_circle
			(center -1.905 -6.985)
			(end -1.683 -6.985)
			(stroke
				(width 0.4445)
				(type solid)
			)
			(fill no)
			(layer "B.Paste")
		)
		(fp_circle
			(center -3.175 -6.985)
			(end -2.953 -6.985)
			(stroke
				(width 0.4445)
				(type solid)
			)
			(fill no)
			(layer "B.Paste")
		)
		(fp_circle
			(center -4.445 -6.985)
			(end -4.223 -6.985)
			(stroke
				(width 0.4445)
				(type solid)
			)
			(fill no)
			(layer "B.Paste")
		)
		(fp_circle
			(center -5.715 -6.985)
			(end -5.493 -6.985)
			(stroke
				(width 0.4445)
				(type solid)
			)
			(fill no)
			(layer "B.Paste")
		)
		(fp_circle
			(center -6.985 -6.985)
			(end -6.763 -6.985)
			(stroke
				(width 0.4445)
				(type solid)
			)
			(fill no)
			(layer "B.Paste")
		)
		(fp_circle
			(center -8.255 -6.985)
			(end -8.033 -6.985)
			(stroke
				(width 0.4445)
				(type solid)
			)
			(fill no)
			(layer "B.Paste")
		)
		(fp_circle
			(center -9.525 -6.985)
			(end -9.303 -6.985)
			(stroke
				(width 0.4445)
				(type solid)
			)
			(fill no)
			(layer "B.Paste")
		)
		(fp_circle
			(center -10.795 -6.985)
			(end -10.573 -6.985)
			(stroke
				(width 0.4445)
				(type solid)
			)
			(fill no)
			(layer "B.Paste")
		)
		(fp_circle
			(center -12.065 -6.985)
			(end -11.843 -6.985)
			(stroke
				(width 0.4445)
				(type solid)
			)
			(fill no)
			(layer "B.Paste")
		)
		(fp_circle
			(center -13.335 -6.985)
			(end -13.113 -6.985)
			(stroke
				(width 0.4445)
				(type solid)
			)
			(fill no)
			(layer "B.Paste")
		)
		(fp_circle
			(center -14.605 -6.985)
			(end -14.383 -6.985)
			(stroke
				(width 0.4445)
				(type solid)
			)
			(fill no)
			(layer "B.Paste")
		)
		(fp_circle
			(center -15.875 -6.985)
			(end -15.653 -6.985)
			(stroke
				(width 0.4445)
				(type solid)
			)
			(fill no)
			(layer "B.Paste")
		)
		(fp_circle
			(center -17.145 -6.985)
			(end -16.923 -6.985)
			(stroke
				(width 0.4445)
				(type solid)
			)
			(fill no)
			(layer "B.Paste")
		)
		(fp_circle
			(center -18.415 -6.985)
			(end -18.193 -6.985)
			(stroke
				(width 0.4445)
				(type solid)
			)
			(fill no)
			(layer "B.Paste")
		)
		(fp_circle
			(center -19.685 -6.985)
			(end -19.463 -6.985)
			(stroke
				(width 0.4445)
				(type solid)
			)
			(fill no)
			(layer "B.Paste")
		)
		(fp_circle
			(center -20.955 -6.985)
			(end -20.733 -6.985)
			(stroke
				(width 0.4445)
				(type solid)
			)
			(fill no)
			(layer "B.Paste")
		)
		(fp_circle
			(center -22.225 -6.985)
			(end -22.003 -6.985)
			(stroke
				(width 0.4445)
				(type solid)
			)
			(fill no)
			(layer "B.Paste")
		)
		(fp_circle
			(center -23.495 -6.985)
			(end -23.273 -6.985)
			(stroke
				(width 0.4445)
				(type solid)
			)
			(fill no)
			(layer "B.Paste")
		)
		(fp_circle
			(center -24.765 -6.985)
			(end -24.543 -6.985)
			(stroke
				(width 0.4445)
				(type solid)
			)
			(fill no)
			(layer "B.Paste")
		)
		(fp_circle
			(center 24.765 -5.715)
			(end 24.987 -5.715)
			(stroke
				(width 0.4445)
				(type solid)
			)
			(fill no)
			(layer "B.Paste")
		)
		(fp_circle
			(center 23.495 -5.715)
			(end 23.717 -5.715)
			(stroke
				(width 0.4445)
				(type solid)
			)
			(fill no)
			(layer "B.Paste")
		)
		(fp_circle
			(center 22.225 -5.715)
			(end 22.447 -5.715)
			(stroke
				(width 0.4445)
				(type solid)
			)
			(fill no)
			(layer "B.Paste")
		)
		(fp_circle
			(center 20.955 -5.715)
			(end 21.177 -5.715)
			(stroke
				(width 0.4445)
				(type solid)
			)
			(fill no)
			(layer "B.Paste")
		)
		(fp_circle
			(center 19.685 -5.715)
			(end 19.907 -5.715)
			(stroke
				(width 0.4445)
				(type solid)
			)
			(fill no)
			(layer "B.Paste")
		)
		(fp_circle
			(center 18.415 -5.715)
			(end 18.637 -5.715)
			(stroke
				(width 0.4445)
				(type solid)
			)
			(fill no)
			(layer "B.Paste")
		)
		(fp_circle
			(center 17.145 -5.715)
			(end 17.367 -5.715)
			(stroke
				(width 0.4445)
				(type solid)
			)
			(fill no)
			(layer "B.Paste")
		)
		(fp_circle
			(center 15.875 -5.715)
			(end 16.097 -5.715)
			(stroke
				(width 0.4445)
				(type solid)
			)
			(fill no)
			(layer "B.Paste")
		)
		(fp_circle
			(center 14.605 -5.715)
			(end 14.827 -5.715)
			(stroke
				(width 0.4445)
				(type solid)
			)
			(fill no)
			(layer "B.Paste")
		)
		(fp_circle
			(center 13.335 -5.715)
			(end 13.557 -5.715)
			(stroke
				(width 0.4445)
				(type solid)
			)
			(fill no)
			(layer "B.Paste")
		)
		(fp_circle
			(center 12.065 -5.715)
			(end 12.287 -5.715)
			(stroke
				(width 0.4445)
				(type solid)
			)
			(fill no)
			(layer "B.Paste")
		)
		(fp_circle
			(center 10.795 -5.715)
			(end 11.017 -5.715)
			(stroke
				(width 0.4445)
				(type solid)
			)
			(fill no)
			(layer "B.Paste")
		)
		(fp_circle
			(center 9.525 -5.715)
			(end 9.747 -5.715)
			(stroke
				(width 0.4445)
				(type solid)
			)
			(fill no)
			(layer "B.Paste")
		)
		(fp_circle
			(center 8.255 -5.715)
			(end 8.477 -5.715)
			(stroke
				(width 0.4445)
				(type solid)
			)
			(fill no)
			(layer "B.Paste")
		)
		(fp_circle
			(center 6.985 -5.715)
			(end 7.207 -5.715)
			(stroke
				(width 0.4445)
				(type solid)
			)
			(fill no)
			(layer "B.Paste")
		)
		(fp_circle
			(center 5.715 -5.715)
			(end 5.937 -5.715)
			(stroke
				(width 0.4445)
				(type solid)
			)
			(fill no)
			(layer "B.Paste")
		)
		(fp_circle
			(center 4.445 -5.715)
			(end 4.667 -5.715)
			(stroke
				(width 0.4445)
				(type solid)
			)
			(fill no)
			(layer "B.Paste")
		)
		(fp_circle
			(center 3.175 -5.715)
			(end 3.397 -5.715)
			(stroke
				(width 0.4445)
				(type solid)
			)
			(fill no)
			(layer "B.Paste")
		)
		(fp_circle
			(center 1.905 -5.715)
			(end 2.127 -5.715)
			(stroke
				(width 0.4445)
				(type solid)
			)
			(fill no)
			(layer "B.Paste")
		)
		(fp_circle
			(center 0.635 -5.715)
			(end 0.857 -5.715)
			(stroke
				(width 0.4445)
				(type solid)
			)
			(fill no)
			(layer "B.Paste")
		)
		(fp_circle
			(center -0.635 -5.715)
			(end -0.413 -5.715)
			(stroke
				(width 0.4445)
				(type solid)
			)
			(fill no)
			(layer "B.Paste")
		)
		(fp_circle
			(center -1.905 -5.715)
			(end -1.683 -5.715)
			(stroke
				(width 0.4445)
				(type solid)
			)
			(fill no)
			(layer "B.Paste")
		)
		(fp_circle
			(center -3.175 -5.715)
			(end -2.953 -5.715)
			(stroke
				(width 0.4445)
				(type solid)
			)
			(fill no)
			(layer "B.Paste")
		)
		(fp_circle
			(center -4.445 -5.715)
			(end -4.223 -5.715)
			(stroke
				(width 0.4445)
				(type solid)
			)
			(fill no)
			(layer "B.Paste")
		)
		(fp_circle
			(center -5.715 -5.715)
			(end -5.493 -5.715)
			(stroke
				(width 0.4445)
				(type solid)
			)
			(fill no)
			(layer "B.Paste")
		)
		(fp_circle
			(center -6.985 -5.715)
			(end -6.763 -5.715)
			(stroke
				(width 0.4445)
				(type solid)
			)
			(fill no)
			(layer "B.Paste")
		)
		(fp_circle
			(center -8.255 -5.715)
			(end -8.033 -5.715)
			(stroke
				(width 0.4445)
				(type solid)
			)
			(fill no)
			(layer "B.Paste")
		)
		(fp_circle
			(center -9.525 -5.715)
			(end -9.303 -5.715)
			(stroke
				(width 0.4445)
				(type solid)
			)
			(fill no)
			(layer "B.Paste")
		)
		(fp_circle
			(center -10.795 -5.715)
			(end -10.573 -5.715)
			(stroke
				(width 0.4445)
				(type solid)
			)
			(fill no)
			(layer "B.Paste")
		)
		(fp_circle
			(center -12.065 -5.715)
			(end -11.843 -5.715)
			(stroke
				(width 0.4445)
				(type solid)
			)
			(fill no)
			(layer "B.Paste")
		)
		(fp_circle
			(center -13.335 -5.715)
			(end -13.113 -5.715)
			(stroke
				(width 0.4445)
				(type solid)
			)
			(fill no)
			(layer "B.Paste")
		)
		(fp_circle
			(center -14.605 -5.715)
			(end -14.383 -5.715)
			(stroke
				(width 0.4445)
				(type solid)
			)
			(fill no)
			(layer "B.Paste")
		)
		(fp_circle
			(center -15.875 -5.715)
			(end -15.653 -5.715)
			(stroke
				(width 0.4445)
				(type solid)
			)
			(fill no)
			(layer "B.Paste")
		)
		(fp_circle
			(center -17.145 -5.715)
			(end -16.923 -5.715)
			(stroke
				(width 0.4445)
				(type solid)
			)
			(fill no)
			(layer "B.Paste")
		)
		(fp_circle
			(center -18.415 -5.715)
			(end -18.193 -5.715)
			(stroke
				(width 0.4445)
				(type solid)
			)
			(fill no)
			(layer "B.Paste")
		)
		(fp_circle
			(center -19.685 -5.715)
			(end -19.463 -5.715)
			(stroke
				(width 0.4445)
				(type solid)
			)
			(fill no)
			(layer "B.Paste")
		)
		(fp_circle
			(center -20.955 -5.715)
			(end -20.733 -5.715)
			(stroke
				(width 0.4445)
				(type solid)
			)
			(fill no)
			(layer "B.Paste")
		)
		(fp_circle
			(center -22.225 -5.715)
			(end -22.003 -5.715)
			(stroke
				(width 0.4445)
				(type solid)
			)
			(fill no)
			(layer "B.Paste")
		)
		(fp_circle
			(center -23.495 -5.715)
			(end -23.273 -5.715)
			(stroke
				(width 0.4445)
				(type solid)
			)
			(fill no)
			(layer "B.Paste")
		)
		(fp_circle
			(center -24.765 -5.715)
			(end -24.543 -5.715)
			(stroke
				(width 0.4445)
				(type solid)
			)
			(fill no)
			(layer "B.Paste")
		)
		(fp_circle
			(center 24.765 -4.445)
			(end 24.987 -4.445)
			(stroke
				(width 0.4445)
				(type solid)
			)
			(fill no)
			(layer "B.Paste")
		)
		(fp_circle
			(center 23.495 -4.445)
			(end 23.717 -4.445)
			(stroke
				(width 0.4445)
				(type solid)
			)
			(fill no)
			(layer "B.Paste")
		)
		(fp_circle
			(center 22.225 -4.445)
			(end 22.447 -4.445)
			(stroke
				(width 0.4445)
				(type solid)
			)
			(fill no)
			(layer "B.Paste")
		)
		(fp_circle
			(center 20.955 -4.445)
			(end 21.177 -4.445)
			(stroke
				(width 0.4445)
				(type solid)
			)
			(fill no)
			(layer "B.Paste")
		)
		(fp_circle
			(center 19.685 -4.445)
			(end 19.907 -4.445)
			(stroke
				(width 0.4445)
				(type solid)
			)
			(fill no)
			(layer "B.Paste")
		)
		(fp_circle
			(center 18.415 -4.445)
			(end 18.637 -4.445)
			(stroke
				(width 0.4445)
				(type solid)
			)
			(fill no)
			(layer "B.Paste")
		)
		(fp_circle
			(center 17.145 -4.445)
			(end 17.367 -4.445)
			(stroke
				(width 0.4445)
				(type solid)
			)
			(fill no)
			(layer "B.Paste")
		)
		(fp_circle
			(center 15.875 -4.445)
			(end 16.097 -4.445)
			(stroke
				(width 0.4445)
				(type solid)
			)
			(fill no)
			(layer "B.Paste")
		)
		(fp_circle
			(center 14.605 -4.445)
			(end 14.827 -4.445)
			(stroke
				(width 0.4445)
				(type solid)
			)
			(fill no)
			(layer "B.Paste")
		)
		(fp_circle
			(center 13.335 -4.445)
			(end 13.557 -4.445)
			(stroke
				(width 0.4445)
				(type solid)
			)
			(fill no)
			(layer "B.Paste")
		)
		(fp_circle
			(center 12.065 -4.445)
			(end 12.287 -4.445)
			(stroke
				(width 0.4445)
				(type solid)
			)
			(fill no)
			(layer "B.Paste")
		)
		(fp_circle
			(center 10.795 -4.445)
			(end 11.017 -4.445)
			(stroke
				(width 0.4445)
				(type solid)
			)
			(fill no)
			(layer "B.Paste")
		)
		(fp_circle
			(center 9.525 -4.445)
			(end 9.747 -4.445)
			(stroke
				(width 0.4445)
				(type solid)
			)
			(fill no)
			(layer "B.Paste")
		)
		(fp_circle
			(center 8.255 -4.445)
			(end 8.477 -4.445)
			(stroke
				(width 0.4445)
				(type solid)
			)
			(fill no)
			(layer "B.Paste")
		)
		(fp_circle
			(center 6.985 -4.445)
			(end 7.207 -4.445)
			(stroke
				(width 0.4445)
				(type solid)
			)
			(fill no)
			(layer "B.Paste")
		)
		(fp_circle
			(center 5.715 -4.445)
			(end 5.937 -4.445)
			(stroke
				(width 0.4445)
				(type solid)
			)
			(fill no)
			(layer "B.Paste")
		)
		(fp_circle
			(center 4.445 -4.445)
			(end 4.667 -4.445)
			(stroke
				(width 0.4445)
				(type solid)
			)
			(fill no)
			(layer "B.Paste")
		)
		(fp_circle
			(center 3.175 -4.445)
			(end 3.397 -4.445)
			(stroke
				(width 0.4445)
				(type solid)
			)
			(fill no)
			(layer "B.Paste")
		)
		(fp_circle
			(center 1.905 -4.445)
			(end 2.127 -4.445)
			(stroke
				(width 0.4445)
				(type solid)
			)
			(fill no)
			(layer "B.Paste")
		)
		(fp_circle
			(center 0.635 -4.445)
			(end 0.857 -4.445)
			(stroke
				(width 0.4445)
				(type solid)
			)
			(fill no)
			(layer "B.Paste")
		)
		(fp_circle
			(center -0.635 -4.445)
			(end -0.413 -4.445)
			(stroke
				(width 0.4445)
				(type solid)
			)
			(fill no)
			(layer "B.Paste")
		)
		(fp_circle
			(center -1.905 -4.445)
			(end -1.683 -4.445)
			(stroke
				(width 0.4445)
				(type solid)
			)
			(fill no)
			(layer "B.Paste")
		)
		(fp_circle
			(center -3.175 -4.445)
			(end -2.953 -4.445)
			(stroke
				(width 0.4445)
				(type solid)
			)
			(fill no)
			(layer "B.Paste")
		)
		(fp_circle
			(center -4.445 -4.445)
			(end -4.223 -4.445)
			(stroke
				(width 0.4445)
				(type solid)
			)
			(fill no)
			(layer "B.Paste")
		)
		(fp_circle
			(center -5.715 -4.445)
			(end -5.493 -4.445)
			(stroke
				(width 0.4445)
				(type solid)
			)
			(fill no)
			(layer "B.Paste")
		)
		(fp_circle
			(center -6.985 -4.445)
			(end -6.763 -4.445)
			(stroke
				(width 0.4445)
				(type solid)
			)
			(fill no)
			(layer "B.Paste")
		)
		(fp_circle
			(center -8.255 -4.445)
			(end -8.033 -4.445)
			(stroke
				(width 0.4445)
				(type solid)
			)
			(fill no)
			(layer "B.Paste")
		)
		(fp_circle
			(center -9.525 -4.445)
			(end -9.303 -4.445)
			(stroke
				(width 0.4445)
				(type solid)
			)
			(fill no)
			(layer "B.Paste")
		)
		(fp_circle
			(center -10.795 -4.445)
			(end -10.573 -4.445)
			(stroke
				(width 0.4445)
				(type solid)
			)
			(fill no)
			(layer "B.Paste")
		)
		(fp_circle
			(center -12.065 -4.445)
			(end -11.843 -4.445)
			(stroke
				(width 0.4445)
				(type solid)
			)
			(fill no)
			(layer "B.Paste")
		)
		(fp_circle
			(center -13.335 -4.445)
			(end -13.113 -4.445)
			(stroke
				(width 0.4445)
				(type solid)
			)
			(fill no)
			(layer "B.Paste")
		)
		(fp_circle
			(center -14.605 -4.445)
			(end -14.383 -4.445)
			(stroke
				(width 0.4445)
				(type solid)
			)
			(fill no)
			(layer "B.Paste")
		)
		(fp_circle
			(center -15.875 -4.445)
			(end -15.653 -4.445)
			(stroke
				(width 0.4445)
				(type solid)
			)
			(fill no)
			(layer "B.Paste")
		)
		(fp_circle
			(center -17.145 -4.445)
			(end -16.923 -4.445)
			(stroke
				(width 0.4445)
				(type solid)
			)
			(fill no)
			(layer "B.Paste")
		)
		(fp_circle
			(center -18.415 -4.445)
			(end -18.193 -4.445)
			(stroke
				(width 0.4445)
				(type solid)
			)
			(fill no)
			(layer "B.Paste")
		)
		(fp_circle
			(center -19.685 -4.445)
			(end -19.463 -4.445)
			(stroke
				(width 0.4445)
				(type solid)
			)
			(fill no)
			(layer "B.Paste")
		)
		(fp_circle
			(center -20.955 -4.445)
			(end -20.733 -4.445)
			(stroke
				(width 0.4445)
				(type solid)
			)
			(fill no)
			(layer "B.Paste")
		)
		(fp_circle
			(center -22.225 -4.445)
			(end -22.003 -4.445)
			(stroke
				(width 0.4445)
				(type solid)
			)
			(fill no)
			(layer "B.Paste")
		)
		(fp_circle
			(center -23.495 -4.445)
			(end -23.273 -4.445)
			(stroke
				(width 0.4445)
				(type solid)
			)
			(fill no)
			(layer "B.Paste")
		)
		(fp_circle
			(center -24.765 -4.445)
			(end -24.543 -4.445)
			(stroke
				(width 0.4445)
				(type solid)
			)
			(fill no)
			(layer "B.Paste")
		)
		(fp_circle
			(center 24.765 -3.175)
			(end 24.987 -3.175)
			(stroke
				(width 0.4445)
				(type solid)
			)
			(fill no)
			(layer "B.Paste")
		)
		(fp_circle
			(center 23.495 -3.175)
			(end 23.717 -3.175)
			(stroke
				(width 0.4445)
				(type solid)
			)
			(fill no)
			(layer "B.Paste")
		)
		(fp_circle
			(center 22.225 -3.175)
			(end 22.447 -3.175)
			(stroke
				(width 0.4445)
				(type solid)
			)
			(fill no)
			(layer "B.Paste")
		)
		(fp_circle
			(center 20.955 -3.175)
			(end 21.177 -3.175)
			(stroke
				(width 0.4445)
				(type solid)
			)
			(fill no)
			(layer "B.Paste")
		)
		(fp_circle
			(center 19.685 -3.175)
			(end 19.907 -3.175)
			(stroke
				(width 0.4445)
				(type solid)
			)
			(fill no)
			(layer "B.Paste")
		)
		(fp_circle
			(center 18.415 -3.175)
			(end 18.637 -3.175)
			(stroke
				(width 0.4445)
				(type solid)
			)
			(fill no)
			(layer "B.Paste")
		)
		(fp_circle
			(center 17.145 -3.175)
			(end 17.367 -3.175)
			(stroke
				(width 0.4445)
				(type solid)
			)
			(fill no)
			(layer "B.Paste")
		)
		(fp_circle
			(center 15.875 -3.175)
			(end 16.097 -3.175)
			(stroke
				(width 0.4445)
				(type solid)
			)
			(fill no)
			(layer "B.Paste")
		)
		(fp_circle
			(center 14.605 -3.175)
			(end 14.827 -3.175)
			(stroke
				(width 0.4445)
				(type solid)
			)
			(fill no)
			(layer "B.Paste")
		)
		(fp_circle
			(center 13.335 -3.175)
			(end 13.557 -3.175)
			(stroke
				(width 0.4445)
				(type solid)
			)
			(fill no)
			(layer "B.Paste")
		)
		(fp_circle
			(center 12.065 -3.175)
			(end 12.287 -3.175)
			(stroke
				(width 0.4445)
				(type solid)
			)
			(fill no)
			(layer "B.Paste")
		)
		(fp_circle
			(center 10.795 -3.175)
			(end 11.017 -3.175)
			(stroke
				(width 0.4445)
				(type solid)
			)
			(fill no)
			(layer "B.Paste")
		)
		(fp_circle
			(center 9.525 -3.175)
			(end 9.747 -3.175)
			(stroke
				(width 0.4445)
				(type solid)
			)
			(fill no)
			(layer "B.Paste")
		)
		(fp_circle
			(center 8.255 -3.175)
			(end 8.477 -3.175)
			(stroke
				(width 0.4445)
				(type solid)
			)
			(fill no)
			(layer "B.Paste")
		)
		(fp_circle
			(center 6.985 -3.175)
			(end 7.207 -3.175)
			(stroke
				(width 0.4445)
				(type solid)
			)
			(fill no)
			(layer "B.Paste")
		)
		(fp_circle
			(center 5.715 -3.175)
			(end 5.937 -3.175)
			(stroke
				(width 0.4445)
				(type solid)
			)
			(fill no)
			(layer "B.Paste")
		)
		(fp_circle
			(center 4.445 -3.175)
			(end 4.667 -3.175)
			(stroke
				(width 0.4445)
				(type solid)
			)
			(fill no)
			(layer "B.Paste")
		)
		(fp_circle
			(center 3.175 -3.175)
			(end 3.397 -3.175)
			(stroke
				(width 0.4445)
				(type solid)
			)
			(fill no)
			(layer "B.Paste")
		)
		(fp_circle
			(center 1.905 -3.175)
			(end 2.127 -3.175)
			(stroke
				(width 0.4445)
				(type solid)
			)
			(fill no)
			(layer "B.Paste")
		)
		(fp_circle
			(center 0.635 -3.175)
			(end 0.857 -3.175)
			(stroke
				(width 0.4445)
				(type solid)
			)
			(fill no)
			(layer "B.Paste")
		)
		(fp_circle
			(center -0.635 -3.175)
			(end -0.413 -3.175)
			(stroke
				(width 0.4445)
				(type solid)
			)
			(fill no)
			(layer "B.Paste")
		)
		(fp_circle
			(center -1.905 -3.175)
			(end -1.683 -3.175)
			(stroke
				(width 0.4445)
				(type solid)
			)
			(fill no)
			(layer "B.Paste")
		)
		(fp_circle
			(center -3.175 -3.175)
			(end -2.953 -3.175)
			(stroke
				(width 0.4445)
				(type solid)
			)
			(fill no)
			(layer "B.Paste")
		)
		(fp_circle
			(center -4.445 -3.175)
			(end -4.223 -3.175)
			(stroke
				(width 0.4445)
				(type solid)
			)
			(fill no)
			(layer "B.Paste")
		)
		(fp_circle
			(center -5.715 -3.175)
			(end -5.493 -3.175)
			(stroke
				(width 0.4445)
				(type solid)
			)
			(fill no)
			(layer "B.Paste")
		)
		(fp_circle
			(center -6.985 -3.175)
			(end -6.763 -3.175)
			(stroke
				(width 0.4445)
				(type solid)
			)
			(fill no)
			(layer "B.Paste")
		)
		(fp_circle
			(center -8.255 -3.175)
			(end -8.033 -3.175)
			(stroke
				(width 0.4445)
				(type solid)
			)
			(fill no)
			(layer "B.Paste")
		)
		(fp_circle
			(center -9.525 -3.175)
			(end -9.303 -3.175)
			(stroke
				(width 0.4445)
				(type solid)
			)
			(fill no)
			(layer "B.Paste")
		)
		(fp_circle
			(center -10.795 -3.175)
			(end -10.573 -3.175)
			(stroke
				(width 0.4445)
				(type solid)
			)
			(fill no)
			(layer "B.Paste")
		)
		(fp_circle
			(center -12.065 -3.175)
			(end -11.843 -3.175)
			(stroke
				(width 0.4445)
				(type solid)
			)
			(fill no)
			(layer "B.Paste")
		)
		(fp_circle
			(center -13.335 -3.175)
			(end -13.113 -3.175)
			(stroke
				(width 0.4445)
				(type solid)
			)
			(fill no)
			(layer "B.Paste")
		)
		(fp_circle
			(center -14.605 -3.175)
			(end -14.383 -3.175)
			(stroke
				(width 0.4445)
				(type solid)
			)
			(fill no)
			(layer "B.Paste")
		)
		(fp_circle
			(center -15.875 -3.175)
			(end -15.653 -3.175)
			(stroke
				(width 0.4445)
				(type solid)
			)
			(fill no)
			(layer "B.Paste")
		)
		(fp_circle
			(center -17.145 -3.175)
			(end -16.923 -3.175)
			(stroke
				(width 0.4445)
				(type solid)
			)
			(fill no)
			(layer "B.Paste")
		)
		(fp_circle
			(center -18.415 -3.175)
			(end -18.193 -3.175)
			(stroke
				(width 0.4445)
				(type solid)
			)
			(fill no)
			(layer "B.Paste")
		)
		(fp_circle
			(center -19.685 -3.175)
			(end -19.463 -3.175)
			(stroke
				(width 0.4445)
				(type solid)
			)
			(fill no)
			(layer "B.Paste")
		)
		(fp_circle
			(center -20.955 -3.175)
			(end -20.733 -3.175)
			(stroke
				(width 0.4445)
				(type solid)
			)
			(fill no)
			(layer "B.Paste")
		)
		(fp_circle
			(center -22.225 -3.175)
			(end -22.003 -3.175)
			(stroke
				(width 0.4445)
				(type solid)
			)
			(fill no)
			(layer "B.Paste")
		)
		(fp_circle
			(center -23.495 -3.175)
			(end -23.273 -3.175)
			(stroke
				(width 0.4445)
				(type solid)
			)
			(fill no)
			(layer "B.Paste")
		)
		(fp_circle
			(center -24.765 -3.175)
			(end -24.543 -3.175)
			(stroke
				(width 0.4445)
				(type solid)
			)
			(fill no)
			(layer "B.Paste")
		)
		(fp_circle
			(center 24.765 -1.905)
			(end 24.987 -1.905)
			(stroke
				(width 0.4445)
				(type solid)
			)
			(fill no)
			(layer "B.Paste")
		)
		(fp_circle
			(center 23.495 -1.905)
			(end 23.717 -1.905)
			(stroke
				(width 0.4445)
				(type solid)
			)
			(fill no)
			(layer "B.Paste")
		)
		(fp_circle
			(center 22.225 -1.905)
			(end 22.447 -1.905)
			(stroke
				(width 0.4445)
				(type solid)
			)
			(fill no)
			(layer "B.Paste")
		)
		(fp_circle
			(center 20.955 -1.905)
			(end 21.177 -1.905)
			(stroke
				(width 0.4445)
				(type solid)
			)
			(fill no)
			(layer "B.Paste")
		)
		(fp_circle
			(center 19.685 -1.905)
			(end 19.907 -1.905)
			(stroke
				(width 0.4445)
				(type solid)
			)
			(fill no)
			(layer "B.Paste")
		)
		(fp_circle
			(center 18.415 -1.905)
			(end 18.637 -1.905)
			(stroke
				(width 0.4445)
				(type solid)
			)
			(fill no)
			(layer "B.Paste")
		)
		(fp_circle
			(center 17.145 -1.905)
			(end 17.367 -1.905)
			(stroke
				(width 0.4445)
				(type solid)
			)
			(fill no)
			(layer "B.Paste")
		)
		(fp_circle
			(center 15.875 -1.905)
			(end 16.097 -1.905)
			(stroke
				(width 0.4445)
				(type solid)
			)
			(fill no)
			(layer "B.Paste")
		)
		(fp_circle
			(center 14.605 -1.905)
			(end 14.827 -1.905)
			(stroke
				(width 0.4445)
				(type solid)
			)
			(fill no)
			(layer "B.Paste")
		)
		(fp_circle
			(center 13.335 -1.905)
			(end 13.557 -1.905)
			(stroke
				(width 0.4445)
				(type solid)
			)
			(fill no)
			(layer "B.Paste")
		)
		(fp_circle
			(center 12.065 -1.905)
			(end 12.287 -1.905)
			(stroke
				(width 0.4445)
				(type solid)
			)
			(fill no)
			(layer "B.Paste")
		)
		(fp_circle
			(center 10.795 -1.905)
			(end 11.017 -1.905)
			(stroke
				(width 0.4445)
				(type solid)
			)
			(fill no)
			(layer "B.Paste")
		)
		(fp_circle
			(center 9.525 -1.905)
			(end 9.747 -1.905)
			(stroke
				(width 0.4445)
				(type solid)
			)
			(fill no)
			(layer "B.Paste")
		)
		(fp_circle
			(center 8.255 -1.905)
			(end 8.477 -1.905)
			(stroke
				(width 0.4445)
				(type solid)
			)
			(fill no)
			(layer "B.Paste")
		)
		(fp_circle
			(center 6.985 -1.905)
			(end 7.207 -1.905)
			(stroke
				(width 0.4445)
				(type solid)
			)
			(fill no)
			(layer "B.Paste")
		)
		(fp_circle
			(center 5.715 -1.905)
			(end 5.937 -1.905)
			(stroke
				(width 0.4445)
				(type solid)
			)
			(fill no)
			(layer "B.Paste")
		)
		(fp_circle
			(center 4.445 -1.905)
			(end 4.667 -1.905)
			(stroke
				(width 0.4445)
				(type solid)
			)
			(fill no)
			(layer "B.Paste")
		)
		(fp_circle
			(center 3.175 -1.905)
			(end 3.397 -1.905)
			(stroke
				(width 0.4445)
				(type solid)
			)
			(fill no)
			(layer "B.Paste")
		)
		(fp_circle
			(center 1.905 -1.905)
			(end 2.127 -1.905)
			(stroke
				(width 0.4445)
				(type solid)
			)
			(fill no)
			(layer "B.Paste")
		)
		(fp_circle
			(center 0.635 -1.905)
			(end 0.857 -1.905)
			(stroke
				(width 0.4445)
				(type solid)
			)
			(fill no)
			(layer "B.Paste")
		)
		(fp_circle
			(center -0.635 -1.905)
			(end -0.413 -1.905)
			(stroke
				(width 0.4445)
				(type solid)
			)
			(fill no)
			(layer "B.Paste")
		)
		(fp_circle
			(center -1.905 -1.905)
			(end -1.683 -1.905)
			(stroke
				(width 0.4445)
				(type solid)
			)
			(fill no)
			(layer "B.Paste")
		)
		(fp_circle
			(center -3.175 -1.905)
			(end -2.953 -1.905)
			(stroke
				(width 0.4445)
				(type solid)
			)
			(fill no)
			(layer "B.Paste")
		)
		(fp_circle
			(center -4.445 -1.905)
			(end -4.223 -1.905)
			(stroke
				(width 0.4445)
				(type solid)
			)
			(fill no)
			(layer "B.Paste")
		)
		(fp_circle
			(center -5.715 -1.905)
			(end -5.493 -1.905)
			(stroke
				(width 0.4445)
				(type solid)
			)
			(fill no)
			(layer "B.Paste")
		)
		(fp_circle
			(center -6.985 -1.905)
			(end -6.763 -1.905)
			(stroke
				(width 0.4445)
				(type solid)
			)
			(fill no)
			(layer "B.Paste")
		)
		(fp_circle
			(center -8.255 -1.905)
			(end -8.033 -1.905)
			(stroke
				(width 0.4445)
				(type solid)
			)
			(fill no)
			(layer "B.Paste")
		)
		(fp_circle
			(center -9.525 -1.905)
			(end -9.303 -1.905)
			(stroke
				(width 0.4445)
				(type solid)
			)
			(fill no)
			(layer "B.Paste")
		)
		(fp_circle
			(center -10.795 -1.905)
			(end -10.573 -1.905)
			(stroke
				(width 0.4445)
				(type solid)
			)
			(fill no)
			(layer "B.Paste")
		)
		(fp_circle
			(center -12.065 -1.905)
			(end -11.843 -1.905)
			(stroke
				(width 0.4445)
				(type solid)
			)
			(fill no)
			(layer "B.Paste")
		)
		(fp_circle
			(center -13.335 -1.905)
			(end -13.113 -1.905)
			(stroke
				(width 0.4445)
				(type solid)
			)
			(fill no)
			(layer "B.Paste")
		)
		(fp_circle
			(center -14.605 -1.905)
			(end -14.383 -1.905)
			(stroke
				(width 0.4445)
				(type solid)
			)
			(fill no)
			(layer "B.Paste")
		)
		(fp_circle
			(center -15.875 -1.905)
			(end -15.653 -1.905)
			(stroke
				(width 0.4445)
				(type solid)
			)
			(fill no)
			(layer "B.Paste")
		)
		(fp_circle
			(center -17.145 -1.905)
			(end -16.923 -1.905)
			(stroke
				(width 0.4445)
				(type solid)
			)
			(fill no)
			(layer "B.Paste")
		)
		(fp_circle
			(center -18.415 -1.905)
			(end -18.193 -1.905)
			(stroke
				(width 0.4445)
				(type solid)
			)
			(fill no)
			(layer "B.Paste")
		)
		(fp_circle
			(center -19.685 -1.905)
			(end -19.463 -1.905)
			(stroke
				(width 0.4445)
				(type solid)
			)
			(fill no)
			(layer "B.Paste")
		)
		(fp_circle
			(center -20.955 -1.905)
			(end -20.733 -1.905)
			(stroke
				(width 0.4445)
				(type solid)
			)
			(fill no)
			(layer "B.Paste")
		)
		(fp_circle
			(center -22.225 -1.905)
			(end -22.003 -1.905)
			(stroke
				(width 0.4445)
				(type solid)
			)
			(fill no)
			(layer "B.Paste")
		)
		(fp_circle
			(center -23.495 -1.905)
			(end -23.273 -1.905)
			(stroke
				(width 0.4445)
				(type solid)
			)
			(fill no)
			(layer "B.Paste")
		)
		(fp_circle
			(center -24.765 -1.905)
			(end -24.543 -1.905)
			(stroke
				(width 0.4445)
				(type solid)
			)
			(fill no)
			(layer "B.Paste")
		)
		(fp_circle
			(center 24.765 -0.635)
			(end 24.987 -0.635)
			(stroke
				(width 0.4445)
				(type solid)
			)
			(fill no)
			(layer "B.Paste")
		)
		(fp_circle
			(center 23.495 -0.635)
			(end 23.717 -0.635)
			(stroke
				(width 0.4445)
				(type solid)
			)
			(fill no)
			(layer "B.Paste")
		)
		(fp_circle
			(center 22.225 -0.635)
			(end 22.447 -0.635)
			(stroke
				(width 0.4445)
				(type solid)
			)
			(fill no)
			(layer "B.Paste")
		)
		(fp_circle
			(center 20.955 -0.635)
			(end 21.177 -0.635)
			(stroke
				(width 0.4445)
				(type solid)
			)
			(fill no)
			(layer "B.Paste")
		)
		(fp_circle
			(center 19.685 -0.635)
			(end 19.907 -0.635)
			(stroke
				(width 0.4445)
				(type solid)
			)
			(fill no)
			(layer "B.Paste")
		)
		(fp_circle
			(center 18.415 -0.635)
			(end 18.637 -0.635)
			(stroke
				(width 0.4445)
				(type solid)
			)
			(fill no)
			(layer "B.Paste")
		)
		(fp_circle
			(center 17.145 -0.635)
			(end 17.367 -0.635)
			(stroke
				(width 0.4445)
				(type solid)
			)
			(fill no)
			(layer "B.Paste")
		)
		(fp_circle
			(center 15.875 -0.635)
			(end 16.097 -0.635)
			(stroke
				(width 0.4445)
				(type solid)
			)
			(fill no)
			(layer "B.Paste")
		)
		(fp_circle
			(center 14.605 -0.635)
			(end 14.827 -0.635)
			(stroke
				(width 0.4445)
				(type solid)
			)
			(fill no)
			(layer "B.Paste")
		)
		(fp_circle
			(center 13.335 -0.635)
			(end 13.557 -0.635)
			(stroke
				(width 0.4445)
				(type solid)
			)
			(fill no)
			(layer "B.Paste")
		)
		(fp_circle
			(center 12.065 -0.635)
			(end 12.287 -0.635)
			(stroke
				(width 0.4445)
				(type solid)
			)
			(fill no)
			(layer "B.Paste")
		)
		(fp_circle
			(center 10.795 -0.635)
			(end 11.017 -0.635)
			(stroke
				(width 0.4445)
				(type solid)
			)
			(fill no)
			(layer "B.Paste")
		)
		(fp_circle
			(center 9.525 -0.635)
			(end 9.747 -0.635)
			(stroke
				(width 0.4445)
				(type solid)
			)
			(fill no)
			(layer "B.Paste")
		)
		(fp_circle
			(center 8.255 -0.635)
			(end 8.477 -0.635)
			(stroke
				(width 0.4445)
				(type solid)
			)
			(fill no)
			(layer "B.Paste")
		)
		(fp_circle
			(center 6.985 -0.635)
			(end 7.207 -0.635)
			(stroke
				(width 0.4445)
				(type solid)
			)
			(fill no)
			(layer "B.Paste")
		)
		(fp_circle
			(center 5.715 -0.635)
			(end 5.937 -0.635)
			(stroke
				(width 0.4445)
				(type solid)
			)
			(fill no)
			(layer "B.Paste")
		)
		(fp_circle
			(center 4.445 -0.635)
			(end 4.667 -0.635)
			(stroke
				(width 0.4445)
				(type solid)
			)
			(fill no)
			(layer "B.Paste")
		)
		(fp_circle
			(center 3.175 -0.635)
			(end 3.397 -0.635)
			(stroke
				(width 0.4445)
				(type solid)
			)
			(fill no)
			(layer "B.Paste")
		)
		(fp_circle
			(center 1.905 -0.635)
			(end 2.127 -0.635)
			(stroke
				(width 0.4445)
				(type solid)
			)
			(fill no)
			(layer "B.Paste")
		)
		(fp_circle
			(center 0.635 -0.635)
			(end 0.857 -0.635)
			(stroke
				(width 0.4445)
				(type solid)
			)
			(fill no)
			(layer "B.Paste")
		)
		(fp_circle
			(center -0.635 -0.635)
			(end -0.413 -0.635)
			(stroke
				(width 0.4445)
				(type solid)
			)
			(fill no)
			(layer "B.Paste")
		)
		(fp_circle
			(center -1.905 -0.635)
			(end -1.683 -0.635)
			(stroke
				(width 0.4445)
				(type solid)
			)
			(fill no)
			(layer "B.Paste")
		)
		(fp_circle
			(center -3.175 -0.635)
			(end -2.953 -0.635)
			(stroke
				(width 0.4445)
				(type solid)
			)
			(fill no)
			(layer "B.Paste")
		)
		(fp_circle
			(center -4.445 -0.635)
			(end -4.223 -0.635)
			(stroke
				(width 0.4445)
				(type solid)
			)
			(fill no)
			(layer "B.Paste")
		)
		(fp_circle
			(center -5.715 -0.635)
			(end -5.493 -0.635)
			(stroke
				(width 0.4445)
				(type solid)
			)
			(fill no)
			(layer "B.Paste")
		)
		(fp_circle
			(center -6.985 -0.635)
			(end -6.763 -0.635)
			(stroke
				(width 0.4445)
				(type solid)
			)
			(fill no)
			(layer "B.Paste")
		)
		(fp_circle
			(center -8.255 -0.635)
			(end -8.033 -0.635)
			(stroke
				(width 0.4445)
				(type solid)
			)
			(fill no)
			(layer "B.Paste")
		)
		(fp_circle
			(center -9.525 -0.635)
			(end -9.303 -0.635)
			(stroke
				(width 0.4445)
				(type solid)
			)
			(fill no)
			(layer "B.Paste")
		)
		(fp_circle
			(center -10.795 -0.635)
			(end -10.573 -0.635)
			(stroke
				(width 0.4445)
				(type solid)
			)
			(fill no)
			(layer "B.Paste")
		)
		(fp_circle
			(center -12.065 -0.635)
			(end -11.843 -0.635)
			(stroke
				(width 0.4445)
				(type solid)
			)
			(fill no)
			(layer "B.Paste")
		)
		(fp_circle
			(center -13.335 -0.635)
			(end -13.113 -0.635)
			(stroke
				(width 0.4445)
				(type solid)
			)
			(fill no)
			(layer "B.Paste")
		)
		(fp_circle
			(center -14.605 -0.635)
			(end -14.383 -0.635)
			(stroke
				(width 0.4445)
				(type solid)
			)
			(fill no)
			(layer "B.Paste")
		)
		(fp_circle
			(center -15.875 -0.635)
			(end -15.653 -0.635)
			(stroke
				(width 0.4445)
				(type solid)
			)
			(fill no)
			(layer "B.Paste")
		)
		(fp_circle
			(center -17.145 -0.635)
			(end -16.923 -0.635)
			(stroke
				(width 0.4445)
				(type solid)
			)
			(fill no)
			(layer "B.Paste")
		)
		(fp_circle
			(center -18.415 -0.635)
			(end -18.193 -0.635)
			(stroke
				(width 0.4445)
				(type solid)
			)
			(fill no)
			(layer "B.Paste")
		)
		(fp_circle
			(center -19.685 -0.635)
			(end -19.463 -0.635)
			(stroke
				(width 0.4445)
				(type solid)
			)
			(fill no)
			(layer "B.Paste")
		)
		(fp_circle
			(center -20.955 -0.635)
			(end -20.733 -0.635)
			(stroke
				(width 0.4445)
				(type solid)
			)
			(fill no)
			(layer "B.Paste")
		)
		(fp_circle
			(center -22.225 -0.635)
			(end -22.003 -0.635)
			(stroke
				(width 0.4445)
				(type solid)
			)
			(fill no)
			(layer "B.Paste")
		)
		(fp_circle
			(center -23.495 -0.635)
			(end -23.273 -0.635)
			(stroke
				(width 0.4445)
				(type solid)
			)
			(fill no)
			(layer "B.Paste")
		)
		(fp_circle
			(center -24.765 -0.635)
			(end -24.543 -0.635)
			(stroke
				(width 0.4445)
				(type solid)
			)
			(fill no)
			(layer "B.Paste")
		)
		(fp_circle
			(center 24.765 0.635)
			(end 24.987 0.635)
			(stroke
				(width 0.4445)
				(type solid)
			)
			(fill no)
			(layer "B.Paste")
		)
		(fp_circle
			(center 23.495 0.635)
			(end 23.717 0.635)
			(stroke
				(width 0.4445)
				(type solid)
			)
			(fill no)
			(layer "B.Paste")
		)
		(fp_circle
			(center 22.225 0.635)
			(end 22.447 0.635)
			(stroke
				(width 0.4445)
				(type solid)
			)
			(fill no)
			(layer "B.Paste")
		)
		(fp_circle
			(center 20.955 0.635)
			(end 21.177 0.635)
			(stroke
				(width 0.4445)
				(type solid)
			)
			(fill no)
			(layer "B.Paste")
		)
		(fp_circle
			(center 19.685 0.635)
			(end 19.907 0.635)
			(stroke
				(width 0.4445)
				(type solid)
			)
			(fill no)
			(layer "B.Paste")
		)
		(fp_circle
			(center 18.415 0.635)
			(end 18.637 0.635)
			(stroke
				(width 0.4445)
				(type solid)
			)
			(fill no)
			(layer "B.Paste")
		)
		(fp_circle
			(center 17.145 0.635)
			(end 17.367 0.635)
			(stroke
				(width 0.4445)
				(type solid)
			)
			(fill no)
			(layer "B.Paste")
		)
		(fp_circle
			(center 15.875 0.635)
			(end 16.097 0.635)
			(stroke
				(width 0.4445)
				(type solid)
			)
			(fill no)
			(layer "B.Paste")
		)
		(fp_circle
			(center 14.605 0.635)
			(end 14.827 0.635)
			(stroke
				(width 0.4445)
				(type solid)
			)
			(fill no)
			(layer "B.Paste")
		)
		(fp_circle
			(center 13.335 0.635)
			(end 13.557 0.635)
			(stroke
				(width 0.4445)
				(type solid)
			)
			(fill no)
			(layer "B.Paste")
		)
		(fp_circle
			(center 12.065 0.635)
			(end 12.287 0.635)
			(stroke
				(width 0.4445)
				(type solid)
			)
			(fill no)
			(layer "B.Paste")
		)
		(fp_circle
			(center 10.795 0.635)
			(end 11.017 0.635)
			(stroke
				(width 0.4445)
				(type solid)
			)
			(fill no)
			(layer "B.Paste")
		)
		(fp_circle
			(center 9.525 0.635)
			(end 9.747 0.635)
			(stroke
				(width 0.4445)
				(type solid)
			)
			(fill no)
			(layer "B.Paste")
		)
		(fp_circle
			(center 8.255 0.635)
			(end 8.477 0.635)
			(stroke
				(width 0.4445)
				(type solid)
			)
			(fill no)
			(layer "B.Paste")
		)
		(fp_circle
			(center 6.985 0.635)
			(end 7.207 0.635)
			(stroke
				(width 0.4445)
				(type solid)
			)
			(fill no)
			(layer "B.Paste")
		)
		(fp_circle
			(center 5.715 0.635)
			(end 5.937 0.635)
			(stroke
				(width 0.4445)
				(type solid)
			)
			(fill no)
			(layer "B.Paste")
		)
		(fp_circle
			(center 4.445 0.635)
			(end 4.667 0.635)
			(stroke
				(width 0.4445)
				(type solid)
			)
			(fill no)
			(layer "B.Paste")
		)
		(fp_circle
			(center 3.175 0.635)
			(end 3.397 0.635)
			(stroke
				(width 0.4445)
				(type solid)
			)
			(fill no)
			(layer "B.Paste")
		)
		(fp_circle
			(center 1.905 0.635)
			(end 2.127 0.635)
			(stroke
				(width 0.4445)
				(type solid)
			)
			(fill no)
			(layer "B.Paste")
		)
		(fp_circle
			(center 0.635 0.635)
			(end 0.857 0.635)
			(stroke
				(width 0.4445)
				(type solid)
			)
			(fill no)
			(layer "B.Paste")
		)
		(fp_circle
			(center -0.635 0.635)
			(end -0.413 0.635)
			(stroke
				(width 0.4445)
				(type solid)
			)
			(fill no)
			(layer "B.Paste")
		)
		(fp_circle
			(center -1.905 0.635)
			(end -1.683 0.635)
			(stroke
				(width 0.4445)
				(type solid)
			)
			(fill no)
			(layer "B.Paste")
		)
		(fp_circle
			(center -3.175 0.635)
			(end -2.953 0.635)
			(stroke
				(width 0.4445)
				(type solid)
			)
			(fill no)
			(layer "B.Paste")
		)
		(fp_circle
			(center -4.445 0.635)
			(end -4.223 0.635)
			(stroke
				(width 0.4445)
				(type solid)
			)
			(fill no)
			(layer "B.Paste")
		)
		(fp_circle
			(center -5.715 0.635)
			(end -5.493 0.635)
			(stroke
				(width 0.4445)
				(type solid)
			)
			(fill no)
			(layer "B.Paste")
		)
		(fp_circle
			(center -6.985 0.635)
			(end -6.763 0.635)
			(stroke
				(width 0.4445)
				(type solid)
			)
			(fill no)
			(layer "B.Paste")
		)
		(fp_circle
			(center -8.255 0.635)
			(end -8.033 0.635)
			(stroke
				(width 0.4445)
				(type solid)
			)
			(fill no)
			(layer "B.Paste")
		)
		(fp_circle
			(center -9.525 0.635)
			(end -9.303 0.635)
			(stroke
				(width 0.4445)
				(type solid)
			)
			(fill no)
			(layer "B.Paste")
		)
		(fp_circle
			(center -10.795 0.635)
			(end -10.573 0.635)
			(stroke
				(width 0.4445)
				(type solid)
			)
			(fill no)
			(layer "B.Paste")
		)
		(fp_circle
			(center -12.065 0.635)
			(end -11.843 0.635)
			(stroke
				(width 0.4445)
				(type solid)
			)
			(fill no)
			(layer "B.Paste")
		)
		(fp_circle
			(center -13.335 0.635)
			(end -13.113 0.635)
			(stroke
				(width 0.4445)
				(type solid)
			)
			(fill no)
			(layer "B.Paste")
		)
		(fp_circle
			(center -14.605 0.635)
			(end -14.383 0.635)
			(stroke
				(width 0.4445)
				(type solid)
			)
			(fill no)
			(layer "B.Paste")
		)
		(fp_circle
			(center -15.875 0.635)
			(end -15.653 0.635)
			(stroke
				(width 0.4445)
				(type solid)
			)
			(fill no)
			(layer "B.Paste")
		)
		(fp_circle
			(center -17.145 0.635)
			(end -16.923 0.635)
			(stroke
				(width 0.4445)
				(type solid)
			)
			(fill no)
			(layer "B.Paste")
		)
		(fp_circle
			(center -18.415 0.635)
			(end -18.193 0.635)
			(stroke
				(width 0.4445)
				(type solid)
			)
			(fill no)
			(layer "B.Paste")
		)
		(fp_circle
			(center -19.685 0.635)
			(end -19.463 0.635)
			(stroke
				(width 0.4445)
				(type solid)
			)
			(fill no)
			(layer "B.Paste")
		)
		(fp_circle
			(center -20.955 0.635)
			(end -20.733 0.635)
			(stroke
				(width 0.4445)
				(type solid)
			)
			(fill no)
			(layer "B.Paste")
		)
		(fp_circle
			(center -22.225 0.635)
			(end -22.003 0.635)
			(stroke
				(width 0.4445)
				(type solid)
			)
			(fill no)
			(layer "B.Paste")
		)
		(fp_circle
			(center -23.495 0.635)
			(end -23.273 0.635)
			(stroke
				(width 0.4445)
				(type solid)
			)
			(fill no)
			(layer "B.Paste")
		)
		(fp_circle
			(center -24.765 0.635)
			(end -24.543 0.635)
			(stroke
				(width 0.4445)
				(type solid)
			)
			(fill no)
			(layer "B.Paste")
		)
		(fp_circle
			(center 24.765 1.905)
			(end 24.987 1.905)
			(stroke
				(width 0.4445)
				(type solid)
			)
			(fill no)
			(layer "B.Paste")
		)
		(fp_circle
			(center 23.495 1.905)
			(end 23.717 1.905)
			(stroke
				(width 0.4445)
				(type solid)
			)
			(fill no)
			(layer "B.Paste")
		)
		(fp_circle
			(center 22.225 1.905)
			(end 22.447 1.905)
			(stroke
				(width 0.4445)
				(type solid)
			)
			(fill no)
			(layer "B.Paste")
		)
		(fp_circle
			(center 20.955 1.905)
			(end 21.177 1.905)
			(stroke
				(width 0.4445)
				(type solid)
			)
			(fill no)
			(layer "B.Paste")
		)
		(fp_circle
			(center 19.685 1.905)
			(end 19.907 1.905)
			(stroke
				(width 0.4445)
				(type solid)
			)
			(fill no)
			(layer "B.Paste")
		)
		(fp_circle
			(center 18.415 1.905)
			(end 18.637 1.905)
			(stroke
				(width 0.4445)
				(type solid)
			)
			(fill no)
			(layer "B.Paste")
		)
		(fp_circle
			(center 17.145 1.905)
			(end 17.367 1.905)
			(stroke
				(width 0.4445)
				(type solid)
			)
			(fill no)
			(layer "B.Paste")
		)
		(fp_circle
			(center 15.875 1.905)
			(end 16.097 1.905)
			(stroke
				(width 0.4445)
				(type solid)
			)
			(fill no)
			(layer "B.Paste")
		)
		(fp_circle
			(center 14.605 1.905)
			(end 14.827 1.905)
			(stroke
				(width 0.4445)
				(type solid)
			)
			(fill no)
			(layer "B.Paste")
		)
		(fp_circle
			(center 13.335 1.905)
			(end 13.557 1.905)
			(stroke
				(width 0.4445)
				(type solid)
			)
			(fill no)
			(layer "B.Paste")
		)
		(fp_circle
			(center 12.065 1.905)
			(end 12.287 1.905)
			(stroke
				(width 0.4445)
				(type solid)
			)
			(fill no)
			(layer "B.Paste")
		)
		(fp_circle
			(center 10.795 1.905)
			(end 11.017 1.905)
			(stroke
				(width 0.4445)
				(type solid)
			)
			(fill no)
			(layer "B.Paste")
		)
		(fp_circle
			(center 9.525 1.905)
			(end 9.747 1.905)
			(stroke
				(width 0.4445)
				(type solid)
			)
			(fill no)
			(layer "B.Paste")
		)
		(fp_circle
			(center 8.255 1.905)
			(end 8.477 1.905)
			(stroke
				(width 0.4445)
				(type solid)
			)
			(fill no)
			(layer "B.Paste")
		)
		(fp_circle
			(center 6.985 1.905)
			(end 7.207 1.905)
			(stroke
				(width 0.4445)
				(type solid)
			)
			(fill no)
			(layer "B.Paste")
		)
		(fp_circle
			(center 5.715 1.905)
			(end 5.937 1.905)
			(stroke
				(width 0.4445)
				(type solid)
			)
			(fill no)
			(layer "B.Paste")
		)
		(fp_circle
			(center 4.445 1.905)
			(end 4.667 1.905)
			(stroke
				(width 0.4445)
				(type solid)
			)
			(fill no)
			(layer "B.Paste")
		)
		(fp_circle
			(center 3.175 1.905)
			(end 3.397 1.905)
			(stroke
				(width 0.4445)
				(type solid)
			)
			(fill no)
			(layer "B.Paste")
		)
		(fp_circle
			(center 1.905 1.905)
			(end 2.127 1.905)
			(stroke
				(width 0.4445)
				(type solid)
			)
			(fill no)
			(layer "B.Paste")
		)
		(fp_circle
			(center 0.635 1.905)
			(end 0.857 1.905)
			(stroke
				(width 0.4445)
				(type solid)
			)
			(fill no)
			(layer "B.Paste")
		)
		(fp_circle
			(center -0.635 1.905)
			(end -0.413 1.905)
			(stroke
				(width 0.4445)
				(type solid)
			)
			(fill no)
			(layer "B.Paste")
		)
		(fp_circle
			(center -1.905 1.905)
			(end -1.683 1.905)
			(stroke
				(width 0.4445)
				(type solid)
			)
			(fill no)
			(layer "B.Paste")
		)
		(fp_circle
			(center -3.175 1.905)
			(end -2.953 1.905)
			(stroke
				(width 0.4445)
				(type solid)
			)
			(fill no)
			(layer "B.Paste")
		)
		(fp_circle
			(center -4.445 1.905)
			(end -4.223 1.905)
			(stroke
				(width 0.4445)
				(type solid)
			)
			(fill no)
			(layer "B.Paste")
		)
		(fp_circle
			(center -5.715 1.905)
			(end -5.493 1.905)
			(stroke
				(width 0.4445)
				(type solid)
			)
			(fill no)
			(layer "B.Paste")
		)
		(fp_circle
			(center -6.985 1.905)
			(end -6.763 1.905)
			(stroke
				(width 0.4445)
				(type solid)
			)
			(fill no)
			(layer "B.Paste")
		)
		(fp_circle
			(center -8.255 1.905)
			(end -8.033 1.905)
			(stroke
				(width 0.4445)
				(type solid)
			)
			(fill no)
			(layer "B.Paste")
		)
		(fp_circle
			(center -9.525 1.905)
			(end -9.303 1.905)
			(stroke
				(width 0.4445)
				(type solid)
			)
			(fill no)
			(layer "B.Paste")
		)
		(fp_circle
			(center -10.795 1.905)
			(end -10.573 1.905)
			(stroke
				(width 0.4445)
				(type solid)
			)
			(fill no)
			(layer "B.Paste")
		)
		(fp_circle
			(center -12.065 1.905)
			(end -11.843 1.905)
			(stroke
				(width 0.4445)
				(type solid)
			)
			(fill no)
			(layer "B.Paste")
		)
		(fp_circle
			(center -13.335 1.905)
			(end -13.113 1.905)
			(stroke
				(width 0.4445)
				(type solid)
			)
			(fill no)
			(layer "B.Paste")
		)
		(fp_circle
			(center -14.605 1.905)
			(end -14.383 1.905)
			(stroke
				(width 0.4445)
				(type solid)
			)
			(fill no)
			(layer "B.Paste")
		)
		(fp_circle
			(center -15.875 1.905)
			(end -15.653 1.905)
			(stroke
				(width 0.4445)
				(type solid)
			)
			(fill no)
			(layer "B.Paste")
		)
		(fp_circle
			(center -17.145 1.905)
			(end -16.923 1.905)
			(stroke
				(width 0.4445)
				(type solid)
			)
			(fill no)
			(layer "B.Paste")
		)
		(fp_circle
			(center -18.415 1.905)
			(end -18.193 1.905)
			(stroke
				(width 0.4445)
				(type solid)
			)
			(fill no)
			(layer "B.Paste")
		)
		(fp_circle
			(center -19.685 1.905)
			(end -19.463 1.905)
			(stroke
				(width 0.4445)
				(type solid)
			)
			(fill no)
			(layer "B.Paste")
		)
		(fp_circle
			(center -20.955 1.905)
			(end -20.733 1.905)
			(stroke
				(width 0.4445)
				(type solid)
			)
			(fill no)
			(layer "B.Paste")
		)
		(fp_circle
			(center -22.225 1.905)
			(end -22.003 1.905)
			(stroke
				(width 0.4445)
				(type solid)
			)
			(fill no)
			(layer "B.Paste")
		)
		(fp_circle
			(center -23.495 1.905)
			(end -23.273 1.905)
			(stroke
				(width 0.4445)
				(type solid)
			)
			(fill no)
			(layer "B.Paste")
		)
		(fp_circle
			(center -24.765 1.905)
			(end -24.543 1.905)
			(stroke
				(width 0.4445)
				(type solid)
			)
			(fill no)
			(layer "B.Paste")
		)
		(fp_circle
			(center 24.765 3.175)
			(end 24.987 3.175)
			(stroke
				(width 0.4445)
				(type solid)
			)
			(fill no)
			(layer "B.Paste")
		)
		(fp_circle
			(center 23.495 3.175)
			(end 23.717 3.175)
			(stroke
				(width 0.4445)
				(type solid)
			)
			(fill no)
			(layer "B.Paste")
		)
		(fp_circle
			(center 22.225 3.175)
			(end 22.447 3.175)
			(stroke
				(width 0.4445)
				(type solid)
			)
			(fill no)
			(layer "B.Paste")
		)
		(fp_circle
			(center 20.955 3.175)
			(end 21.177 3.175)
			(stroke
				(width 0.4445)
				(type solid)
			)
			(fill no)
			(layer "B.Paste")
		)
		(fp_circle
			(center 19.685 3.175)
			(end 19.907 3.175)
			(stroke
				(width 0.4445)
				(type solid)
			)
			(fill no)
			(layer "B.Paste")
		)
		(fp_circle
			(center 18.415 3.175)
			(end 18.637 3.175)
			(stroke
				(width 0.4445)
				(type solid)
			)
			(fill no)
			(layer "B.Paste")
		)
		(fp_circle
			(center 17.145 3.175)
			(end 17.367 3.175)
			(stroke
				(width 0.4445)
				(type solid)
			)
			(fill no)
			(layer "B.Paste")
		)
		(fp_circle
			(center 15.875 3.175)
			(end 16.097 3.175)
			(stroke
				(width 0.4445)
				(type solid)
			)
			(fill no)
			(layer "B.Paste")
		)
		(fp_circle
			(center 14.605 3.175)
			(end 14.827 3.175)
			(stroke
				(width 0.4445)
				(type solid)
			)
			(fill no)
			(layer "B.Paste")
		)
		(fp_circle
			(center 13.335 3.175)
			(end 13.557 3.175)
			(stroke
				(width 0.4445)
				(type solid)
			)
			(fill no)
			(layer "B.Paste")
		)
		(fp_circle
			(center 12.065 3.175)
			(end 12.287 3.175)
			(stroke
				(width 0.4445)
				(type solid)
			)
			(fill no)
			(layer "B.Paste")
		)
		(fp_circle
			(center 10.795 3.175)
			(end 11.017 3.175)
			(stroke
				(width 0.4445)
				(type solid)
			)
			(fill no)
			(layer "B.Paste")
		)
		(fp_circle
			(center 9.525 3.175)
			(end 9.747 3.175)
			(stroke
				(width 0.4445)
				(type solid)
			)
			(fill no)
			(layer "B.Paste")
		)
		(fp_circle
			(center 8.255 3.175)
			(end 8.477 3.175)
			(stroke
				(width 0.4445)
				(type solid)
			)
			(fill no)
			(layer "B.Paste")
		)
		(fp_circle
			(center 6.985 3.175)
			(end 7.207 3.175)
			(stroke
				(width 0.4445)
				(type solid)
			)
			(fill no)
			(layer "B.Paste")
		)
		(fp_circle
			(center 5.715 3.175)
			(end 5.937 3.175)
			(stroke
				(width 0.4445)
				(type solid)
			)
			(fill no)
			(layer "B.Paste")
		)
		(fp_circle
			(center 4.445 3.175)
			(end 4.667 3.175)
			(stroke
				(width 0.4445)
				(type solid)
			)
			(fill no)
			(layer "B.Paste")
		)
		(fp_circle
			(center 3.175 3.175)
			(end 3.397 3.175)
			(stroke
				(width 0.4445)
				(type solid)
			)
			(fill no)
			(layer "B.Paste")
		)
		(fp_circle
			(center 1.905 3.175)
			(end 2.127 3.175)
			(stroke
				(width 0.4445)
				(type solid)
			)
			(fill no)
			(layer "B.Paste")
		)
		(fp_circle
			(center 0.635 3.175)
			(end 0.857 3.175)
			(stroke
				(width 0.4445)
				(type solid)
			)
			(fill no)
			(layer "B.Paste")
		)
		(fp_circle
			(center -0.635 3.175)
			(end -0.413 3.175)
			(stroke
				(width 0.4445)
				(type solid)
			)
			(fill no)
			(layer "B.Paste")
		)
		(fp_circle
			(center -1.905 3.175)
			(end -1.683 3.175)
			(stroke
				(width 0.4445)
				(type solid)
			)
			(fill no)
			(layer "B.Paste")
		)
		(fp_circle
			(center -3.175 3.175)
			(end -2.953 3.175)
			(stroke
				(width 0.4445)
				(type solid)
			)
			(fill no)
			(layer "B.Paste")
		)
		(fp_circle
			(center -4.445 3.175)
			(end -4.223 3.175)
			(stroke
				(width 0.4445)
				(type solid)
			)
			(fill no)
			(layer "B.Paste")
		)
		(fp_circle
			(center -5.715 3.175)
			(end -5.493 3.175)
			(stroke
				(width 0.4445)
				(type solid)
			)
			(fill no)
			(layer "B.Paste")
		)
		(fp_circle
			(center -6.985 3.175)
			(end -6.763 3.175)
			(stroke
				(width 0.4445)
				(type solid)
			)
			(fill no)
			(layer "B.Paste")
		)
		(fp_circle
			(center -8.255 3.175)
			(end -8.033 3.175)
			(stroke
				(width 0.4445)
				(type solid)
			)
			(fill no)
			(layer "B.Paste")
		)
		(fp_circle
			(center -9.525 3.175)
			(end -9.303 3.175)
			(stroke
				(width 0.4445)
				(type solid)
			)
			(fill no)
			(layer "B.Paste")
		)
		(fp_circle
			(center -10.795 3.175)
			(end -10.573 3.175)
			(stroke
				(width 0.4445)
				(type solid)
			)
			(fill no)
			(layer "B.Paste")
		)
		(fp_circle
			(center -12.065 3.175)
			(end -11.843 3.175)
			(stroke
				(width 0.4445)
				(type solid)
			)
			(fill no)
			(layer "B.Paste")
		)
		(fp_circle
			(center -13.335 3.175)
			(end -13.113 3.175)
			(stroke
				(width 0.4445)
				(type solid)
			)
			(fill no)
			(layer "B.Paste")
		)
		(fp_circle
			(center -14.605 3.175)
			(end -14.383 3.175)
			(stroke
				(width 0.4445)
				(type solid)
			)
			(fill no)
			(layer "B.Paste")
		)
		(fp_circle
			(center -15.875 3.175)
			(end -15.653 3.175)
			(stroke
				(width 0.4445)
				(type solid)
			)
			(fill no)
			(layer "B.Paste")
		)
		(fp_circle
			(center -17.145 3.175)
			(end -16.923 3.175)
			(stroke
				(width 0.4445)
				(type solid)
			)
			(fill no)
			(layer "B.Paste")
		)
		(fp_circle
			(center -18.415 3.175)
			(end -18.193 3.175)
			(stroke
				(width 0.4445)
				(type solid)
			)
			(fill no)
			(layer "B.Paste")
		)
		(fp_circle
			(center -19.685 3.175)
			(end -19.463 3.175)
			(stroke
				(width 0.4445)
				(type solid)
			)
			(fill no)
			(layer "B.Paste")
		)
		(fp_circle
			(center -20.955 3.175)
			(end -20.733 3.175)
			(stroke
				(width 0.4445)
				(type solid)
			)
			(fill no)
			(layer "B.Paste")
		)
		(fp_circle
			(center -22.225 3.175)
			(end -22.003 3.175)
			(stroke
				(width 0.4445)
				(type solid)
			)
			(fill no)
			(layer "B.Paste")
		)
		(fp_circle
			(center -23.495 3.175)
			(end -23.273 3.175)
			(stroke
				(width 0.4445)
				(type solid)
			)
			(fill no)
			(layer "B.Paste")
		)
		(fp_circle
			(center -24.765 3.175)
			(end -24.543 3.175)
			(stroke
				(width 0.4445)
				(type solid)
			)
			(fill no)
			(layer "B.Paste")
		)
		(fp_circle
			(center 24.765 4.445)
			(end 24.987 4.445)
			(stroke
				(width 0.4445)
				(type solid)
			)
			(fill no)
			(layer "B.Paste")
		)
		(fp_circle
			(center 23.495 4.445)
			(end 23.717 4.445)
			(stroke
				(width 0.4445)
				(type solid)
			)
			(fill no)
			(layer "B.Paste")
		)
		(fp_circle
			(center 22.225 4.445)
			(end 22.447 4.445)
			(stroke
				(width 0.4445)
				(type solid)
			)
			(fill no)
			(layer "B.Paste")
		)
		(fp_circle
			(center 20.955 4.445)
			(end 21.177 4.445)
			(stroke
				(width 0.4445)
				(type solid)
			)
			(fill no)
			(layer "B.Paste")
		)
		(fp_circle
			(center 19.685 4.445)
			(end 19.907 4.445)
			(stroke
				(width 0.4445)
				(type solid)
			)
			(fill no)
			(layer "B.Paste")
		)
		(fp_circle
			(center 18.415 4.445)
			(end 18.637 4.445)
			(stroke
				(width 0.4445)
				(type solid)
			)
			(fill no)
			(layer "B.Paste")
		)
		(fp_circle
			(center 17.145 4.445)
			(end 17.367 4.445)
			(stroke
				(width 0.4445)
				(type solid)
			)
			(fill no)
			(layer "B.Paste")
		)
		(fp_circle
			(center 15.875 4.445)
			(end 16.097 4.445)
			(stroke
				(width 0.4445)
				(type solid)
			)
			(fill no)
			(layer "B.Paste")
		)
		(fp_circle
			(center 14.605 4.445)
			(end 14.827 4.445)
			(stroke
				(width 0.4445)
				(type solid)
			)
			(fill no)
			(layer "B.Paste")
		)
		(fp_circle
			(center 13.335 4.445)
			(end 13.557 4.445)
			(stroke
				(width 0.4445)
				(type solid)
			)
			(fill no)
			(layer "B.Paste")
		)
		(fp_circle
			(center 12.065 4.445)
			(end 12.287 4.445)
			(stroke
				(width 0.4445)
				(type solid)
			)
			(fill no)
			(layer "B.Paste")
		)
		(fp_circle
			(center 10.795 4.445)
			(end 11.017 4.445)
			(stroke
				(width 0.4445)
				(type solid)
			)
			(fill no)
			(layer "B.Paste")
		)
		(fp_circle
			(center 9.525 4.445)
			(end 9.747 4.445)
			(stroke
				(width 0.4445)
				(type solid)
			)
			(fill no)
			(layer "B.Paste")
		)
		(fp_circle
			(center 8.255 4.445)
			(end 8.477 4.445)
			(stroke
				(width 0.4445)
				(type solid)
			)
			(fill no)
			(layer "B.Paste")
		)
		(fp_circle
			(center 6.985 4.445)
			(end 7.207 4.445)
			(stroke
				(width 0.4445)
				(type solid)
			)
			(fill no)
			(layer "B.Paste")
		)
		(fp_circle
			(center 5.715 4.445)
			(end 5.937 4.445)
			(stroke
				(width 0.4445)
				(type solid)
			)
			(fill no)
			(layer "B.Paste")
		)
		(fp_circle
			(center 4.445 4.445)
			(end 4.667 4.445)
			(stroke
				(width 0.4445)
				(type solid)
			)
			(fill no)
			(layer "B.Paste")
		)
		(fp_circle
			(center 3.175 4.445)
			(end 3.397 4.445)
			(stroke
				(width 0.4445)
				(type solid)
			)
			(fill no)
			(layer "B.Paste")
		)
		(fp_circle
			(center 1.905 4.445)
			(end 2.127 4.445)
			(stroke
				(width 0.4445)
				(type solid)
			)
			(fill no)
			(layer "B.Paste")
		)
		(fp_circle
			(center 0.635 4.445)
			(end 0.857 4.445)
			(stroke
				(width 0.4445)
				(type solid)
			)
			(fill no)
			(layer "B.Paste")
		)
		(fp_circle
			(center -0.635 4.445)
			(end -0.413 4.445)
			(stroke
				(width 0.4445)
				(type solid)
			)
			(fill no)
			(layer "B.Paste")
		)
		(fp_circle
			(center -1.905 4.445)
			(end -1.683 4.445)
			(stroke
				(width 0.4445)
				(type solid)
			)
			(fill no)
			(layer "B.Paste")
		)
		(fp_circle
			(center -3.175 4.445)
			(end -2.953 4.445)
			(stroke
				(width 0.4445)
				(type solid)
			)
			(fill no)
			(layer "B.Paste")
		)
		(fp_circle
			(center -4.445 4.445)
			(end -4.223 4.445)
			(stroke
				(width 0.4445)
				(type solid)
			)
			(fill no)
			(layer "B.Paste")
		)
		(fp_circle
			(center -5.715 4.445)
			(end -5.493 4.445)
			(stroke
				(width 0.4445)
				(type solid)
			)
			(fill no)
			(layer "B.Paste")
		)
		(fp_circle
			(center -6.985 4.445)
			(end -6.763 4.445)
			(stroke
				(width 0.4445)
				(type solid)
			)
			(fill no)
			(layer "B.Paste")
		)
		(fp_circle
			(center -8.255 4.445)
			(end -8.033 4.445)
			(stroke
				(width 0.4445)
				(type solid)
			)
			(fill no)
			(layer "B.Paste")
		)
		(fp_circle
			(center -9.525 4.445)
			(end -9.303 4.445)
			(stroke
				(width 0.4445)
				(type solid)
			)
			(fill no)
			(layer "B.Paste")
		)
		(fp_circle
			(center -10.795 4.445)
			(end -10.573 4.445)
			(stroke
				(width 0.4445)
				(type solid)
			)
			(fill no)
			(layer "B.Paste")
		)
		(fp_circle
			(center -12.065 4.445)
			(end -11.843 4.445)
			(stroke
				(width 0.4445)
				(type solid)
			)
			(fill no)
			(layer "B.Paste")
		)
		(fp_circle
			(center -13.335 4.445)
			(end -13.113 4.445)
			(stroke
				(width 0.4445)
				(type solid)
			)
			(fill no)
			(layer "B.Paste")
		)
		(fp_circle
			(center -14.605 4.445)
			(end -14.383 4.445)
			(stroke
				(width 0.4445)
				(type solid)
			)
			(fill no)
			(layer "B.Paste")
		)
		(fp_circle
			(center -15.875 4.445)
			(end -15.653 4.445)
			(stroke
				(width 0.4445)
				(type solid)
			)
			(fill no)
			(layer "B.Paste")
		)
		(fp_circle
			(center -17.145 4.445)
			(end -16.923 4.445)
			(stroke
				(width 0.4445)
				(type solid)
			)
			(fill no)
			(layer "B.Paste")
		)
		(fp_circle
			(center -18.415 4.445)
			(end -18.193 4.445)
			(stroke
				(width 0.4445)
				(type solid)
			)
			(fill no)
			(layer "B.Paste")
		)
		(fp_circle
			(center -19.685 4.445)
			(end -19.463 4.445)
			(stroke
				(width 0.4445)
				(type solid)
			)
			(fill no)
			(layer "B.Paste")
		)
		(fp_circle
			(center -20.955 4.445)
			(end -20.733 4.445)
			(stroke
				(width 0.4445)
				(type solid)
			)
			(fill no)
			(layer "B.Paste")
		)
		(fp_circle
			(center -22.225 4.445)
			(end -22.003 4.445)
			(stroke
				(width 0.4445)
				(type solid)
			)
			(fill no)
			(layer "B.Paste")
		)
		(fp_circle
			(center -23.495 4.445)
			(end -23.273 4.445)
			(stroke
				(width 0.4445)
				(type solid)
			)
			(fill no)
			(layer "B.Paste")
		)
		(fp_circle
			(center -24.765 4.445)
			(end -24.543 4.445)
			(stroke
				(width 0.4445)
				(type solid)
			)
			(fill no)
			(layer "B.Paste")
		)
		(fp_circle
			(center 24.765 5.715)
			(end 24.987 5.715)
			(stroke
				(width 0.4445)
				(type solid)
			)
			(fill no)
			(layer "B.Paste")
		)
		(fp_circle
			(center 23.495 5.715)
			(end 23.717 5.715)
			(stroke
				(width 0.4445)
				(type solid)
			)
			(fill no)
			(layer "B.Paste")
		)
		(fp_circle
			(center 22.225 5.715)
			(end 22.447 5.715)
			(stroke
				(width 0.4445)
				(type solid)
			)
			(fill no)
			(layer "B.Paste")
		)
		(fp_circle
			(center 20.955 5.715)
			(end 21.177 5.715)
			(stroke
				(width 0.4445)
				(type solid)
			)
			(fill no)
			(layer "B.Paste")
		)
		(fp_circle
			(center 19.685 5.715)
			(end 19.907 5.715)
			(stroke
				(width 0.4445)
				(type solid)
			)
			(fill no)
			(layer "B.Paste")
		)
		(fp_circle
			(center 18.415 5.715)
			(end 18.637 5.715)
			(stroke
				(width 0.4445)
				(type solid)
			)
			(fill no)
			(layer "B.Paste")
		)
		(fp_circle
			(center 17.145 5.715)
			(end 17.367 5.715)
			(stroke
				(width 0.4445)
				(type solid)
			)
			(fill no)
			(layer "B.Paste")
		)
		(fp_circle
			(center 15.875 5.715)
			(end 16.097 5.715)
			(stroke
				(width 0.4445)
				(type solid)
			)
			(fill no)
			(layer "B.Paste")
		)
		(fp_circle
			(center 14.605 5.715)
			(end 14.827 5.715)
			(stroke
				(width 0.4445)
				(type solid)
			)
			(fill no)
			(layer "B.Paste")
		)
		(fp_circle
			(center 13.335 5.715)
			(end 13.557 5.715)
			(stroke
				(width 0.4445)
				(type solid)
			)
			(fill no)
			(layer "B.Paste")
		)
		(fp_circle
			(center 12.065 5.715)
			(end 12.287 5.715)
			(stroke
				(width 0.4445)
				(type solid)
			)
			(fill no)
			(layer "B.Paste")
		)
		(fp_circle
			(center 10.795 5.715)
			(end 11.017 5.715)
			(stroke
				(width 0.4445)
				(type solid)
			)
			(fill no)
			(layer "B.Paste")
		)
		(fp_circle
			(center 9.525 5.715)
			(end 9.747 5.715)
			(stroke
				(width 0.4445)
				(type solid)
			)
			(fill no)
			(layer "B.Paste")
		)
		(fp_circle
			(center 8.255 5.715)
			(end 8.477 5.715)
			(stroke
				(width 0.4445)
				(type solid)
			)
			(fill no)
			(layer "B.Paste")
		)
		(fp_circle
			(center 6.985 5.715)
			(end 7.207 5.715)
			(stroke
				(width 0.4445)
				(type solid)
			)
			(fill no)
			(layer "B.Paste")
		)
		(fp_circle
			(center 5.715 5.715)
			(end 5.937 5.715)
			(stroke
				(width 0.4445)
				(type solid)
			)
			(fill no)
			(layer "B.Paste")
		)
		(fp_circle
			(center 4.445 5.715)
			(end 4.667 5.715)
			(stroke
				(width 0.4445)
				(type solid)
			)
			(fill no)
			(layer "B.Paste")
		)
		(fp_circle
			(center 3.175 5.715)
			(end 3.397 5.715)
			(stroke
				(width 0.4445)
				(type solid)
			)
			(fill no)
			(layer "B.Paste")
		)
		(fp_circle
			(center 1.905 5.715)
			(end 2.127 5.715)
			(stroke
				(width 0.4445)
				(type solid)
			)
			(fill no)
			(layer "B.Paste")
		)
		(fp_circle
			(center 0.635 5.715)
			(end 0.857 5.715)
			(stroke
				(width 0.4445)
				(type solid)
			)
			(fill no)
			(layer "B.Paste")
		)
		(fp_circle
			(center -0.635 5.715)
			(end -0.413 5.715)
			(stroke
				(width 0.4445)
				(type solid)
			)
			(fill no)
			(layer "B.Paste")
		)
		(fp_circle
			(center -1.905 5.715)
			(end -1.683 5.715)
			(stroke
				(width 0.4445)
				(type solid)
			)
			(fill no)
			(layer "B.Paste")
		)
		(fp_circle
			(center -3.175 5.715)
			(end -2.953 5.715)
			(stroke
				(width 0.4445)
				(type solid)
			)
			(fill no)
			(layer "B.Paste")
		)
		(fp_circle
			(center -4.445 5.715)
			(end -4.223 5.715)
			(stroke
				(width 0.4445)
				(type solid)
			)
			(fill no)
			(layer "B.Paste")
		)
		(fp_circle
			(center -5.715 5.715)
			(end -5.493 5.715)
			(stroke
				(width 0.4445)
				(type solid)
			)
			(fill no)
			(layer "B.Paste")
		)
		(fp_circle
			(center -6.985 5.715)
			(end -6.763 5.715)
			(stroke
				(width 0.4445)
				(type solid)
			)
			(fill no)
			(layer "B.Paste")
		)
		(fp_circle
			(center -8.255 5.715)
			(end -8.033 5.715)
			(stroke
				(width 0.4445)
				(type solid)
			)
			(fill no)
			(layer "B.Paste")
		)
		(fp_circle
			(center -9.525 5.715)
			(end -9.303 5.715)
			(stroke
				(width 0.4445)
				(type solid)
			)
			(fill no)
			(layer "B.Paste")
		)
		(fp_circle
			(center -10.795 5.715)
			(end -10.573 5.715)
			(stroke
				(width 0.4445)
				(type solid)
			)
			(fill no)
			(layer "B.Paste")
		)
		(fp_circle
			(center -12.065 5.715)
			(end -11.843 5.715)
			(stroke
				(width 0.4445)
				(type solid)
			)
			(fill no)
			(layer "B.Paste")
		)
		(fp_circle
			(center -13.335 5.715)
			(end -13.113 5.715)
			(stroke
				(width 0.4445)
				(type solid)
			)
			(fill no)
			(layer "B.Paste")
		)
		(fp_circle
			(center -14.605 5.715)
			(end -14.383 5.715)
			(stroke
				(width 0.4445)
				(type solid)
			)
			(fill no)
			(layer "B.Paste")
		)
		(fp_circle
			(center -15.875 5.715)
			(end -15.653 5.715)
			(stroke
				(width 0.4445)
				(type solid)
			)
			(fill no)
			(layer "B.Paste")
		)
		(fp_circle
			(center -17.145 5.715)
			(end -16.923 5.715)
			(stroke
				(width 0.4445)
				(type solid)
			)
			(fill no)
			(layer "B.Paste")
		)
		(fp_circle
			(center -18.415 5.715)
			(end -18.193 5.715)
			(stroke
				(width 0.4445)
				(type solid)
			)
			(fill no)
			(layer "B.Paste")
		)
		(fp_circle
			(center -19.685 5.715)
			(end -19.463 5.715)
			(stroke
				(width 0.4445)
				(type solid)
			)
			(fill no)
			(layer "B.Paste")
		)
		(fp_circle
			(center -20.955 5.715)
			(end -20.733 5.715)
			(stroke
				(width 0.4445)
				(type solid)
			)
			(fill no)
			(layer "B.Paste")
		)
		(fp_circle
			(center -22.225 5.715)
			(end -22.003 5.715)
			(stroke
				(width 0.4445)
				(type solid)
			)
			(fill no)
			(layer "B.Paste")
		)
		(fp_circle
			(center -23.495 5.715)
			(end -23.273 5.715)
			(stroke
				(width 0.4445)
				(type solid)
			)
			(fill no)
			(layer "B.Paste")
		)
		(fp_circle
			(center -24.765 5.715)
			(end -24.543 5.715)
			(stroke
				(width 0.4445)
				(type solid)
			)
			(fill no)
			(layer "B.Paste")
		)
		(fp_circle
			(center 24.765 6.985)
			(end 24.987 6.985)
			(stroke
				(width 0.4445)
				(type solid)
			)
			(fill no)
			(layer "B.Paste")
		)
		(fp_circle
			(center 23.495 6.985)
			(end 23.717 6.985)
			(stroke
				(width 0.4445)
				(type solid)
			)
			(fill no)
			(layer "B.Paste")
		)
		(fp_circle
			(center 22.225 6.985)
			(end 22.447 6.985)
			(stroke
				(width 0.4445)
				(type solid)
			)
			(fill no)
			(layer "B.Paste")
		)
		(fp_circle
			(center 20.955 6.985)
			(end 21.177 6.985)
			(stroke
				(width 0.4445)
				(type solid)
			)
			(fill no)
			(layer "B.Paste")
		)
		(fp_circle
			(center 19.685 6.985)
			(end 19.907 6.985)
			(stroke
				(width 0.4445)
				(type solid)
			)
			(fill no)
			(layer "B.Paste")
		)
		(fp_circle
			(center 18.415 6.985)
			(end 18.637 6.985)
			(stroke
				(width 0.4445)
				(type solid)
			)
			(fill no)
			(layer "B.Paste")
		)
		(fp_circle
			(center 17.145 6.985)
			(end 17.367 6.985)
			(stroke
				(width 0.4445)
				(type solid)
			)
			(fill no)
			(layer "B.Paste")
		)
		(fp_circle
			(center 15.875 6.985)
			(end 16.097 6.985)
			(stroke
				(width 0.4445)
				(type solid)
			)
			(fill no)
			(layer "B.Paste")
		)
		(fp_circle
			(center 14.605 6.985)
			(end 14.827 6.985)
			(stroke
				(width 0.4445)
				(type solid)
			)
			(fill no)
			(layer "B.Paste")
		)
		(fp_circle
			(center 13.335 6.985)
			(end 13.557 6.985)
			(stroke
				(width 0.4445)
				(type solid)
			)
			(fill no)
			(layer "B.Paste")
		)
		(fp_circle
			(center 12.065 6.985)
			(end 12.287 6.985)
			(stroke
				(width 0.4445)
				(type solid)
			)
			(fill no)
			(layer "B.Paste")
		)
		(fp_circle
			(center 10.795 6.985)
			(end 11.017 6.985)
			(stroke
				(width 0.4445)
				(type solid)
			)
			(fill no)
			(layer "B.Paste")
		)
		(fp_circle
			(center 9.525 6.985)
			(end 9.747 6.985)
			(stroke
				(width 0.4445)
				(type solid)
			)
			(fill no)
			(layer "B.Paste")
		)
		(fp_circle
			(center 8.255 6.985)
			(end 8.477 6.985)
			(stroke
				(width 0.4445)
				(type solid)
			)
			(fill no)
			(layer "B.Paste")
		)
		(fp_circle
			(center 6.985 6.985)
			(end 7.207 6.985)
			(stroke
				(width 0.4445)
				(type solid)
			)
			(fill no)
			(layer "B.Paste")
		)
		(fp_circle
			(center 5.715 6.985)
			(end 5.937 6.985)
			(stroke
				(width 0.4445)
				(type solid)
			)
			(fill no)
			(layer "B.Paste")
		)
		(fp_circle
			(center 4.445 6.985)
			(end 4.667 6.985)
			(stroke
				(width 0.4445)
				(type solid)
			)
			(fill no)
			(layer "B.Paste")
		)
		(fp_circle
			(center 3.175 6.985)
			(end 3.397 6.985)
			(stroke
				(width 0.4445)
				(type solid)
			)
			(fill no)
			(layer "B.Paste")
		)
		(fp_circle
			(center 1.905 6.985)
			(end 2.127 6.985)
			(stroke
				(width 0.4445)
				(type solid)
			)
			(fill no)
			(layer "B.Paste")
		)
		(fp_circle
			(center 0.635 6.985)
			(end 0.857 6.985)
			(stroke
				(width 0.4445)
				(type solid)
			)
			(fill no)
			(layer "B.Paste")
		)
		(fp_circle
			(center -0.635 6.985)
			(end -0.413 6.985)
			(stroke
				(width 0.4445)
				(type solid)
			)
			(fill no)
			(layer "B.Paste")
		)
		(fp_circle
			(center -1.905 6.985)
			(end -1.683 6.985)
			(stroke
				(width 0.4445)
				(type solid)
			)
			(fill no)
			(layer "B.Paste")
		)
		(fp_circle
			(center -3.175 6.985)
			(end -2.953 6.985)
			(stroke
				(width 0.4445)
				(type solid)
			)
			(fill no)
			(layer "B.Paste")
		)
		(fp_circle
			(center -4.445 6.985)
			(end -4.223 6.985)
			(stroke
				(width 0.4445)
				(type solid)
			)
			(fill no)
			(layer "B.Paste")
		)
		(fp_circle
			(center -5.715 6.985)
			(end -5.493 6.985)
			(stroke
				(width 0.4445)
				(type solid)
			)
			(fill no)
			(layer "B.Paste")
		)
		(fp_circle
			(center -6.985 6.985)
			(end -6.763 6.985)
			(stroke
				(width 0.4445)
				(type solid)
			)
			(fill no)
			(layer "B.Paste")
		)
		(fp_circle
			(center -8.255 6.985)
			(end -8.033 6.985)
			(stroke
				(width 0.4445)
				(type solid)
			)
			(fill no)
			(layer "B.Paste")
		)
		(fp_circle
			(center -9.525 6.985)
			(end -9.303 6.985)
			(stroke
				(width 0.4445)
				(type solid)
			)
			(fill no)
			(layer "B.Paste")
		)
		(fp_circle
			(center -10.795 6.985)
			(end -10.573 6.985)
			(stroke
				(width 0.4445)
				(type solid)
			)
			(fill no)
			(layer "B.Paste")
		)
		(fp_circle
			(center -12.065 6.985)
			(end -11.843 6.985)
			(stroke
				(width 0.4445)
				(type solid)
			)
			(fill no)
			(layer "B.Paste")
		)
		(fp_circle
			(center -13.335 6.985)
			(end -13.113 6.985)
			(stroke
				(width 0.4445)
				(type solid)
			)
			(fill no)
			(layer "B.Paste")
		)
		(fp_circle
			(center -14.605 6.985)
			(end -14.383 6.985)
			(stroke
				(width 0.4445)
				(type solid)
			)
			(fill no)
			(layer "B.Paste")
		)
		(fp_circle
			(center -15.875 6.985)
			(end -15.653 6.985)
			(stroke
				(width 0.4445)
				(type solid)
			)
			(fill no)
			(layer "B.Paste")
		)
		(fp_circle
			(center -17.145 6.985)
			(end -16.923 6.985)
			(stroke
				(width 0.4445)
				(type solid)
			)
			(fill no)
			(layer "B.Paste")
		)
		(fp_circle
			(center -18.415 6.985)
			(end -18.193 6.985)
			(stroke
				(width 0.4445)
				(type solid)
			)
			(fill no)
			(layer "B.Paste")
		)
		(fp_circle
			(center -19.685 6.985)
			(end -19.463 6.985)
			(stroke
				(width 0.4445)
				(type solid)
			)
			(fill no)
			(layer "B.Paste")
		)
		(fp_circle
			(center -20.955 6.985)
			(end -20.733 6.985)
			(stroke
				(width 0.4445)
				(type solid)
			)
			(fill no)
			(layer "B.Paste")
		)
		(fp_circle
			(center -22.225 6.985)
			(end -22.003 6.985)
			(stroke
				(width 0.4445)
				(type solid)
			)
			(fill no)
			(layer "B.Paste")
		)
		(fp_circle
			(center -23.495 6.985)
			(end -23.273 6.985)
			(stroke
				(width 0.4445)
				(type solid)
			)
			(fill no)
			(layer "B.Paste")
		)
		(fp_circle
			(center -24.765 6.985)
			(end -24.543 6.985)
			(stroke
				(width 0.4445)
				(type solid)
			)
			(fill no)
			(layer "B.Paste")
		)
		(fp_circle
			(center 24.765 8.255)
			(end 24.987 8.255)
			(stroke
				(width 0.4445)
				(type solid)
			)
			(fill no)
			(layer "B.Paste")
		)
		(fp_circle
			(center 23.495 8.255)
			(end 23.717 8.255)
			(stroke
				(width 0.4445)
				(type solid)
			)
			(fill no)
			(layer "B.Paste")
		)
		(fp_circle
			(center 22.225 8.255)
			(end 22.447 8.255)
			(stroke
				(width 0.4445)
				(type solid)
			)
			(fill no)
			(layer "B.Paste")
		)
		(fp_circle
			(center 20.955 8.255)
			(end 21.177 8.255)
			(stroke
				(width 0.4445)
				(type solid)
			)
			(fill no)
			(layer "B.Paste")
		)
		(fp_circle
			(center 19.685 8.255)
			(end 19.907 8.255)
			(stroke
				(width 0.4445)
				(type solid)
			)
			(fill no)
			(layer "B.Paste")
		)
		(fp_circle
			(center 18.415 8.255)
			(end 18.637 8.255)
			(stroke
				(width 0.4445)
				(type solid)
			)
			(fill no)
			(layer "B.Paste")
		)
		(fp_circle
			(center 17.145 8.255)
			(end 17.367 8.255)
			(stroke
				(width 0.4445)
				(type solid)
			)
			(fill no)
			(layer "B.Paste")
		)
		(fp_circle
			(center 15.875 8.255)
			(end 16.097 8.255)
			(stroke
				(width 0.4445)
				(type solid)
			)
			(fill no)
			(layer "B.Paste")
		)
		(fp_circle
			(center 14.605 8.255)
			(end 14.827 8.255)
			(stroke
				(width 0.4445)
				(type solid)
			)
			(fill no)
			(layer "B.Paste")
		)
		(fp_circle
			(center 13.335 8.255)
			(end 13.557 8.255)
			(stroke
				(width 0.4445)
				(type solid)
			)
			(fill no)
			(layer "B.Paste")
		)
		(fp_circle
			(center 12.065 8.255)
			(end 12.287 8.255)
			(stroke
				(width 0.4445)
				(type solid)
			)
			(fill no)
			(layer "B.Paste")
		)
		(fp_circle
			(center 10.795 8.255)
			(end 11.017 8.255)
			(stroke
				(width 0.4445)
				(type solid)
			)
			(fill no)
			(layer "B.Paste")
		)
		(fp_circle
			(center 9.525 8.255)
			(end 9.747 8.255)
			(stroke
				(width 0.4445)
				(type solid)
			)
			(fill no)
			(layer "B.Paste")
		)
		(fp_circle
			(center 8.255 8.255)
			(end 8.477 8.255)
			(stroke
				(width 0.4445)
				(type solid)
			)
			(fill no)
			(layer "B.Paste")
		)
		(fp_circle
			(center 6.985 8.255)
			(end 7.207 8.255)
			(stroke
				(width 0.4445)
				(type solid)
			)
			(fill no)
			(layer "B.Paste")
		)
		(fp_circle
			(center 5.715 8.255)
			(end 5.937 8.255)
			(stroke
				(width 0.4445)
				(type solid)
			)
			(fill no)
			(layer "B.Paste")
		)
		(fp_circle
			(center 4.445 8.255)
			(end 4.667 8.255)
			(stroke
				(width 0.4445)
				(type solid)
			)
			(fill no)
			(layer "B.Paste")
		)
		(fp_circle
			(center 3.175 8.255)
			(end 3.397 8.255)
			(stroke
				(width 0.4445)
				(type solid)
			)
			(fill no)
			(layer "B.Paste")
		)
		(fp_circle
			(center 1.905 8.255)
			(end 2.127 8.255)
			(stroke
				(width 0.4445)
				(type solid)
			)
			(fill no)
			(layer "B.Paste")
		)
		(fp_circle
			(center 0.635 8.255)
			(end 0.857 8.255)
			(stroke
				(width 0.4445)
				(type solid)
			)
			(fill no)
			(layer "B.Paste")
		)
		(fp_circle
			(center -0.635 8.255)
			(end -0.413 8.255)
			(stroke
				(width 0.4445)
				(type solid)
			)
			(fill no)
			(layer "B.Paste")
		)
		(fp_circle
			(center -1.905 8.255)
			(end -1.683 8.255)
			(stroke
				(width 0.4445)
				(type solid)
			)
			(fill no)
			(layer "B.Paste")
		)
		(fp_circle
			(center -3.175 8.255)
			(end -2.953 8.255)
			(stroke
				(width 0.4445)
				(type solid)
			)
			(fill no)
			(layer "B.Paste")
		)
		(fp_circle
			(center -4.445 8.255)
			(end -4.223 8.255)
			(stroke
				(width 0.4445)
				(type solid)
			)
			(fill no)
			(layer "B.Paste")
		)
		(fp_circle
			(center -5.715 8.255)
			(end -5.493 8.255)
			(stroke
				(width 0.4445)
				(type solid)
			)
			(fill no)
			(layer "B.Paste")
		)
		(fp_circle
			(center -6.985 8.255)
			(end -6.763 8.255)
			(stroke
				(width 0.4445)
				(type solid)
			)
			(fill no)
			(layer "B.Paste")
		)
		(fp_circle
			(center -8.255 8.255)
			(end -8.033 8.255)
			(stroke
				(width 0.4445)
				(type solid)
			)
			(fill no)
			(layer "B.Paste")
		)
		(fp_circle
			(center -9.525 8.255)
			(end -9.303 8.255)
			(stroke
				(width 0.4445)
				(type solid)
			)
			(fill no)
			(layer "B.Paste")
		)
		(fp_circle
			(center -10.795 8.255)
			(end -10.573 8.255)
			(stroke
				(width 0.4445)
				(type solid)
			)
			(fill no)
			(layer "B.Paste")
		)
		(fp_circle
			(center -12.065 8.255)
			(end -11.843 8.255)
			(stroke
				(width 0.4445)
				(type solid)
			)
			(fill no)
			(layer "B.Paste")
		)
		(fp_circle
			(center -13.335 8.255)
			(end -13.113 8.255)
			(stroke
				(width 0.4445)
				(type solid)
			)
			(fill no)
			(layer "B.Paste")
		)
		(fp_circle
			(center -14.605 8.255)
			(end -14.383 8.255)
			(stroke
				(width 0.4445)
				(type solid)
			)
			(fill no)
			(layer "B.Paste")
		)
		(fp_circle
			(center -15.875 8.255)
			(end -15.653 8.255)
			(stroke
				(width 0.4445)
				(type solid)
			)
			(fill no)
			(layer "B.Paste")
		)
		(fp_circle
			(center -17.145 8.255)
			(end -16.923 8.255)
			(stroke
				(width 0.4445)
				(type solid)
			)
			(fill no)
			(layer "B.Paste")
		)
		(fp_circle
			(center -18.415 8.255)
			(end -18.193 8.255)
			(stroke
				(width 0.4445)
				(type solid)
			)
			(fill no)
			(layer "B.Paste")
		)
		(fp_circle
			(center -19.685 8.255)
			(end -19.463 8.255)
			(stroke
				(width 0.4445)
				(type solid)
			)
			(fill no)
			(layer "B.Paste")
		)
		(fp_circle
			(center -20.955 8.255)
			(end -20.733 8.255)
			(stroke
				(width 0.4445)
				(type solid)
			)
			(fill no)
			(layer "B.Paste")
		)
		(fp_circle
			(center -22.225 8.255)
			(end -22.003 8.255)
			(stroke
				(width 0.4445)
				(type solid)
			)
			(fill no)
			(layer "B.Paste")
		)
		(fp_circle
			(center -23.495 8.255)
			(end -23.273 8.255)
			(stroke
				(width 0.4445)
				(type solid)
			)
			(fill no)
			(layer "B.Paste")
		)
		(fp_circle
			(center -24.765 8.255)
			(end -24.543 8.255)
			(stroke
				(width 0.4445)
				(type solid)
			)
			(fill no)
			(layer "B.Paste")
		)
		(fp_rect
			(start -35.5 11.52)
			(end 35.5 -11.52)
			(stroke
				(width 0.05)
				(type solid)
			)
			(fill no)
			(layer "B.CrtYd")
		)
		(fp_line
			(start 27.889 -9.88)
			(end -27.889 -9.88)
			(stroke
				(width 0.15)
				(type solid)
			)
			(layer "B.Fab")
		)
		(fp_line
			(start -27.889 -9.88)
			(end -27.889 9.88)
			(stroke
				(width 0.15)
				(type solid)
			)
			(layer "B.Fab")
		)
		(fp_line
			(start 28.779 -0.76)
			(end 27.889 -0.76)
			(stroke
				(width 0.15)
				(type solid)
			)
			(layer "B.Fab")
		)
		(fp_line
			(start 27.889 -0.76)
			(end 27.889 -9.88)
			(stroke
				(width 0.15)
				(type solid)
			)
			(layer "B.Fab")
		)
		(fp_line
			(start 28.779 0.76)
			(end 28.779 -0.76)
			(stroke
				(width 0.15)
				(type solid)
			)
			(layer "B.Fab")
		)
		(fp_line
			(start 27.889 0.76)
			(end 28.779 0.76)
			(stroke
				(width 0.15)
				(type solid)
			)
			(layer "B.Fab")
		)
		(fp_line
			(start 27.889 9.88)
			(end 27.889 0.76)
			(stroke
				(width 0.15)
				(type solid)
			)
			(layer "B.Fab")
		)
		(fp_line
			(start -27.889 9.88)
			(end 27.889 9.88)
			(stroke
				(width 0.15)
				(type solid)
			)
			(layer "B.Fab")
		)
		(fp_circle
			(center 28.5 8.255)
			(end 28.6 8.255)
			(stroke
				(width 0.15)
				(type solid)
			)
			(fill no)
			(layer "B.Fab")
		)
		(fp_text user "${REFERENCE}"
			(at -35.5 -13.52 270)
			(layer "B.Fab")
			(effects
				(font
					(size 0.7 0.7)
					(thickness 0.15)
				)
				(justify left bottom mirror)
			)
		)
		(fp_text user "Author: Antmicro"
			(at -35.5 -14.72 270)
			(layer "B.Fab")
			(effects
				(font
					(size 0.7 0.7)
					(thickness 0.15)
				)
				(justify left bottom mirror)
			)
		)
		(fp_text user "License: Apache-2.0"
			(at -35.5 -15.92 270)
			(layer "B.Fab")
			(effects
				(font
					(size 0.7 0.7)
					(thickness 0.15)
				)
				(justify left bottom mirror)
			)
		)
		(pad "" np_thru_hole circle
			(at -31.5 -1.88 90)
			(size 6 6)
			(drill 3.2)
			(layers "*.Cu" "*.Mask")
		)
		(pad "" np_thru_hole circle
			(at -27.19 -3.05 90)
			(size 1.27 1.27)
			(drill 1.27)
			(layers "*.Cu" "*.Mask")
		)
		(pad "" np_thru_hole circle
			(at 27.19 0 90)
			(size 1.27 1.27)
			(drill 1.27)
			(layers "*.Cu" "*.Mask")
		)
		(pad "" np_thru_hole circle
			(at 31.5 -1.84 90)
			(size 6 6)
			(drill 3.2)
			(layers "*.Cu" "*.Mask")
		)
		(pad "A01" smd circle
			(at 24.765 5.715 90)
			(size 0.64 0.64)
			(layers "B.Cu" "B.Mask")
			(net 1 "GND")
			(pinfunction "A01")
			(pintype "passive")
		)
		(pad "A02" smd circle
			(at 23.495 5.715 90)
			(size 0.64 0.64)
			(layers "B.Cu" "B.Mask")
			(net 656 "/Expansion connector/DP2.AUX-")
			(pinfunction "A02")
			(pintype "passive")
		)
		(pad "A03" smd circle
			(at 22.225 5.715 90)
			(size 0.64 0.64)
			(layers "B.Cu" "B.Mask")
			(net 572 "/Expansion connector/DP2.AUX+")
			(pinfunction "A03")
			(pintype "passive")
		)
		(pad "A04" smd circle
			(at 20.955 5.715 90)
			(size 0.64 0.64)
			(layers "B.Cu" "B.Mask")
			(net 1 "GND")
			(pinfunction "A04")
			(pintype "passive")
		)
		(pad "A05" smd circle
			(at 19.685 5.715 90)
			(size 0.64 0.64)
			(layers "B.Cu" "B.Mask")
			(net 1 "GND")
			(pinfunction "A05")
			(pintype "passive")
		)
		(pad "A06" smd circle
			(at 18.415 5.715 90)
			(size 0.64 0.64)
			(layers "B.Cu" "B.Mask")
			(net 737 "/Expansion connector/DP2.TX0-")
			(pinfunction "A06")
			(pintype "passive")
		)
		(pad "A07" smd circle
			(at 17.145 5.715 90)
			(size 0.64 0.64)
			(layers "B.Cu" "B.Mask")
			(net 591 "/Expansion connector/DP2.TX0+")
			(pinfunction "A07")
			(pintype "passive")
		)
		(pad "A08" smd circle
			(at 15.875 5.715 90)
			(size 0.64 0.64)
			(layers "B.Cu" "B.Mask")
			(net 1 "GND")
			(pinfunction "A08")
			(pintype "passive")
		)
		(pad "A09" smd circle
			(at 14.605 5.715 90)
			(size 0.64 0.64)
			(layers "B.Cu" "B.Mask")
			(net 1 "GND")
			(pinfunction "A09")
			(pintype "passive")
		)
		(pad "A10" smd circle
			(at 13.335 5.715 90)
			(size 0.64 0.64)
			(layers "B.Cu" "B.Mask")
			(net 744 "/Expansion connector/DP2.TX1-")
			(pinfunction "A10")
			(pintype "passive")
		)
		(pad "A11" smd circle
			(at 12.065 5.715 90)
			(size 0.64 0.64)
			(layers "B.Cu" "B.Mask")
			(net 726 "/Expansion connector/DP2.TX1+")
			(pinfunction "A11")
			(pintype "passive")
		)
		(pad "A12" smd circle
			(at 10.795 5.715 90)
			(size 0.64 0.64)
			(layers "B.Cu" "B.Mask")
			(net 1 "GND")
			(pinfunction "A12")
			(pintype "passive")
		)
		(pad "A13" smd circle
			(at 9.525 5.715 90)
			(size 0.64 0.64)
			(layers "B.Cu" "B.Mask")
			(net 1 "GND")
			(pinfunction "A13")
			(pintype "passive")
		)
		(pad "A14" smd circle
			(at 8.255 5.715 90)
			(size 0.64 0.64)
			(layers "B.Cu" "B.Mask")
			(net 742 "/Expansion connector/DP2.TX2-")
			(pinfunction "A14")
			(pintype "passive")
		)
		(pad "A15" smd circle
			(at 6.985 5.715 90)
			(size 0.64 0.64)
			(layers "B.Cu" "B.Mask")
			(net 756 "/Expansion connector/DP2.TX2+")
			(pinfunction "A15")
			(pintype "passive")
		)
		(pad "A16" smd circle
			(at 5.715 5.715 90)
			(size 0.64 0.64)
			(layers "B.Cu" "B.Mask")
			(net 1 "GND")
			(pinfunction "A16")
			(pintype "passive")
		)
		(pad "A17" smd circle
			(at 4.445 5.715 90)
			(size 0.64 0.64)
			(layers "B.Cu" "B.Mask")
			(net 1 "GND")
			(pinfunction "A17")
			(pintype "passive")
		)
		(pad "A18" smd circle
			(at 3.175 5.715 90)
			(size 0.64 0.64)
			(layers "B.Cu" "B.Mask")
			(net 631 "/Expansion connector/DP2.TX3-")
			(pinfunction "A18")
			(pintype "passive")
		)
		(pad "A19" smd circle
			(at 1.905 5.715 90)
			(size 0.64 0.64)
			(layers "B.Cu" "B.Mask")
			(net 640 "/Expansion connector/DP2.TX3+")
			(pinfunction "A19")
			(pintype "passive")
		)
		(pad "A20" smd circle
			(at 0.635 5.715 90)
			(size 0.64 0.64)
			(layers "B.Cu" "B.Mask")
			(net 1 "GND")
			(pinfunction "A20")
			(pintype "passive")
		)
		(pad "A21" smd circle
			(at -0.635 5.715 90)
			(size 0.64 0.64)
			(layers "B.Cu" "B.Mask")
			(net 1 "GND")
			(pinfunction "A21")
			(pintype "passive")
		)
		(pad "A22" smd circle
			(at -1.905 5.715 90)
			(size 0.64 0.64)
			(layers "B.Cu" "B.Mask")
			(net 482 "unconnected-(J18-PadA22)")
			(pinfunction "A22")
			(pintype "passive+no_connect")
		)
		(pad "A23" smd circle
			(at -3.175 5.715 90)
			(size 0.64 0.64)
			(layers "B.Cu" "B.Mask")
			(net 483 "unconnected-(J18-PadA23)")
			(pinfunction "A23")
			(pintype "passive+no_connect")
		)
		(pad "A24" smd circle
			(at -4.445 5.715 90)
			(size 0.64 0.64)
			(layers "B.Cu" "B.Mask")
			(net 1 "GND")
			(pinfunction "A24")
			(pintype "passive")
		)
		(pad "A25" smd circle
			(at -5.715 5.715 90)
			(size 0.64 0.64)
			(layers "B.Cu" "B.Mask")
			(net 1 "GND")
			(pinfunction "A25")
			(pintype "passive")
		)
		(pad "A26" smd circle
			(at -6.985 5.715 90)
			(size 0.64 0.64)
			(layers "B.Cu" "B.Mask")
			(net 375 "unconnected-(J18-PadA26)")
			(pinfunction "A26")
			(pintype "passive+no_connect")
		)
		(pad "A27" smd circle
			(at -8.255 5.715 90)
			(size 0.64 0.64)
			(layers "B.Cu" "B.Mask")
			(net 590 "unconnected-(J18-PadA27)")
			(pinfunction "A27")
			(pintype "passive+no_connect")
		)
		(pad "A28" smd circle
			(at -9.525 5.715 90)
			(size 0.64 0.64)
			(layers "B.Cu" "B.Mask")
			(net 1 "GND")
			(pinfunction "A28")
			(pintype "passive")
		)
		(pad "A29" smd circle
			(at -10.795 5.715 90)
			(size 0.64 0.64)
			(layers "B.Cu" "B.Mask")
			(net 1 "GND")
			(pinfunction "A29")
			(pintype "passive")
		)
		(pad "A30" smd circle
			(at -12.065 5.715 90)
			(size 0.64 0.64)
			(layers "B.Cu" "B.Mask")
			(net 480 "unconnected-(J18-PadA30)")
			(pinfunction "A30")
			(pintype "passive+no_connect")
		)
		(pad "A31" smd circle
			(at -13.335 5.715 90)
			(size 0.64 0.64)
			(layers "B.Cu" "B.Mask")
			(net 719 "unconnected-(J18-PadA31)")
			(pinfunction "A31")
			(pintype "passive+no_connect")
		)
		(pad "A32" smd circle
			(at -14.605 5.715 90)
			(size 0.64 0.64)
			(layers "B.Cu" "B.Mask")
			(net 1 "GND")
			(pinfunction "A32")
			(pintype "passive")
		)
		(pad "A33" smd circle
			(at -15.875 5.715 90)
			(size 0.64 0.64)
			(layers "B.Cu" "B.Mask")
			(net 1 "GND")
			(pinfunction "A33")
			(pintype "passive")
		)
		(pad "A34" smd circle
			(at -17.145 5.715 90)
			(size 0.64 0.64)
			(layers "B.Cu" "B.Mask")
			(net 599 "unconnected-(J18-PadA34)")
			(pinfunction "A34")
			(pintype "passive+no_connect")
		)
		(pad "A35" smd circle
			(at -18.415 5.715 90)
			(size 0.64 0.64)
			(layers "B.Cu" "B.Mask")
			(net 349 "unconnected-(J18-PadA35)")
			(pinfunction "A35")
			(pintype "passive+no_connect")
		)
		(pad "A36" smd circle
			(at -19.685 5.715 90)
			(size 0.64 0.64)
			(layers "B.Cu" "B.Mask")
			(net 1 "GND")
			(pinfunction "A36")
			(pintype "passive")
		)
		(pad "A37" smd circle
			(at -20.955 5.715 90)
			(size 0.64 0.64)
			(layers "B.Cu" "B.Mask")
			(net 1 "GND")
			(pinfunction "A37")
			(pintype "passive")
		)
		(pad "A38" smd circle
			(at -22.225 5.715 90)
			(size 0.64 0.64)
			(layers "B.Cu" "B.Mask")
			(net 685 "unconnected-(J18-PadA38)")
			(pinfunction "A38")
			(pintype "passive+no_connect")
		)
		(pad "A39" smd circle
			(at -23.495 5.715 90)
			(size 0.64 0.64)
			(layers "B.Cu" "B.Mask")
			(net 650 "unconnected-(J18-PadA39)")
			(pinfunction "A39")
			(pintype "passive+no_connect")
		)
		(pad "A40" smd circle
			(at -24.765 5.715 90)
			(size 0.64 0.64)
			(layers "B.Cu" "B.Mask")
			(net 1 "GND")
			(pinfunction "A40")
			(pintype "passive")
		)
		(pad "B01" smd circle
			(at 24.765 4.445 90)
			(size 0.64 0.64)
			(layers "B.Cu" "B.Mask")
			(net 659 "Net-(J18-PadB01)")
			(pinfunction "B01")
			(pintype "passive")
		)
		(pad "B02" smd circle
			(at 23.495 4.445 90)
			(size 0.64 0.64)
			(layers "B.Cu" "B.Mask")
			(net 1 "GND")
			(pinfunction "B02")
			(pintype "passive")
		)
		(pad "B03" smd circle
			(at 22.225 4.445 90)
			(size 0.64 0.64)
			(layers "B.Cu" "B.Mask")
			(net 1 "GND")
			(pinfunction "B03")
			(pintype "passive")
		)
		(pad "B04" smd circle
			(at 20.955 4.445 90)
			(size 0.64 0.64)
			(layers "B.Cu" "B.Mask")
			(net 648 "/Expansion connector/DP3.TX3+")
			(pinfunction "B04")
			(pintype "passive")
		)
		(pad "B05" smd circle
			(at 19.685 4.445 90)
			(size 0.64 0.64)
			(layers "B.Cu" "B.Mask")
			(net 661 "/Expansion connector/DP3.TX3-")
			(pinfunction "B05")
			(pintype "passive")
		)
		(pad "B06" smd circle
			(at 18.415 4.445 90)
			(size 0.64 0.64)
			(layers "B.Cu" "B.Mask")
			(net 1 "GND")
			(pinfunction "B06")
			(pintype "passive")
		)
		(pad "B07" smd circle
			(at 17.145 4.445 90)
			(size 0.64 0.64)
			(layers "B.Cu" "B.Mask")
			(net 1 "GND")
			(pinfunction "B07")
			(pintype "passive")
		)
		(pad "B08" smd circle
			(at 15.875 4.445 90)
			(size 0.64 0.64)
			(layers "B.Cu" "B.Mask")
			(net 593 "/Expansion connector/DP3.TX2+")
			(pinfunction "B08")
			(pintype "passive")
		)
		(pad "B09" smd circle
			(at 14.605 4.445 90)
			(size 0.64 0.64)
			(layers "B.Cu" "B.Mask")
			(net 680 "/Expansion connector/DP3.TX2-")
			(pinfunction "B09")
			(pintype "passive")
		)
		(pad "B10" smd circle
			(at 13.335 4.445 90)
			(size 0.64 0.64)
			(layers "B.Cu" "B.Mask")
			(net 1 "GND")
			(pinfunction "B10")
			(pintype "passive")
		)
		(pad "B11" smd circle
			(at 12.065 4.445 90)
			(size 0.64 0.64)
			(layers "B.Cu" "B.Mask")
			(net 1 "GND")
			(pinfunction "B11")
			(pintype "passive")
		)
		(pad "B12" smd circle
			(at 10.795 4.445 90)
			(size 0.64 0.64)
			(layers "B.Cu" "B.Mask")
			(net 736 "/Expansion connector/DP3.TX1+")
			(pinfunction "B12")
			(pintype "passive")
		)
		(pad "B13" smd circle
			(at 9.525 4.445 90)
			(size 0.64 0.64)
			(layers "B.Cu" "B.Mask")
			(net 675 "/Expansion connector/DP3.TX1-")
			(pinfunction "B13")
			(pintype "passive")
		)
		(pad "B14" smd circle
			(at 8.255 4.445 90)
			(size 0.64 0.64)
			(layers "B.Cu" "B.Mask")
			(net 1 "GND")
			(pinfunction "B14")
			(pintype "passive")
		)
		(pad "B15" smd circle
			(at 6.985 4.445 90)
			(size 0.64 0.64)
			(layers "B.Cu" "B.Mask")
			(net 1 "GND")
			(pinfunction "B15")
			(pintype "passive")
		)
		(pad "B16" smd circle
			(at 5.715 4.445 90)
			(size 0.64 0.64)
			(layers "B.Cu" "B.Mask")
			(net 691 "/Expansion connector/DP3.TX0+")
			(pinfunction "B16")
			(pintype "passive")
		)
		(pad "B17" smd circle
			(at 4.445 4.445 90)
			(size 0.64 0.64)
			(layers "B.Cu" "B.Mask")
			(net 665 "/Expansion connector/DP3.TX0-")
			(pinfunction "B17")
			(pintype "passive")
		)
		(pad "B18" smd circle
			(at 3.175 4.445 90)
			(size 0.64 0.64)
			(layers "B.Cu" "B.Mask")
			(net 1 "GND")
			(pinfunction "B18")
			(pintype "passive")
		)
		(pad "B19" smd circle
			(at 1.905 4.445 90)
			(size 0.64 0.64)
			(layers "B.Cu" "B.Mask")
			(net 1 "GND")
			(pinfunction "B19")
			(pintype "passive")
		)
		(pad "B20" smd circle
			(at 0.635 4.445 90)
			(size 0.64 0.64)
			(layers "B.Cu" "B.Mask")
			(net 776 "/Expansion connector/DP3.AUX+")
			(pinfunction "B20")
			(pintype "passive")
		)
		(pad "B21" smd circle
			(at -0.635 4.445 90)
			(size 0.64 0.64)
			(layers "B.Cu" "B.Mask")
			(net 657 "/Expansion connector/DP3.AUX-")
			(pinfunction "B21")
			(pintype "passive")
		)
		(pad "B22" smd circle
			(at -1.905 4.445 90)
			(size 0.64 0.64)
			(layers "B.Cu" "B.Mask")
			(net 1 "GND")
			(pinfunction "B22")
			(pintype "passive")
		)
		(pad "B23" smd circle
			(at -3.175 4.445 90)
			(size 0.64 0.64)
			(layers "B.Cu" "B.Mask")
			(net 1 "GND")
			(pinfunction "B23")
			(pintype "passive")
		)
		(pad "B24" smd circle
			(at -4.445 4.445 90)
			(size 0.64 0.64)
			(layers "B.Cu" "B.Mask")
			(net 784 "unconnected-(J18-PadB24)")
			(pinfunction "B24")
			(pintype "passive+no_connect")
		)
		(pad "B25" smd circle
			(at -5.715 4.445 90)
			(size 0.64 0.64)
			(layers "B.Cu" "B.Mask")
			(net 841 "unconnected-(J18-PadB25)")
			(pinfunction "B25")
			(pintype "passive+no_connect")
		)
		(pad "B26" smd circle
			(at -6.985 4.445 90)
			(size 0.64 0.64)
			(layers "B.Cu" "B.Mask")
			(net 1 "GND")
			(pinfunction "B26")
			(pintype "passive")
		)
		(pad "B27" smd circle
			(at -8.255 4.445 90)
			(size 0.64 0.64)
			(layers "B.Cu" "B.Mask")
			(net 1 "GND")
			(pinfunction "B27")
			(pintype "passive")
		)
		(pad "B28" smd circle
			(at -9.525 4.445 90)
			(size 0.64 0.64)
			(layers "B.Cu" "B.Mask")
			(net 313 "unconnected-(J18-PadB28)")
			(pinfunction "B28")
			(pintype "passive+no_connect")
		)
		(pad "B29" smd circle
			(at -10.795 4.445 90)
			(size 0.64 0.64)
			(layers "B.Cu" "B.Mask")
			(net 340 "unconnected-(J18-PadB29)")
			(pinfunction "B29")
			(pintype "passive+no_connect")
		)
		(pad "B30" smd circle
			(at -12.065 4.445 90)
			(size 0.64 0.64)
			(layers "B.Cu" "B.Mask")
			(net 1 "GND")
			(pinfunction "B30")
			(pintype "passive")
		)
		(pad "B31" smd circle
			(at -13.335 4.445 90)
			(size 0.64 0.64)
			(layers "B.Cu" "B.Mask")
			(net 1 "GND")
			(pinfunction "B31")
			(pintype "passive")
		)
		(pad "B32" smd circle
			(at -14.605 4.445 90)
			(size 0.64 0.64)
			(layers "B.Cu" "B.Mask")
			(net 443 "unconnected-(J18-PadB32)")
			(pinfunction "B32")
			(pintype "passive+no_connect")
		)
		(pad "B33" smd circle
			(at -15.875 4.445 90)
			(size 0.64 0.64)
			(layers "B.Cu" "B.Mask")
			(net 397 "unconnected-(J18-PadB33)")
			(pinfunction "B33")
			(pintype "passive+no_connect")
		)
		(pad "B34" smd circle
			(at -17.145 4.445 90)
			(size 0.64 0.64)
			(layers "B.Cu" "B.Mask")
			(net 1 "GND")
			(pinfunction "B34")
			(pintype "passive")
		)
		(pad "B35" smd circle
			(at -18.415 4.445 90)
			(size 0.64 0.64)
			(layers "B.Cu" "B.Mask")
			(net 1 "GND")
			(pinfunction "B35")
			(pintype "passive")
		)
		(pad "B36" smd circle
			(at -19.685 4.445 90)
			(size 0.64 0.64)
			(layers "B.Cu" "B.Mask")
			(net 473 "unconnected-(J18-PadB36)")
			(pinfunction "B36")
			(pintype "passive+no_connect")
		)
		(pad "B37" smd circle
			(at -20.955 4.445 90)
			(size 0.64 0.64)
			(layers "B.Cu" "B.Mask")
			(net 422 "unconnected-(J18-PadB37)")
			(pinfunction "B37")
			(pintype "passive+no_connect")
		)
		(pad "B38" smd circle
			(at -22.225 4.445 90)
			(size 0.64 0.64)
			(layers "B.Cu" "B.Mask")
			(net 1 "GND")
			(pinfunction "B38")
			(pintype "passive")
		)
		(pad "B39" smd circle
			(at -23.495 4.445 90)
			(size 0.64 0.64)
			(layers "B.Cu" "B.Mask")
			(net 1 "GND")
			(pinfunction "B39")
			(pintype "passive")
		)
		(pad "B40" smd circle
			(at -24.765 4.445 90)
			(size 0.64 0.64)
			(layers "B.Cu" "B.Mask")
			(net 777 "Net-(J18-PadB40)")
			(pinfunction "B40")
			(pintype "passive")
		)
		(pad "C01" smd circle
			(at 24.765 3.175 90)
			(size 0.64 0.64)
			(layers "B.Cu" "B.Mask")
			(net 1 "GND")
			(pinfunction "C01")
			(pintype "passive")
		)
		(pad "C02" smd circle
			(at 23.495 3.175 90)
			(size 0.64 0.64)
			(layers "B.Cu" "B.Mask")
			(net 428 "unconnected-(J18-PadC02)")
			(pinfunction "C02")
			(pintype "passive+no_connect")
		)
		(pad "C03" smd circle
			(at 22.225 3.175 90)
			(size 0.64 0.64)
			(layers "B.Cu" "B.Mask")
			(net 357 "unconnected-(J18-PadC03)")
			(pinfunction "C03")
			(pintype "passive+no_connect")
		)
		(pad "C04" smd circle
			(at 20.955 3.175 90)
			(size 0.64 0.64)
			(layers "B.Cu" "B.Mask")
			(net 1 "GND")
			(pinfunction "C04")
			(pintype "passive")
		)
		(pad "C05" smd circle
			(at 19.685 3.175 90)
			(size 0.64 0.64)
			(layers "B.Cu" "B.Mask")
			(net 1 "GND")
			(pinfunction "C05")
			(pintype "passive")
		)
		(pad "C06" smd circle
			(at 18.415 3.175 90)
			(size 0.64 0.64)
			(layers "B.Cu" "B.Mask")
			(net 304 "unconnected-(J18-PadC06)")
			(pinfunction "C06")
			(pintype "passive+no_connect")
		)
		(pad "C07" smd circle
			(at 17.145 3.175 90)
			(size 0.64 0.64)
			(layers "B.Cu" "B.Mask")
			(net 412 "unconnected-(J18-PadC07)")
			(pinfunction "C07")
			(pintype "passive+no_connect")
		)
		(pad "C08" smd circle
			(at 15.875 3.175 90)
			(size 0.64 0.64)
			(layers "B.Cu" "B.Mask")
			(net 1 "GND")
			(pinfunction "C08")
			(pintype "passive")
		)
		(pad "C09" smd circle
			(at 14.605 3.175 90)
			(size 0.64 0.64)
			(layers "B.Cu" "B.Mask")
			(net 1 "GND")
			(pinfunction "C09")
			(pintype "passive")
		)
		(pad "C10" smd circle
			(at 13.335 3.175 90)
			(size 0.64 0.64)
			(layers "B.Cu" "B.Mask")
			(net 569 "/Expansion connector/PCIe_{C3x2}.~{RST}")
			(pinfunction "C10")
			(pintype "passive")
		)
		(pad "C11" smd circle
			(at 12.065 3.175 90)
			(size 0.64 0.64)
			(layers "B.Cu" "B.Mask")
			(net 565 "/Expansion connector/PCIe_{C3x2}.~{CLKREQ}")
			(pinfunction "C11")
			(pintype "passive")
		)
		(pad "C12" smd circle
			(at 10.795 3.175 90)
			(size 0.64 0.64)
			(layers "B.Cu" "B.Mask")
			(net 1 "GND")
			(pinfunction "C12")
			(pintype "passive")
		)
		(pad "C13" smd circle
			(at 9.525 3.175 90)
			(size 0.64 0.64)
			(layers "B.Cu" "B.Mask")
			(net 1 "GND")
			(pinfunction "C13")
			(pintype "passive")
		)
		(pad "C14" smd circle
			(at 8.255 3.175 90)
			(size 0.64 0.64)
			(layers "B.Cu" "B.Mask")
			(net 554 "/Expansion connector/PCIe_{C2x1}.~{RST}")
			(pinfunction "C14")
			(pintype "passive")
		)
		(pad "C15" smd circle
			(at 6.985 3.175 90)
			(size 0.64 0.64)
			(layers "B.Cu" "B.Mask")
			(net 694 "/Expansion connector/PCIe_{C2x1}.~{CLKREQ}")
			(pinfunction "C15")
			(pintype "passive")
		)
		(pad "C16" smd circle
			(at 5.715 3.175 90)
			(size 0.64 0.64)
			(layers "B.Cu" "B.Mask")
			(net 1 "GND")
			(pinfunction "C16")
			(pintype "passive")
		)
		(pad "C17" smd circle
			(at 4.445 3.175 90)
			(size 0.64 0.64)
			(layers "B.Cu" "B.Mask")
			(net 1 "GND")
			(pinfunction "C17")
			(pintype "passive")
		)
		(pad "C18" smd circle
			(at 3.175 3.175 90)
			(size 0.64 0.64)
			(layers "B.Cu" "B.Mask")
			(net 781 "/Expansion connector/DP1.HPD")
			(pinfunction "C18")
			(pintype "passive")
		)
		(pad "C19" smd circle
			(at 1.905 3.175 90)
			(size 0.64 0.64)
			(layers "B.Cu" "B.Mask")
			(net 789 "/Expansion connector/DP2.HPD")
			(pinfunction "C19")
			(pintype "passive")
		)
		(pad "C20" smd circle
			(at 0.635 3.175 90)
			(size 0.64 0.64)
			(layers "B.Cu" "B.Mask")
			(net 1 "GND")
			(pinfunction "C20")
			(pintype "passive")
		)
		(pad "C21" smd circle
			(at -0.635 3.175 90)
			(size 0.64 0.64)
			(layers "B.Cu" "B.Mask")
			(net 1 "GND")
			(pinfunction "C21")
			(pintype "passive")
		)
		(pad "C22" smd circle
			(at -1.905 3.175 90)
			(size 0.64 0.64)
			(layers "B.Cu" "B.Mask")
			(net 574 "/Expansion connector/DP3.HPD")
			(pinfunction "C22")
			(pintype "passive")
		)
		(pad "C23" smd circle
			(at -3.175 3.175 90)
			(size 0.64 0.64)
			(layers "B.Cu" "B.Mask")
			(net 321 "/Expansion connector/GPIO.MCLK03")
			(pinfunction "C23")
			(pintype "passive")
		)
		(pad "C24" smd circle
			(at -4.445 3.175 90)
			(size 0.64 0.64)
			(layers "B.Cu" "B.Mask")
			(net 1 "GND")
			(pinfunction "C24")
			(pintype "passive")
		)
		(pad "C25" smd circle
			(at -5.715 3.175 90)
			(size 0.64 0.64)
			(layers "B.Cu" "B.Mask")
			(net 1 "GND")
			(pinfunction "C25")
			(pintype "passive")
		)
		(pad "C26" smd circle
			(at -6.985 3.175 90)
			(size 0.64 0.64)
			(layers "B.Cu" "B.Mask")
			(net 368 "/Expansion connector/GPIO.21")
			(pinfunction "C26")
			(pintype "passive")
		)
		(pad "C27" smd circle
			(at -8.255 3.175 90)
			(size 0.64 0.64)
			(layers "B.Cu" "B.Mask")
			(net 861 "/Expansion connector/GPIO.27")
			(pinfunction "C27")
			(pintype "passive")
		)
		(pad "C28" smd circle
			(at -9.525 3.175 90)
			(size 0.64 0.64)
			(layers "B.Cu" "B.Mask")
			(net 1 "GND")
			(pinfunction "C28")
			(pintype "passive")
		)
		(pad "C29" smd circle
			(at -10.795 3.175 90)
			(size 0.64 0.64)
			(layers "B.Cu" "B.Mask")
			(net 1 "GND")
			(pinfunction "C29")
			(pintype "passive")
		)
		(pad "C30" smd circle
			(at -12.065 3.175 90)
			(size 0.64 0.64)
			(layers "B.Cu" "B.Mask")
			(net 407 "/Expansion connector/I2C0.SCL")
			(pinfunction "C30")
			(pintype "passive")
		)
		(pad "C31" smd circle
			(at -13.335 3.175 90)
			(size 0.64 0.64)
			(layers "B.Cu" "B.Mask")
			(net 561 "/Expansion connector/I2C0.SDA")
			(pinfunction "C31")
			(pintype "passive")
		)
		(pad "C32" smd circle
			(at -14.605 3.175 90)
			(size 0.64 0.64)
			(layers "B.Cu" "B.Mask")
			(net 1 "GND")
			(pinfunction "C32")
			(pintype "passive")
		)
		(pad "C33" smd circle
			(at -15.875 3.175 90)
			(size 0.64 0.64)
			(layers "B.Cu" "B.Mask")
			(net 1 "GND")
			(pinfunction "C33")
			(pintype "passive")
		)
		(pad "C34" smd circle
			(at -17.145 3.175 90)
			(size 0.64 0.64)
			(layers "B.Cu" "B.Mask")
			(net 677 "/Expansion connector/ADDR0")
			(pinfunction "C34")
			(pintype "passive")
		)
		(pad "C35" smd circle
			(at -18.415 3.175 90)
			(size 0.64 0.64)
			(layers "B.Cu" "B.Mask")
			(net 289 "/Expansion connector/+12V_FMC")
			(pinfunction "C35")
			(pintype "passive")
		)
		(pad "C36" smd circle
			(at -19.685 3.175 90)
			(size 0.64 0.64)
			(layers "B.Cu" "B.Mask")
			(net 1 "GND")
			(pinfunction "C36")
			(pintype "passive")
		)
		(pad "C37" smd circle
			(at -20.955 3.175 90)
			(size 0.64 0.64)
			(layers "B.Cu" "B.Mask")
			(net 289 "/Expansion connector/+12V_FMC")
			(pinfunction "C37")
			(pintype "passive")
		)
		(pad "C38" smd circle
			(at -22.225 3.175 90)
			(size 0.64 0.64)
			(layers "B.Cu" "B.Mask")
			(net 1 "GND")
			(pinfunction "C38")
			(pintype "passive")
		)
		(pad "C39" smd circle
			(at -23.495 3.175 90)
			(size 0.64 0.64)
			(layers "B.Cu" "B.Mask")
			(net 297 "/Expansion connector/+3V3_FMC")
			(pinfunction "C39")
			(pintype "passive")
		)
		(pad "C40" smd circle
			(at -24.765 3.175 90)
			(size 0.64 0.64)
			(layers "B.Cu" "B.Mask")
			(net 1 "GND")
			(pinfunction "C40")
			(pintype "passive")
		)
		(pad "D01" smd circle
			(at 24.765 1.905 90)
			(size 0.64 0.64)
			(layers "B.Cu" "B.Mask")
			(net 342 "/Expansion connector/FMC_PG_C2M")
			(pinfunction "D01")
			(pintype "passive")
		)
		(pad "D02" smd circle
			(at 23.495 1.905 90)
			(size 0.64 0.64)
			(layers "B.Cu" "B.Mask")
			(net 1 "GND")
			(pinfunction "D02")
			(pintype "passive")
		)
		(pad "D03" smd circle
			(at 22.225 1.905 90)
			(size 0.64 0.64)
			(layers "B.Cu" "B.Mask")
			(net 1 "GND")
			(pinfunction "D03")
			(pintype "passive")
		)
		(pad "D04" smd circle
			(at 20.955 1.905 90)
			(size 0.64 0.64)
			(layers "B.Cu" "B.Mask")
			(net 434 "unconnected-(J18-PadD04)")
			(pinfunction "D04")
			(pintype "passive+no_connect")
		)
		(pad "D05" smd circle
			(at 19.685 1.905 90)
			(size 0.64 0.64)
			(layers "B.Cu" "B.Mask")
			(net 309 "unconnected-(J18-PadD05)")
			(pinfunction "D05")
			(pintype "passive+no_connect")
		)
		(pad "D06" smd circle
			(at 18.415 1.905 90)
			(size 0.64 0.64)
			(layers "B.Cu" "B.Mask")
			(net 1 "GND")
			(pinfunction "D06")
			(pintype "passive")
		)
		(pad "D07" smd circle
			(at 17.145 1.905 90)
			(size 0.64 0.64)
			(layers "B.Cu" "B.Mask")
			(net 1 "GND")
			(pinfunction "D07")
			(pintype "passive")
		)
		(pad "D08" smd circle
			(at 15.875 1.905 90)
			(size 0.64 0.64)
			(layers "B.Cu" "B.Mask")
			(net 82 "/Expansion connector/UART2.RTS")
			(pinfunction "D08")
			(pintype "passive")
		)
		(pad "D09" smd circle
			(at 14.605 1.905 90)
			(size 0.64 0.64)
			(layers "B.Cu" "B.Mask")
			(net 158 "/Expansion connector/UART2.CTS")
			(pinfunction "D09")
			(pintype "passive")
		)
		(pad "D10" smd circle
			(at 13.335 1.905 90)
			(size 0.64 0.64)
			(layers "B.Cu" "B.Mask")
			(net 1 "GND")
			(pinfunction "D10")
			(pintype "passive")
		)
		(pad "D11" smd circle
			(at 12.065 1.905 90)
			(size 0.64 0.64)
			(layers "B.Cu" "B.Mask")
			(net 61 "/Expansion connector/UART2.TX")
			(pinfunction "D11")
			(pintype "passive")
		)
		(pad "D12" smd circle
			(at 10.795 1.905 90)
			(size 0.64 0.64)
			(layers "B.Cu" "B.Mask")
			(net 51 "/Expansion connector/UART2.RX")
			(pinfunction "D12")
			(pintype "passive")
		)
		(pad "D13" smd circle
			(at 9.525 1.905 90)
			(size 0.64 0.64)
			(layers "B.Cu" "B.Mask")
			(net 1 "GND")
			(pinfunction "D13")
			(pintype "passive")
		)
		(pad "D14" smd circle
			(at 8.255 1.905 90)
			(size 0.64 0.64)
			(layers "B.Cu" "B.Mask")
			(net 56 "/Expansion connector/UART5.RTS")
			(pinfunction "D14")
			(pintype "passive")
		)
		(pad "D15" smd circle
			(at 6.985 1.905 90)
			(size 0.64 0.64)
			(layers "B.Cu" "B.Mask")
			(net 121 "/Expansion connector/UART5.CTS")
			(pinfunction "D15")
			(pintype "passive")
		)
		(pad "D16" smd circle
			(at 5.715 1.905 90)
			(size 0.64 0.64)
			(layers "B.Cu" "B.Mask")
			(net 1 "GND")
			(pinfunction "D16")
			(pintype "passive")
		)
		(pad "D17" smd circle
			(at 4.445 1.905 90)
			(size 0.64 0.64)
			(layers "B.Cu" "B.Mask")
			(net 118 "/Expansion connector/UART5.TX")
			(pinfunction "D17")
			(pintype "passive")
		)
		(pad "D18" smd circle
			(at 3.175 1.905 90)
			(size 0.64 0.64)
			(layers "B.Cu" "B.Mask")
			(net 151 "/Expansion connector/UART5.RX")
			(pinfunction "D18")
			(pintype "passive")
		)
		(pad "D19" smd circle
			(at 1.905 1.905 90)
			(size 0.64 0.64)
			(layers "B.Cu" "B.Mask")
			(net 1 "GND")
			(pinfunction "D19")
			(pintype "passive")
		)
		(pad "D20" smd circle
			(at 0.635 1.905 90)
			(size 0.64 0.64)
			(layers "B.Cu" "B.Mask")
			(net 850 "/I2C_{SYS}.SDA")
			(pinfunction "D20")
			(pintype "passive")
		)
		(pad "D21" smd circle
			(at -0.635 1.905 90)
			(size 0.64 0.64)
			(layers "B.Cu" "B.Mask")
			(net 853 "/I2C_{SYS}.SCL")
			(pinfunction "D21")
			(pintype "passive")
		)
		(pad "D22" smd circle
			(at -1.905 1.905 90)
			(size 0.64 0.64)
			(layers "B.Cu" "B.Mask")
			(net 1 "GND")
			(pinfunction "D22")
			(pintype "passive")
		)
		(pad "D23" smd circle
			(at -3.175 1.905 90)
			(size 0.64 0.64)
			(layers "B.Cu" "B.Mask")
			(net 842 "/Expansion connector/I2C7.SDA")
			(pinfunction "D23")
			(pintype "passive")
		)
		(pad "D24" smd circle
			(at -4.445 1.905 90)
			(size 0.64 0.64)
			(layers "B.Cu" "B.Mask")
			(net 866 "/Expansion connector/I2C7.SCL")
			(pinfunction "D24")
			(pintype "passive")
		)
		(pad "D25" smd circle
			(at -5.715 1.905 90)
			(size 0.64 0.64)
			(layers "B.Cu" "B.Mask")
			(net 1 "GND")
			(pinfunction "D25")
			(pintype "passive")
		)
		(pad "D26" smd circle
			(at -6.985 1.905 90)
			(size 0.64 0.64)
			(layers "B.Cu" "B.Mask")
			(net 857 "/Expansion connector/I2C8.SCL")
			(pinfunction "D26")
			(pintype "passive")
		)
		(pad "D27" smd circle
			(at -8.255 1.905 90)
			(size 0.64 0.64)
			(layers "B.Cu" "B.Mask")
			(net 856 "/Expansion connector/I2C8.SDA")
			(pinfunction "D27")
			(pintype "passive")
		)
		(pad "D28" smd circle
			(at -9.525 1.905 90)
			(size 0.64 0.64)
			(layers "B.Cu" "B.Mask")
			(net 1 "GND")
			(pinfunction "D28")
			(pintype "passive")
		)
		(pad "D29" smd circle
			(at -10.795 1.905 90)
			(size 0.64 0.64)
			(layers "B.Cu" "B.Mask")
			(net 655 "unconnected-(J18-PadD29)")
			(pinfunction "D29")
			(pintype "passive+no_connect")
		)
		(pad "D30" smd circle
			(at -12.065 1.905 90)
			(size 0.64 0.64)
			(layers "B.Cu" "B.Mask")
			(net 449 "unconnected-(J18-PadD30)")
			(pinfunction "D30")
			(pintype "passive+no_connect")
		)
		(pad "D31" smd circle
			(at -13.335 1.905 90)
			(size 0.64 0.64)
			(layers "B.Cu" "B.Mask")
			(net 383 "unconnected-(J18-PadD31)")
			(pinfunction "D31")
			(pintype "passive+no_connect")
		)
		(pad "D32" smd circle
			(at -14.605 1.905 90)
			(size 0.64 0.64)
			(layers "B.Cu" "B.Mask")
			(net 148 "/Expansion connector/+3V3_AUX")
			(pinfunction "D32")
			(pintype "passive")
		)
		(pad "D33" smd circle
			(at -15.875 1.905 90)
			(size 0.64 0.64)
			(layers "B.Cu" "B.Mask")
			(net 484 "unconnected-(J18-PadD33)")
			(pinfunction "D33")
			(pintype "passive+no_connect")
		)
		(pad "D34" smd circle
			(at -17.145 1.905 90)
			(size 0.64 0.64)
			(layers "B.Cu" "B.Mask")
			(net 384 "unconnected-(J18-PadD34)")
			(pinfunction "D34")
			(pintype "passive+no_connect")
		)
		(pad "D35" smd circle
			(at -18.415 1.905 90)
			(size 0.64 0.64)
			(layers "B.Cu" "B.Mask")
			(net 472 "/Expansion connector/ADDR1")
			(pinfunction "D35")
			(pintype "passive")
		)
		(pad "D36" smd circle
			(at -19.685 1.905 90)
			(size 0.64 0.64)
			(layers "B.Cu" "B.Mask")
			(net 297 "/Expansion connector/+3V3_FMC")
			(pinfunction "D36")
			(pintype "passive")
		)
		(pad "D37" smd circle
			(at -20.955 1.905 90)
			(size 0.64 0.64)
			(layers "B.Cu" "B.Mask")
			(net 1 "GND")
			(pinfunction "D37")
			(pintype "passive")
		)
		(pad "D38" smd circle
			(at -22.225 1.905 90)
			(size 0.64 0.64)
			(layers "B.Cu" "B.Mask")
			(net 297 "/Expansion connector/+3V3_FMC")
			(pinfunction "D38")
			(pintype "passive")
		)
		(pad "D39" smd circle
			(at -23.495 1.905 90)
			(size 0.64 0.64)
			(layers "B.Cu" "B.Mask")
			(net 1 "GND")
			(pinfunction "D39")
			(pintype "passive")
		)
		(pad "D40" smd circle
			(at -24.765 1.905 90)
			(size 0.64 0.64)
			(layers "B.Cu" "B.Mask")
			(net 297 "/Expansion connector/+3V3_FMC")
			(pinfunction "D40")
			(pintype "passive")
		)
		(pad "E01" smd circle
			(at 24.765 0.635 90)
			(size 0.64 0.64)
			(layers "B.Cu" "B.Mask")
			(net 1 "GND")
			(pinfunction "E01")
			(pintype "passive")
		)
		(pad "E02" smd circle
			(at 23.495 0.635 90)
			(size 0.64 0.64)
			(layers "B.Cu" "B.Mask")
			(net 865 "unconnected-(J18-PadE02)")
			(pinfunction "E02")
			(pintype "passive+no_connect")
		)
		(pad "E03" smd circle
			(at 22.225 0.635 90)
			(size 0.64 0.64)
			(layers "B.Cu" "B.Mask")
			(net 860 "unconnected-(J18-PadE03)")
			(pinfunction "E03")
			(pintype "passive+no_connect")
		)
		(pad "E04" smd circle
			(at 20.955 0.635 90)
			(size 0.64 0.64)
			(layers "B.Cu" "B.Mask")
			(net 1 "GND")
			(pinfunction "E04")
			(pintype "passive")
		)
		(pad "E05" smd circle
			(at 19.685 0.635 90)
			(size 0.64 0.64)
			(layers "B.Cu" "B.Mask")
			(net 1 "GND")
			(pinfunction "E05")
			(pintype "passive")
		)
		(pad "E06" smd circle
			(at 18.415 0.635 90)
			(size 0.64 0.64)
			(layers "B.Cu" "B.Mask")
			(net 858 "unconnected-(J18-PadE06)")
			(pinfunction "E06")
			(pintype "passive+no_connect")
		)
		(pad "E07" smd circle
			(at 17.145 0.635 90)
			(size 0.64 0.64)
			(layers "B.Cu" "B.Mask")
			(net 854 "unconnected-(J18-PadE07)")
			(pinfunction "E07")
			(pintype "passive+no_connect")
		)
		(pad "E08" smd circle
			(at 15.875 0.635 90)
			(size 0.64 0.64)
			(layers "B.Cu" "B.Mask")
			(net 1 "GND")
			(pinfunction "E08")
			(pintype "passive")
		)
		(pad "E09" smd circle
			(at 14.605 0.635 90)
			(size 0.64 0.64)
			(layers "B.Cu" "B.Mask")
			(net 288 "unconnected-(J18-PadE09)")
			(pinfunction "E09")
			(pintype "passive+no_connect")
		)
		(pad "E10" smd circle
			(at 13.335 0.635 90)
			(size 0.64 0.64)
			(layers "B.Cu" "B.Mask")
			(net 844 "unconnected-(J18-PadE10)")
			(pinfunction "E10")
			(pintype "passive+no_connect")
		)
		(pad "E11" smd circle
			(at 12.065 0.635 90)
			(size 0.64 0.64)
			(layers "B.Cu" "B.Mask")
			(net 1 "GND")
			(pinfunction "E11")
			(pintype "passive")
		)
		(pad "E12" smd circle
			(at 10.795 0.635 90)
			(size 0.64 0.64)
			(layers "B.Cu" "B.Mask")
			(net 385 "unconnected-(J18-PadE12)")
			(pinfunction "E12")
			(pintype "passive+no_connect")
		)
		(pad "E13" smd circle
			(at 9.525 0.635 90)
			(size 0.64 0.64)
			(layers "B.Cu" "B.Mask")
			(net 346 "unconnected-(J18-PadE13)")
			(pinfunction "E13")
			(pintype "passive+no_connect")
		)
		(pad "E14" smd circle
			(at 8.255 0.635 90)
			(size 0.64 0.64)
			(layers "B.Cu" "B.Mask")
			(net 1 "GND")
			(pinfunction "E14")
			(pintype "passive")
		)
		(pad "E15" smd circle
			(at 6.985 0.635 90)
			(size 0.64 0.64)
			(layers "B.Cu" "B.Mask")
			(net 863 "unconnected-(J18-PadE15)")
			(pinfunction "E15")
			(pintype "passive+no_connect")
		)
		(pad "E16" smd circle
			(at 5.715 0.635 90)
			(size 0.64 0.64)
			(layers "B.Cu" "B.Mask")
			(net 381 "unconnected-(J18-PadE16)")
			(pinfunction "E16")
			(pintype "passive+no_connect")
		)
		(pad "E17" smd circle
			(at 4.445 0.635 90)
			(size 0.64 0.64)
			(layers "B.Cu" "B.Mask")
			(net 1 "GND")
			(pinfunction "E17")
			(pintype "passive")
		)
		(pad "E18" smd circle
			(at 3.175 0.635 90)
			(size 0.64 0.64)
			(layers "B.Cu" "B.Mask")
			(net 862 "unconnected-(J18-PadE18)")
			(pinfunction "E18")
			(pintype "passive+no_connect")
		)
		(pad "E19" smd circle
			(at 1.905 0.635 90)
			(size 0.64 0.64)
			(layers "B.Cu" "B.Mask")
			(net 848 "unconnected-(J18-PadE19)")
			(pinfunction "E19")
			(pintype "passive+no_connect")
		)
		(pad "E20" smd circle
			(at 0.635 0.635 90)
			(size 0.64 0.64)
			(layers "B.Cu" "B.Mask")
			(net 1 "GND")
			(pinfunction "E20")
			(pintype "passive")
		)
		(pad "E21" smd circle
			(at -0.635 0.635 90)
			(size 0.64 0.64)
			(layers "B.Cu" "B.Mask")
			(net 437 "unconnected-(J18-PadE21)")
			(pinfunction "E21")
			(pintype "passive+no_connect")
		)
		(pad "E22" smd circle
			(at -1.905 0.635 90)
			(size 0.64 0.64)
			(layers "B.Cu" "B.Mask")
			(net 840 "unconnected-(J18-PadE22)")
			(pinfunction "E22")
			(pintype "passive+no_connect")
		)
		(pad "E23" smd circle
			(at -3.175 0.635 90)
			(size 0.64 0.64)
			(layers "B.Cu" "B.Mask")
			(net 1 "GND")
			(pinfunction "E23")
			(pintype "passive")
		)
		(pad "E24" smd circle
			(at -4.445 0.635 90)
			(size 0.64 0.64)
			(layers "B.Cu" "B.Mask")
			(net 446 "unconnected-(J18-PadE24)")
			(pinfunction "E24")
			(pintype "passive+no_connect")
		)
		(pad "E25" smd circle
			(at -5.715 0.635 90)
			(size 0.64 0.64)
			(layers "B.Cu" "B.Mask")
			(net 290 "unconnected-(J18-PadE25)")
			(pinfunction "E25")
			(pintype "passive+no_connect")
		)
		(pad "E26" smd circle
			(at -6.985 0.635 90)
			(size 0.64 0.64)
			(layers "B.Cu" "B.Mask")
			(net 1 "GND")
			(pinfunction "E26")
			(pintype "passive")
		)
		(pad "E27" smd circle
			(at -8.255 0.635 90)
			(size 0.64 0.64)
			(layers "B.Cu" "B.Mask")
			(net 845 "unconnected-(J18-PadE27)")
			(pinfunction "E27")
			(pintype "passive+no_connect")
		)
		(pad "E28" smd circle
			(at -9.525 0.635 90)
			(size 0.64 0.64)
			(layers "B.Cu" "B.Mask")
			(net 457 "unconnected-(J18-PadE28)")
			(pinfunction "E28")
			(pintype "passive+no_connect")
		)
		(pad "E29" smd circle
			(at -10.795 0.635 90)
			(size 0.64 0.64)
			(layers "B.Cu" "B.Mask")
			(net 1 "GND")
			(pinfunction "E29")
			(pintype "passive")
		)
		(pad "E30" smd circle
			(at -12.065 0.635 90)
			(size 0.64 0.64)
			(layers "B.Cu" "B.Mask")
			(net 847 "unconnected-(J18-PadE30)")
			(pinfunction "E30")
			(pintype "passive+no_connect")
		)
		(pad "E31" smd circle
			(at -13.335 0.635 90)
			(size 0.64 0.64)
			(layers "B.Cu" "B.Mask")
			(net 855 "unconnected-(J18-PadE31)")
			(pinfunction "E31")
			(pintype "passive+no_connect")
		)
		(pad "E32" smd circle
			(at -14.605 0.635 90)
			(size 0.64 0.64)
			(layers "B.Cu" "B.Mask")
			(net 1 "GND")
			(pinfunction "E32")
			(pintype "passive")
		)
		(pad "E33" smd circle
			(at -15.875 0.635 90)
			(size 0.64 0.64)
			(layers "B.Cu" "B.Mask")
			(net 312 "unconnected-(J18-PadE33)")
			(pinfunction "E33")
			(pintype "passive+no_connect")
		)
		(pad "E34" smd circle
			(at -17.145 0.635 90)
			(size 0.64 0.64)
			(layers "B.Cu" "B.Mask")
			(net 477 "unconnected-(J18-PadE34)")
			(pinfunction "E34")
			(pintype "passive+no_connect")
		)
		(pad "E35" smd circle
			(at -18.415 0.635 90)
			(size 0.64 0.64)
			(layers "B.Cu" "B.Mask")
			(net 1 "GND")
			(pinfunction "E35")
			(pintype "passive")
		)
		(pad "E36" smd circle
			(at -19.685 0.635 90)
			(size 0.64 0.64)
			(layers "B.Cu" "B.Mask")
			(net 358 "unconnected-(J18-PadE36)")
			(pinfunction "E36")
			(pintype "passive+no_connect")
		)
		(pad "E37" smd circle
			(at -20.955 0.635 90)
			(size 0.64 0.64)
			(layers "B.Cu" "B.Mask")
			(net 447 "unconnected-(J18-PadE37)")
			(pinfunction "E37")
			(pintype "passive+no_connect")
		)
		(pad "E38" smd circle
			(at -22.225 0.635 90)
			(size 0.64 0.64)
			(layers "B.Cu" "B.Mask")
			(net 1 "GND")
			(pinfunction "E38")
			(pintype "passive")
		)
		(pad "E39" smd circle
			(at -23.495 0.635 90)
			(size 0.64 0.64)
			(layers "B.Cu" "B.Mask")
			(net 295 "/Expansion connector/+V_{ADJ}")
			(pinfunction "E39")
			(pintype "passive")
		)
		(pad "E40" smd circle
			(at -24.765 0.635 90)
			(size 0.64 0.64)
			(layers "B.Cu" "B.Mask")
			(net 1 "GND")
			(pinfunction "E40")
			(pintype "passive")
		)
		(pad "F01" smd circle
			(at 24.765 -0.635 90)
			(size 0.64 0.64)
			(layers "B.Cu" "B.Mask")
			(net 330 "/Expansion connector/FMC_PG_M2C")
			(pinfunction "F01")
			(pintype "passive")
		)
		(pad "F02" smd circle
			(at 23.495 -0.635 90)
			(size 0.64 0.64)
			(layers "B.Cu" "B.Mask")
			(net 1 "GND")
			(pinfunction "F02")
			(pintype "passive")
		)
		(pad "F03" smd circle
			(at 22.225 -0.635 90)
			(size 0.64 0.64)
			(layers "B.Cu" "B.Mask")
			(net 1 "GND")
			(pinfunction "F03")
			(pintype "passive")
		)
		(pad "F04" smd circle
			(at 20.955 -0.635 90)
			(size 0.64 0.64)
			(layers "B.Cu" "B.Mask")
			(net 441 "unconnected-(J18-PadF04)")
			(pinfunction "F04")
			(pintype "passive+no_connect")
		)
		(pad "F05" smd circle
			(at 19.685 -0.635 90)
			(size 0.64 0.64)
			(layers "B.Cu" "B.Mask")
			(net 481 "unconnected-(J18-PadF05)")
			(pinfunction "F05")
			(pintype "passive+no_connect")
		)
		(pad "F06" smd circle
			(at 18.415 -0.635 90)
			(size 0.64 0.64)
			(layers "B.Cu" "B.Mask")
			(net 1 "GND")
			(pinfunction "F06")
			(pintype "passive")
		)
		(pad "F07" smd circle
			(at 17.145 -0.635 90)
			(size 0.64 0.64)
			(layers "B.Cu" "B.Mask")
			(net 455 "unconnected-(J18-PadF07)")
			(pinfunction "F07")
			(pintype "passive+no_connect")
		)
		(pad "F08" smd circle
			(at 15.875 -0.635 90)
			(size 0.64 0.64)
			(layers "B.Cu" "B.Mask")
			(net 316 "unconnected-(J18-PadF08)")
			(pinfunction "F08")
			(pintype "passive+no_connect")
		)
		(pad "F09" smd circle
			(at 14.605 -0.635 90)
			(size 0.64 0.64)
			(layers "B.Cu" "B.Mask")
			(net 1 "GND")
			(pinfunction "F09")
			(pintype "passive")
		)
		(pad "F10" smd circle
			(at 13.335 -0.635 90)
			(size 0.64 0.64)
			(layers "B.Cu" "B.Mask")
			(net 413 "unconnected-(J18-PadF10)")
			(pinfunction "F10")
			(pintype "passive+no_connect")
		)
		(pad "F11" smd circle
			(at 12.065 -0.635 90)
			(size 0.64 0.64)
			(layers "B.Cu" "B.Mask")
			(net 402 "unconnected-(J18-PadF11)")
			(pinfunction "F11")
			(pintype "passive+no_connect")
		)
		(pad "F12" smd circle
			(at 10.795 -0.635 90)
			(size 0.64 0.64)
			(layers "B.Cu" "B.Mask")
			(net 1 "GND")
			(pinfunction "F12")
			(pintype "passive")
		)
		(pad "F13" smd circle
			(at 9.525 -0.635 90)
			(size 0.64 0.64)
			(layers "B.Cu" "B.Mask")
			(net 445 "unconnected-(J18-PadF13)")
			(pinfunction "F13")
			(pintype "passive+no_connect")
		)
		(pad "F14" smd circle
			(at 8.255 -0.635 90)
			(size 0.64 0.64)
			(layers "B.Cu" "B.Mask")
			(net 427 "unconnected-(J18-PadF14)")
			(pinfunction "F14")
			(pintype "passive+no_connect")
		)
		(pad "F15" smd circle
			(at 6.985 -0.635 90)
			(size 0.64 0.64)
			(layers "B.Cu" "B.Mask")
			(net 1 "GND")
			(pinfunction "F15")
			(pintype "passive")
		)
		(pad "F16" smd circle
			(at 5.715 -0.635 90)
			(size 0.64 0.64)
			(layers "B.Cu" "B.Mask")
			(net 363 "unconnected-(J18-PadF16)")
			(pinfunction "F16")
			(pintype "passive+no_connect")
		)
		(pad "F17" smd circle
			(at 4.445 -0.635 90)
			(size 0.64 0.64)
			(layers "B.Cu" "B.Mask")
			(net 474 "unconnected-(J18-PadF17)")
			(pinfunction "F17")
			(pintype "passive+no_connect")
		)
		(pad "F18" smd circle
			(at 3.175 -0.635 90)
			(size 0.64 0.64)
			(layers "B.Cu" "B.Mask")
			(net 1 "GND")
			(pinfunction "F18")
			(pintype "passive")
		)
		(pad "F19" smd circle
			(at 1.905 -0.635 90)
			(size 0.64 0.64)
			(layers "B.Cu" "B.Mask")
			(net 577 "unconnected-(J18-PadF19)")
			(pinfunction "F19")
			(pintype "passive+no_connect")
		)
		(pad "F20" smd circle
			(at 0.635 -0.635 90)
			(size 0.64 0.64)
			(layers "B.Cu" "B.Mask")
			(net 454 "unconnected-(J18-PadF20)")
			(pinfunction "F20")
			(pintype "passive+no_connect")
		)
		(pad "F21" smd circle
			(at -0.635 -0.635 90)
			(size 0.64 0.64)
			(layers "B.Cu" "B.Mask")
			(net 1 "GND")
			(pinfunction "F21")
			(pintype "passive")
		)
		(pad "F22" smd circle
			(at -1.905 -0.635 90)
			(size 0.64 0.64)
			(layers "B.Cu" "B.Mask")
			(net 658 "unconnected-(J18-PadF22)")
			(pinfunction "F22")
			(pintype "passive+no_connect")
		)
		(pad "F23" smd circle
			(at -3.175 -0.635 90)
			(size 0.64 0.64)
			(layers "B.Cu" "B.Mask")
			(net 337 "unconnected-(J18-PadF23)")
			(pinfunction "F23")
			(pintype "passive+no_connect")
		)
		(pad "F24" smd circle
			(at -4.445 -0.635 90)
			(size 0.64 0.64)
			(layers "B.Cu" "B.Mask")
			(net 1 "GND")
			(pinfunction "F24")
			(pintype "passive")
		)
		(pad "F25" smd circle
			(at -5.715 -0.635 90)
			(size 0.64 0.64)
			(layers "B.Cu" "B.Mask")
			(net 628 "unconnected-(J18-PadF25)")
			(pinfunction "F25")
			(pintype "passive+no_connect")
		)
		(pad "F26" smd circle
			(at -6.985 -0.635 90)
			(size 0.64 0.64)
			(layers "B.Cu" "B.Mask")
			(net 594 "unconnected-(J18-PadF26)")
			(pinfunction "F26")
			(pintype "passive+no_connect")
		)
		(pad "F27" smd circle
			(at -8.255 -0.635 90)
			(size 0.64 0.64)
			(layers "B.Cu" "B.Mask")
			(net 1 "GND")
			(pinfunction "F27")
			(pintype "passive")
		)
		(pad "F28" smd circle
			(at -9.525 -0.635 90)
			(size 0.64 0.64)
			(layers "B.Cu" "B.Mask")
			(net 465 "unconnected-(J18-PadF28)")
			(pinfunction "F28")
			(pintype "passive+no_connect")
		)
		(pad "F29" smd circle
			(at -10.795 -0.635 90)
			(size 0.64 0.64)
			(layers "B.Cu" "B.Mask")
			(net 745 "unconnected-(J18-PadF29)")
			(pinfunction "F29")
			(pintype "passive+no_connect")
		)
		(pad "F30" smd circle
			(at -12.065 -0.635 90)
			(size 0.64 0.64)
			(layers "B.Cu" "B.Mask")
			(net 1 "GND")
			(pinfunction "F30")
			(pintype "passive")
		)
		(pad "F31" smd circle
			(at -13.335 -0.635 90)
			(size 0.64 0.64)
			(layers "B.Cu" "B.Mask")
			(net 708 "unconnected-(J18-PadF31)")
			(pinfunction "F31")
			(pintype "passive+no_connect")
		)
		(pad "F32" smd circle
			(at -14.605 -0.635 90)
			(size 0.64 0.64)
			(layers "B.Cu" "B.Mask")
			(net 611 "unconnected-(J18-PadF32)")
			(pinfunction "F32")
			(pintype "passive+no_connect")
		)
		(pad "F33" smd circle
			(at -15.875 -0.635 90)
			(size 0.64 0.64)
			(layers "B.Cu" "B.Mask")
			(net 1 "GND")
			(pinfunction "F33")
			(pintype "passive")
		)
		(pad "F34" smd circle
			(at -17.145 -0.635 90)
			(size 0.64 0.64)
			(layers "B.Cu" "B.Mask")
			(net 403 "unconnected-(J18-PadF34)")
			(pinfunction "F34")
			(pintype "passive+no_connect")
		)
		(pad "F35" smd circle
			(at -18.415 -0.635 90)
			(size 0.64 0.64)
			(layers "B.Cu" "B.Mask")
			(net 456 "unconnected-(J18-PadF35)")
			(pinfunction "F35")
			(pintype "passive+no_connect")
		)
		(pad "F36" smd circle
			(at -19.685 -0.635 90)
			(size 0.64 0.64)
			(layers "B.Cu" "B.Mask")
			(net 1 "GND")
			(pinfunction "F36")
			(pintype "passive")
		)
		(pad "F37" smd circle
			(at -20.955 -0.635 90)
			(size 0.64 0.64)
			(layers "B.Cu" "B.Mask")
			(net 424 "unconnected-(J18-PadF37)")
			(pinfunction "F37")
			(pintype "passive+no_connect")
		)
		(pad "F38" smd circle
			(at -22.225 -0.635 90)
			(size 0.64 0.64)
			(layers "B.Cu" "B.Mask")
			(net 404 "unconnected-(J18-PadF38)")
			(pinfunction "F38")
			(pintype "passive+no_connect")
		)
		(pad "F39" smd circle
			(at -23.495 -0.635 90)
			(size 0.64 0.64)
			(layers "B.Cu" "B.Mask")
			(net 1 "GND")
			(pinfunction "F39")
			(pintype "passive")
		)
		(pad "F40" smd circle
			(at -24.765 -0.635 90)
			(size 0.64 0.64)
			(layers "B.Cu" "B.Mask")
			(net 295 "/Expansion connector/+V_{ADJ}")
			(pinfunction "F40")
			(pintype "passive")
		)
		(pad "G01" smd circle
			(at 24.765 -1.905 90)
			(size 0.64 0.64)
			(layers "B.Cu" "B.Mask")
			(net 1 "GND")
			(pinfunction "G01")
			(pintype "passive")
		)
		(pad "G02" smd circle
			(at 23.495 -1.905 90)
			(size 0.64 0.64)
			(layers "B.Cu" "B.Mask")
			(net 362 "/Expansion connector/GPIO.MCLK01")
			(pinfunction "G02")
			(pintype "passive")
		)
		(pad "G03" smd circle
			(at 22.225 -1.905 90)
			(size 0.64 0.64)
			(layers "B.Cu" "B.Mask")
			(net 416 "/Expansion connector/GPIO.MCLK02")
			(pinfunction "G03")
			(pintype "passive")
		)
		(pad "G04" smd circle
			(at 20.955 -1.905 90)
			(size 0.64 0.64)
			(layers "B.Cu" "B.Mask")
			(net 1 "GND")
			(pinfunction "G04")
			(pintype "passive")
		)
		(pad "G05" smd circle
			(at 19.685 -1.905 90)
			(size 0.64 0.64)
			(layers "B.Cu" "B.Mask")
			(net 1 "GND")
			(pinfunction "G05")
			(pintype "passive")
		)
		(pad "G06" smd circle
			(at 18.415 -1.905 90)
			(size 0.64 0.64)
			(layers "B.Cu" "B.Mask")
			(net 120 "/Expansion connector/I2S2.CLK")
			(pinfunction "G06")
			(pintype "passive")
		)
		(pad "G07" smd circle
			(at 17.145 -1.905 90)
			(size 0.64 0.64)
			(layers "B.Cu" "B.Mask")
			(net 146 "/Expansion connector/I2S2.FS")
			(pinfunction "G07")
			(pintype "passive")
		)
		(pad "G08" smd circle
			(at 15.875 -1.905 90)
			(size 0.64 0.64)
			(layers "B.Cu" "B.Mask")
			(net 1 "GND")
			(pinfunction "G08")
			(pintype "passive")
		)
		(pad "G09" smd circle
			(at 14.605 -1.905 90)
			(size 0.64 0.64)
			(layers "B.Cu" "B.Mask")
			(net 172 "/Expansion connector/I2S2.SDOUT")
			(pinfunction "G09")
			(pintype "passive")
		)
		(pad "G10" smd circle
			(at 13.335 -1.905 90)
			(size 0.64 0.64)
			(layers "B.Cu" "B.Mask")
			(net 168 "/Expansion connector/I2S2.SDIN")
			(pinfunction "G10")
			(pintype "passive")
		)
		(pad "G11" smd circle
			(at 12.065 -1.905 90)
			(size 0.64 0.64)
			(layers "B.Cu" "B.Mask")
			(net 1 "GND")
			(pinfunction "G11")
			(pintype "passive")
		)
		(pad "G12" smd circle
			(at 10.795 -1.905 90)
			(size 0.64 0.64)
			(layers "B.Cu" "B.Mask")
			(net 165 "/Expansion connector/I2S3.CLK")
			(pinfunction "G12")
			(pintype "passive")
		)
		(pad "G13" smd circle
			(at 9.525 -1.905 90)
			(size 0.64 0.64)
			(layers "B.Cu" "B.Mask")
			(net 111 "/Expansion connector/I2S3.FS")
			(pinfunction "G13")
			(pintype "passive")
		)
		(pad "G14" smd circle
			(at 8.255 -1.905 90)
			(size 0.64 0.64)
			(layers "B.Cu" "B.Mask")
			(net 1 "GND")
			(pinfunction "G14")
			(pintype "passive")
		)
		(pad "G15" smd circle
			(at 6.985 -1.905 90)
			(size 0.64 0.64)
			(layers "B.Cu" "B.Mask")
			(net 141 "/Expansion connector/I2S3.SDOUT")
			(pinfunction "G15")
			(pintype "passive")
		)
		(pad "G16" smd circle
			(at 5.715 -1.905 90)
			(size 0.64 0.64)
			(layers "B.Cu" "B.Mask")
			(net 114 "/Expansion connector/I2S3.SDIN")
			(pinfunction "G16")
			(pintype "passive")
		)
		(pad "G17" smd circle
			(at 4.445 -1.905 90)
			(size 0.64 0.64)
			(layers "B.Cu" "B.Mask")
			(net 1 "GND")
			(pinfunction "G17")
			(pintype "passive")
		)
		(pad "G18" smd circle
			(at 3.175 -1.905 90)
			(size 0.64 0.64)
			(layers "B.Cu" "B.Mask")
			(net 292 "/Expansion connector/SPI1.~{CS0}")
			(pinfunction "G18")
			(pintype "passive")
		)
		(pad "G19" smd circle
			(at 1.905 -1.905 90)
			(size 0.64 0.64)
			(layers "B.Cu" "B.Mask")
			(net 364 "/Expansion connector/SPI1.~{CS1}")
			(pinfunction "G19")
			(pintype "passive")
		)
		(pad "G20" smd circle
			(at 0.635 -1.905 90)
			(size 0.64 0.64)
			(layers "B.Cu" "B.Mask")
			(net 1 "GND")
			(pinfunction "G20")
			(pintype "passive")
		)
		(pad "G21" smd circle
			(at -0.635 -1.905 90)
			(size 0.64 0.64)
			(layers "B.Cu" "B.Mask")
			(net 69 "/Expansion connector/SPI1.MISO")
			(pinfunction "G21")
			(pintype "passive")
		)
		(pad "G22" smd circle
			(at -1.905 -1.905 90)
			(size 0.64 0.64)
			(layers "B.Cu" "B.Mask")
			(net 65 "/Expansion connector/SPI1.MOSI")
			(pinfunction "G22")
			(pintype "passive")
		)
		(pad "G23" smd circle
			(at -3.175 -1.905 90)
			(size 0.64 0.64)
			(layers "B.Cu" "B.Mask")
			(net 1 "GND")
			(pinfunction "G23")
			(pintype "passive")
		)
		(pad "G24" smd circle
			(at -4.445 -1.905 90)
			(size 0.64 0.64)
			(layers "B.Cu" "B.Mask")
			(net 421 "/Expansion connector/SPI1.SCK")
			(pinfunction "G24")
			(pintype "passive")
		)
		(pad "G25" smd circle
			(at -5.715 -1.905 90)
			(size 0.64 0.64)
			(layers "B.Cu" "B.Mask")
			(net 409 "/Expansion connector/SPI2.~{CS0}")
			(pinfunction "G25")
			(pintype "passive")
		)
		(pad "G26" smd circle
			(at -6.985 -1.905 90)
			(size 0.64 0.64)
			(layers "B.Cu" "B.Mask")
			(net 1 "GND")
			(pinfunction "G26")
			(pintype "passive")
		)
		(pad "G27" smd circle
			(at -8.255 -1.905 90)
			(size 0.64 0.64)
			(layers "B.Cu" "B.Mask")
			(net 393 "/Expansion connector/SPI2.SCK")
			(pinfunction "G27")
			(pintype "passive")
		)
		(pad "G28" smd circle
			(at -9.525 -1.905 90)
			(size 0.64 0.64)
			(layers "B.Cu" "B.Mask")
			(net 109 "/Expansion connector/SPI2.MISO")
			(pinfunction "G28")
			(pintype "passive")
		)
		(pad "G29" smd circle
			(at -10.795 -1.905 90)
			(size 0.64 0.64)
			(layers "B.Cu" "B.Mask")
			(net 1 "GND")
			(pinfunction "G29")
			(pintype "passive")
		)
		(pad "G30" smd circle
			(at -12.065 -1.905 90)
			(size 0.64 0.64)
			(layers "B.Cu" "B.Mask")
			(net 173 "/Expansion connector/SPI2.MOSI")
			(pinfunction "G30")
			(pintype "passive")
		)
		(pad "G31" smd circle
			(at -13.335 -1.905 90)
			(size 0.64 0.64)
			(layers "B.Cu" "B.Mask")
			(net 438 "/Expansion connector/SPI3.~{CS0}")
			(pinfunction "G31")
			(pintype "passive")
		)
		(pad "G32" smd circle
			(at -14.605 -1.905 90)
			(size 0.64 0.64)
			(layers "B.Cu" "B.Mask")
			(net 1 "GND")
			(pinfunction "G32")
			(pintype "passive")
		)
		(pad "G33" smd circle
			(at -15.875 -1.905 90)
			(size 0.64 0.64)
			(layers "B.Cu" "B.Mask")
			(net 390 "unconnected-(J18-PadG33)")
			(pinfunction "G33")
			(pintype "passive+no_connect")
		)
		(pad "G34" smd circle
			(at -17.145 -1.905 90)
			(size 0.64 0.64)
			(layers "B.Cu" "B.Mask")
			(net 326 "unconnected-(J18-PadG34)")
			(pinfunction "G34")
			(pintype "passive+no_connect")
		)
		(pad "G35" smd circle
			(at -18.415 -1.905 90)
			(size 0.64 0.64)
			(layers "B.Cu" "B.Mask")
			(net 1 "GND")
			(pinfunction "G35")
			(pintype "passive")
		)
		(pad "G36" smd circle
			(at -19.685 -1.905 90)
			(size 0.64 0.64)
			(layers "B.Cu" "B.Mask")
			(net 300 "unconnected-(J18-PadG36)")
			(pinfunction "G36")
			(pintype "passive+no_connect")
		)
		(pad "G37" smd circle
			(at -20.955 -1.905 90)
			(size 0.64 0.64)
			(layers "B.Cu" "B.Mask")
			(net 308 "unconnected-(J18-PadG37)")
			(pinfunction "G37")
			(pintype "passive+no_connect")
		)
		(pad "G38" smd circle
			(at -22.225 -1.905 90)
			(size 0.64 0.64)
			(layers "B.Cu" "B.Mask")
			(net 1 "GND")
			(pinfunction "G38")
			(pintype "passive")
		)
		(pad "G39" smd circle
			(at -23.495 -1.905 90)
			(size 0.64 0.64)
			(layers "B.Cu" "B.Mask")
			(net 295 "/Expansion connector/+V_{ADJ}")
			(pinfunction "G39")
			(pintype "passive")
		)
		(pad "G40" smd circle
			(at -24.765 -1.905 90)
			(size 0.64 0.64)
			(layers "B.Cu" "B.Mask")
			(net 1 "GND")
			(pinfunction "G40")
			(pintype "passive")
		)
		(pad "H01" smd circle
			(at 24.765 -3.175 90)
			(size 0.64 0.64)
			(layers "B.Cu" "B.Mask")
			(net 431 "Net-(J18-PadH01)")
			(pinfunction "H01")
			(pintype "passive")
		)
		(pad "H02" smd circle
			(at 23.495 -3.175 90)
			(size 0.64 0.64)
			(layers "B.Cu" "B.Mask")
			(net 761 "Net-(J18-PadH02)")
			(pinfunction "H02")
			(pintype "passive")
		)
		(pad "H03" smd circle
			(at 22.225 -3.175 90)
			(size 0.64 0.64)
			(layers "B.Cu" "B.Mask")
			(net 1 "GND")
			(pinfunction "H03")
			(pintype "passive")
		)
		(pad "H04" smd circle
			(at 20.955 -3.175 90)
			(size 0.64 0.64)
			(layers "B.Cu" "B.Mask")
			(net 432 "unconnected-(J18-PadH04)")
			(pinfunction "H04")
			(pintype "passive+no_connect")
		)
		(pad "H05" smd circle
			(at 19.685 -3.175 90)
			(size 0.64 0.64)
			(layers "B.Cu" "B.Mask")
			(net 852 "unconnected-(J18-PadH05)")
			(pinfunction "H05")
			(pintype "passive+no_connect")
		)
		(pad "H06" smd circle
			(at 18.415 -3.175 90)
			(size 0.64 0.64)
			(layers "B.Cu" "B.Mask")
			(net 1 "GND")
			(pinfunction "H06")
			(pintype "passive")
		)
		(pad "H07" smd circle
			(at 17.145 -3.175 90)
			(size 0.64 0.64)
			(layers "B.Cu" "B.Mask")
			(net 105 "/Expansion connector/CAN0.DIN")
			(pinfunction "H07")
			(pintype "passive")
		)
		(pad "H08" smd circle
			(at 15.875 -3.175 90)
			(size 0.64 0.64)
			(layers "B.Cu" "B.Mask")
			(net 142 "/Expansion connector/CAN0.DOUT")
			(pinfunction "H08")
			(pintype "passive")
		)
		(pad "H09" smd circle
			(at 14.605 -3.175 90)
			(size 0.64 0.64)
			(layers "B.Cu" "B.Mask")
			(net 1 "GND")
			(pinfunction "H09")
			(pintype "passive")
		)
		(pad "H10" smd circle
			(at 13.335 -3.175 90)
			(size 0.64 0.64)
			(layers "B.Cu" "B.Mask")
			(net 50 "/Expansion connector/CAN1.DIN")
			(pinfunction "H10")
			(pintype "passive")
		)
		(pad "H11" smd circle
			(at 12.065 -3.175 90)
			(size 0.64 0.64)
			(layers "B.Cu" "B.Mask")
			(net 81 "/Expansion connector/CAN1.DOUT")
			(pinfunction "H11")
			(pintype "passive")
		)
		(pad "H12" smd circle
			(at 10.795 -3.175 90)
			(size 0.64 0.64)
			(layers "B.Cu" "B.Mask")
			(net 1 "GND")
			(pinfunction "H12")
			(pintype "passive")
		)
		(pad "H13" smd circle
			(at 9.525 -3.175 90)
			(size 0.64 0.64)
			(layers "B.Cu" "B.Mask")
			(net 690 "/Expansion connector/CAN2.DIN")
			(pinfunction "H13")
			(pintype "passive")
		)
		(pad "H14" smd circle
			(at 8.255 -3.175 90)
			(size 0.64 0.64)
			(layers "B.Cu" "B.Mask")
			(net 600 "/Expansion connector/CAN2.DOUT")
			(pinfunction "H14")
			(pintype "passive")
		)
		(pad "H15" smd circle
			(at 6.985 -3.175 90)
			(size 0.64 0.64)
			(layers "B.Cu" "B.Mask")
			(net 1 "GND")
			(pinfunction "H15")
			(pintype "passive")
		)
		(pad "H16" smd circle
			(at 5.715 -3.175 90)
			(size 0.64 0.64)
			(layers "B.Cu" "B.Mask")
			(net 701 "/Expansion connector/CAN3.DIN")
			(pinfunction "H16")
			(pintype "passive")
		)
		(pad "H17" smd circle
			(at 4.445 -3.175 90)
			(size 0.64 0.64)
			(layers "B.Cu" "B.Mask")
			(net 783 "/Expansion connector/CAN3.DOUT")
			(pinfunction "H17")
			(pintype "passive")
		)
		(pad "H18" smd circle
			(at 3.175 -3.175 90)
			(size 0.64 0.64)
			(layers "B.Cu" "B.Mask")
			(net 1 "GND")
			(pinfunction "H18")
			(pintype "passive")
		)
		(pad "H19" smd circle
			(at 1.905 -3.175 90)
			(size 0.64 0.64)
			(layers "B.Cu" "B.Mask")
			(net 487 "/Expansion connector/GPIO.USER_LED0")
			(pinfunction "H19")
			(pintype "passive")
		)
		(pad "H20" smd circle
			(at 0.635 -3.175 90)
			(size 0.64 0.64)
			(layers "B.Cu" "B.Mask")
			(net 371 "/Expansion connector/GPIO.USER_LED1")
			(pinfunction "H20")
			(pintype "passive")
		)
		(pad "H21" smd circle
			(at -0.635 -3.175 90)
			(size 0.64 0.64)
			(layers "B.Cu" "B.Mask")
			(net 1 "GND")
			(pinfunction "H21")
			(pintype "passive")
		)
		(pad "H22" smd circle
			(at -1.905 -3.175 90)
			(size 0.64 0.64)
			(layers "B.Cu" "B.Mask")
			(net 448 "/Expansion connector/GPIO.USER_BTN0")
			(pinfunction "H22")
			(pintype "passive")
		)
		(pad "H23" smd circle
			(at -3.175 -3.175 90)
			(size 0.64 0.64)
			(layers "B.Cu" "B.Mask")
			(net 356 "/Expansion connector/GPIO.USER_BTN1")
			(pinfunction "H23")
			(pintype "passive")
		)
		(pad "H24" smd circle
			(at -4.445 -3.175 90)
			(size 0.64 0.64)
			(layers "B.Cu" "B.Mask")
			(net 1 "GND")
			(pinfunction "H24")
			(pintype "passive")
		)
		(pad "H25" smd circle
			(at -5.715 -3.175 90)
			(size 0.64 0.64)
			(layers "B.Cu" "B.Mask")
			(net 849 "/Expansion connector/GPIO.18")
			(pinfunction "H25")
			(pintype "passive")
		)
		(pad "H26" smd circle
			(at -6.985 -3.175 90)
			(size 0.64 0.64)
			(layers "B.Cu" "B.Mask")
			(net 464 "/Expansion connector/GPIO.20")
			(pinfunction "H26")
			(pintype "passive")
		)
		(pad "H27" smd circle
			(at -8.255 -3.175 90)
			(size 0.64 0.64)
			(layers "B.Cu" "B.Mask")
			(net 1 "GND")
			(pinfunction "H27")
			(pintype "passive")
		)
		(pad "H28" smd circle
			(at -9.525 -3.175 90)
			(size 0.64 0.64)
			(layers "B.Cu" "B.Mask")
			(net 49 "/Expansion connector/SPI3.MOSI")
			(pinfunction "H28")
			(pintype "passive")
		)
		(pad "H29" smd circle
			(at -10.795 -3.175 90)
			(size 0.64 0.64)
			(layers "B.Cu" "B.Mask")
			(net 305 "/Expansion connector/SPI3.SCK")
			(pinfunction "H29")
			(pintype "passive")
		)
		(pad "H30" smd circle
			(at -12.065 -3.175 90)
			(size 0.64 0.64)
			(layers "B.Cu" "B.Mask")
			(net 1 "GND")
			(pinfunction "H30")
			(pintype "passive")
		)
		(pad "H31" smd circle
			(at -13.335 -3.175 90)
			(size 0.64 0.64)
			(layers "B.Cu" "B.Mask")
			(net 405 "/Expansion connector/SPI3.~{CS1}")
			(pinfunction "H31")
			(pintype "passive")
		)
		(pad "H32" smd circle
			(at -14.605 -3.175 90)
			(size 0.64 0.64)
			(layers "B.Cu" "B.Mask")
			(net 75 "/Expansion connector/SPI3.MISO")
			(pinfunction "H32")
			(pintype "passive")
		)
		(pad "H33" smd circle
			(at -15.875 -3.175 90)
			(size 0.64 0.64)
			(layers "B.Cu" "B.Mask")
			(net 1 "GND")
			(pinfunction "H33")
			(pintype "passive")
		)
		(pad "H34" smd circle
			(at -17.145 -3.175 90)
			(size 0.64 0.64)
			(layers "B.Cu" "B.Mask")
			(net 846 "unconnected-(J18-PadH34)")
			(pinfunction "H34")
			(pintype "passive+no_connect")
		)
		(pad "H35" smd circle
			(at -18.415 -3.175 90)
			(size 0.64 0.64)
			(layers "B.Cu" "B.Mask")
			(net 1360 "unconnected-(J18-PadH35)")
			(pinfunction "H35")
			(pintype "passive+no_connect")
		)
		(pad "H36" smd circle
			(at -19.685 -3.175 90)
			(size 0.64 0.64)
			(layers "B.Cu" "B.Mask")
			(net 1 "GND")
			(pinfunction "H36")
			(pintype "passive")
		)
		(pad "H37" smd circle
			(at -20.955 -3.175 90)
			(size 0.64 0.64)
			(layers "B.Cu" "B.Mask")
			(net 864 "unconnected-(J18-PadH37)")
			(pinfunction "H37")
			(pintype "passive+no_connect")
		)
		(pad "H38" smd circle
			(at -22.225 -3.175 90)
			(size 0.64 0.64)
			(layers "B.Cu" "B.Mask")
			(net 859 "unconnected-(J18-PadH38)")
			(pinfunction "H38")
			(pintype "passive+no_connect")
		)
		(pad "H39" smd circle
			(at -23.495 -3.175 90)
			(size 0.64 0.64)
			(layers "B.Cu" "B.Mask")
			(net 1 "GND")
			(pinfunction "H39")
			(pintype "passive")
		)
		(pad "H40" smd circle
			(at -24.765 -3.175 90)
			(size 0.64 0.64)
			(layers "B.Cu" "B.Mask")
			(net 295 "/Expansion connector/+V_{ADJ}")
			(pinfunction "H40")
			(pintype "passive")
		)
		(pad "J01" smd circle
			(at 24.765 -4.445 90)
			(size 0.64 0.64)
			(layers "B.Cu" "B.Mask")
			(net 1 "GND")
			(pinfunction "J01")
			(pintype "passive")
		)
		(pad "J02" smd circle
			(at 23.495 -4.445 90)
			(size 0.64 0.64)
			(layers "B.Cu" "B.Mask")
			(net 353 "unconnected-(J18-PadJ02)")
			(pinfunction "J02")
			(pintype "passive+no_connect")
		)
		(pad "J03" smd circle
			(at 22.225 -4.445 90)
			(size 0.64 0.64)
			(layers "B.Cu" "B.Mask")
			(net 401 "unconnected-(J18-PadJ03)")
			(pinfunction "J03")
			(pintype "passive+no_connect")
		)
		(pad "J04" smd circle
			(at 20.955 -4.445 90)
			(size 0.64 0.64)
			(layers "B.Cu" "B.Mask")
			(net 1 "GND")
			(pinfunction "J04")
			(pintype "passive")
		)
		(pad "J05" smd circle
			(at 19.685 -4.445 90)
			(size 0.64 0.64)
			(layers "B.Cu" "B.Mask")
			(net 1 "GND")
			(pinfunction "J05")
			(pintype "passive")
		)
		(pad "J06" smd circle
			(at 18.415 -4.445 90)
			(size 0.64 0.64)
			(layers "B.Cu" "B.Mask")
			(net 466 "unconnected-(J18-PadJ06)")
			(pinfunction "J06")
			(pintype "passive+no_connect")
		)
		(pad "J07" smd circle
			(at 17.145 -4.445 90)
			(size 0.64 0.64)
			(layers "B.Cu" "B.Mask")
			(net 352 "unconnected-(J18-PadJ07)")
			(pinfunction "J07")
			(pintype "passive+no_connect")
		)
		(pad "J08" smd circle
			(at 15.875 -4.445 90)
			(size 0.64 0.64)
			(layers "B.Cu" "B.Mask")
			(net 1 "GND")
			(pinfunction "J08")
			(pintype "passive")
		)
		(pad "J09" smd circle
			(at 14.605 -4.445 90)
			(size 0.64 0.64)
			(layers "B.Cu" "B.Mask")
			(net 284 "unconnected-(J18-PadJ09)")
			(pinfunction "J09")
			(pintype "passive+no_connect")
		)
		(pad "J10" smd circle
			(at 13.335 -4.445 90)
			(size 0.64 0.64)
			(layers "B.Cu" "B.Mask")
			(net 380 "unconnected-(J18-PadJ10)")
			(pinfunction "J10")
			(pintype "passive+no_connect")
		)
		(pad "J11" smd circle
			(at 12.065 -4.445 90)
			(size 0.64 0.64)
			(layers "B.Cu" "B.Mask")
			(net 1 "GND")
			(pinfunction "J11")
			(pintype "passive")
		)
		(pad "J12" smd circle
			(at 10.795 -4.445 90)
			(size 0.64 0.64)
			(layers "B.Cu" "B.Mask")
			(net 365 "unconnected-(J18-PadJ12)")
			(pinfunction "J12")
			(pintype "passive+no_connect")
		)
		(pad "J13" smd circle
			(at 9.525 -4.445 90)
			(size 0.64 0.64)
			(layers "B.Cu" "B.Mask")
			(net 332 "unconnected-(J18-PadJ13)")
			(pinfunction "J13")
			(pintype "passive+no_connect")
		)
		(pad "J14" smd circle
			(at 8.255 -4.445 90)
			(size 0.64 0.64)
			(layers "B.Cu" "B.Mask")
			(net 1 "GND")
			(pinfunction "J14")
			(pintype "passive")
		)
		(pad "J15" smd circle
			(at 6.985 -4.445 90)
			(size 0.64 0.64)
			(layers "B.Cu" "B.Mask")
			(net 395 "unconnected-(J18-PadJ15)")
			(pinfunction "J15")
			(pintype "passive+no_connect")
		)
		(pad "J16" smd circle
			(at 5.715 -4.445 90)
			(size 0.64 0.64)
			(layers "B.Cu" "B.Mask")
			(net 396 "unconnected-(J18-PadJ16)")
			(pinfunction "J16")
			(pintype "passive+no_connect")
		)
		(pad "J17" smd circle
			(at 4.445 -4.445 90)
			(size 0.64 0.64)
			(layers "B.Cu" "B.Mask")
			(net 1 "GND")
			(pinfunction "J17")
			(pintype "passive")
		)
		(pad "J18" smd circle
			(at 3.175 -4.445 90)
			(size 0.64 0.64)
			(layers "B.Cu" "B.Mask")
			(net 377 "unconnected-(J18-PadJ18)")
			(pinfunction "J18")
			(pintype "passive+no_connect")
		)
		(pad "J19" smd circle
			(at 1.905 -4.445 90)
			(size 0.64 0.64)
			(layers "B.Cu" "B.Mask")
			(net 461 "unconnected-(J18-PadJ19)")
			(pinfunction "J19")
			(pintype "passive+no_connect")
		)
		(pad "J20" smd circle
			(at 0.635 -4.445 90)
			(size 0.64 0.64)
			(layers "B.Cu" "B.Mask")
			(net 1 "GND")
			(pinfunction "J20")
			(pintype "passive")
		)
		(pad "J21" smd circle
			(at -0.635 -4.445 90)
			(size 0.64 0.64)
			(layers "B.Cu" "B.Mask")
			(net 298 "unconnected-(J18-PadJ21)")
			(pinfunction "J21")
			(pintype "passive+no_connect")
		)
		(pad "J22" smd circle
			(at -1.905 -4.445 90)
			(size 0.64 0.64)
			(layers "B.Cu" "B.Mask")
			(net 296 "unconnected-(J18-PadJ22)")
			(pinfunction "J22")
			(pintype "passive+no_connect")
		)
		(pad "J23" smd circle
			(at -3.175 -4.445 90)
			(size 0.64 0.64)
			(layers "B.Cu" "B.Mask")
			(net 1 "GND")
			(pinfunction "J23")
			(pintype "passive")
		)
		(pad "J24" smd circle
			(at -4.445 -4.445 90)
			(size 0.64 0.64)
			(layers "B.Cu" "B.Mask")
			(net 343 "unconnected-(J18-PadJ24)")
			(pinfunction "J24")
			(pintype "passive+no_connect")
		)
		(pad "J25" smd circle
			(at -5.715 -4.445 90)
			(size 0.64 0.64)
			(layers "B.Cu" "B.Mask")
			(net 351 "unconnected-(J18-PadJ25)")
			(pinfunction "J25")
			(pintype "passive+no_connect")
		)
		(pad "J26" smd circle
			(at -6.985 -4.445 90)
			(size 0.64 0.64)
			(layers "B.Cu" "B.Mask")
			(net 1 "GND")
			(pinfunction "J26")
			(pintype "passive")
		)
		(pad "J27" smd circle
			(at -8.255 -4.445 90)
			(size 0.64 0.64)
			(layers "B.Cu" "B.Mask")
			(net 420 "unconnected-(J18-PadJ27)")
			(pinfunction "J27")
			(pintype "passive+no_connect")
		)
		(pad "J28" smd circle
			(at -9.525 -4.445 90)
			(size 0.64 0.64)
			(layers "B.Cu" "B.Mask")
			(net 367 "unconnected-(J18-PadJ28)")
			(pinfunction "J28")
			(pintype "passive+no_connect")
		)
		(pad "J29" smd circle
			(at -10.795 -4.445 90)
			(size 0.64 0.64)
			(layers "B.Cu" "B.Mask")
			(net 1 "GND")
			(pinfunction "J29")
			(pintype "passive")
		)
		(pad "J30" smd circle
			(at -12.065 -4.445 90)
			(size 0.64 0.64)
			(layers "B.Cu" "B.Mask")
			(net 318 "unconnected-(J18-PadJ30)")
			(pinfunction "J30")
			(pintype "passive+no_connect")
		)
		(pad "J31" smd circle
			(at -13.335 -4.445 90)
			(size 0.64 0.64)
			(layers "B.Cu" "B.Mask")
			(net 388 "unconnected-(J18-PadJ31)")
			(pinfunction "J31")
			(pintype "passive+no_connect")
		)
		(pad "J32" smd circle
			(at -14.605 -4.445 90)
			(size 0.64 0.64)
			(layers "B.Cu" "B.Mask")
			(net 1 "GND")
			(pinfunction "J32")
			(pintype "passive")
		)
		(pad "J33" smd circle
			(at -15.875 -4.445 90)
			(size 0.64 0.64)
			(layers "B.Cu" "B.Mask")
			(net 458 "unconnected-(J18-PadJ33)")
			(pinfunction "J33")
			(pintype "passive+no_connect")
		)
		(pad "J34" smd circle
			(at -17.145 -4.445 90)
			(size 0.64 0.64)
			(layers "B.Cu" "B.Mask")
			(net 378 "unconnected-(J18-PadJ34)")
			(pinfunction "J34")
			(pintype "passive+no_connect")
		)
		(pad "J35" smd circle
			(at -18.415 -4.445 90)
			(size 0.64 0.64)
			(layers "B.Cu" "B.Mask")
			(net 1 "GND")
			(pinfunction "J35")
			(pintype "passive")
		)
		(pad "J36" smd circle
			(at -19.685 -4.445 90)
			(size 0.64 0.64)
			(layers "B.Cu" "B.Mask")
			(net 460 "unconnected-(J18-PadJ36)")
			(pinfunction "J36")
			(pintype "passive+no_connect")
		)
		(pad "J37" smd circle
			(at -20.955 -4.445 90)
			(size 0.64 0.64)
			(layers "B.Cu" "B.Mask")
			(net 470 "unconnected-(J18-PadJ37)")
			(pinfunction "J37")
			(pintype "passive+no_connect")
		)
		(pad "J38" smd circle
			(at -22.225 -4.445 90)
			(size 0.64 0.64)
			(layers "B.Cu" "B.Mask")
			(net 1 "GND")
			(pinfunction "J38")
			(pintype "passive")
		)
		(pad "J39" smd circle
			(at -23.495 -4.445 90)
			(size 0.64 0.64)
			(layers "B.Cu" "B.Mask")
			(net 450 "Net-(J18-PadJ39)")
			(pinfunction "J39")
			(pintype "passive")
		)
		(pad "J40" smd circle
			(at -24.765 -4.445 90)
			(size 0.64 0.64)
			(layers "B.Cu" "B.Mask")
			(net 1 "GND")
			(pinfunction "J40")
			(pintype "passive")
		)
		(pad "K01" smd circle
			(at 24.765 -5.715 90)
			(size 0.64 0.64)
			(layers "B.Cu" "B.Mask")
			(net 753 "Net-(J18-PadK01)")
			(pinfunction "K01")
			(pintype "passive")
		)
		(pad "K02" smd circle
			(at 23.495 -5.715 90)
			(size 0.64 0.64)
			(layers "B.Cu" "B.Mask")
			(net 1 "GND")
			(pinfunction "K02")
			(pintype "passive")
		)
		(pad "K03" smd circle
			(at 22.225 -5.715 90)
			(size 0.64 0.64)
			(layers "B.Cu" "B.Mask")
			(net 1 "GND")
			(pinfunction "K03")
			(pintype "passive")
		)
		(pad "K04" smd circle
			(at 20.955 -5.715 90)
			(size 0.64 0.64)
			(layers "B.Cu" "B.Mask")
			(net 366 "unconnected-(J18-PadK04)")
			(pinfunction "K04")
			(pintype "passive+no_connect")
		)
		(pad "K05" smd circle
			(at 19.685 -5.715 90)
			(size 0.64 0.64)
			(layers "B.Cu" "B.Mask")
			(net 426 "unconnected-(J18-PadK05)")
			(pinfunction "K05")
			(pintype "passive+no_connect")
		)
		(pad "K06" smd circle
			(at 18.415 -5.715 90)
			(size 0.64 0.64)
			(layers "B.Cu" "B.Mask")
			(net 1 "GND")
			(pinfunction "K06")
			(pintype "passive")
		)
		(pad "K07" smd circle
			(at 17.145 -5.715 90)
			(size 0.64 0.64)
			(layers "B.Cu" "B.Mask")
			(net 451 "unconnected-(J18-PadK07)")
			(pinfunction "K07")
			(pintype "passive+no_connect")
		)
		(pad "K08" smd circle
			(at 15.875 -5.715 90)
			(size 0.64 0.64)
			(layers "B.Cu" "B.Mask")
			(net 387 "unconnected-(J18-PadK08)")
			(pinfunction "K08")
			(pintype "passive+no_connect")
		)
		(pad "K09" smd circle
			(at 14.605 -5.715 90)
			(size 0.64 0.64)
			(layers "B.Cu" "B.Mask")
			(net 1 "GND")
			(pinfunction "K09")
			(pintype "passive")
		)
		(pad "K10" smd circle
			(at 13.335 -5.715 90)
			(size 0.64 0.64)
			(layers "B.Cu" "B.Mask")
			(net 486 "unconnected-(J18-PadK10)")
			(pinfunction "K10")
			(pintype "passive+no_connect")
		)
		(pad "K11" smd circle
			(at 12.065 -5.715 90)
			(size 0.64 0.64)
			(layers "B.Cu" "B.Mask")
			(net 406 "unconnected-(J18-PadK11)")
			(pinfunction "K11")
			(pintype "passive+no_connect")
		)
		(pad "K12" smd circle
			(at 10.795 -5.715 90)
			(size 0.64 0.64)
			(layers "B.Cu" "B.Mask")
			(net 1 "GND")
			(pinfunction "K12")
			(pintype "passive")
		)
		(pad "K13" smd circle
			(at 9.525 -5.715 90)
			(size 0.64 0.64)
			(layers "B.Cu" "B.Mask")
			(net 355 "unconnected-(J18-PadK13)")
			(pinfunction "K13")
			(pintype "passive+no_connect")
		)
		(pad "K14" smd circle
			(at 8.255 -5.715 90)
			(size 0.64 0.64)
			(layers "B.Cu" "B.Mask")
			(net 429 "unconnected-(J18-PadK14)")
			(pinfunction "K14")
			(pintype "passive+no_connect")
		)
		(pad "K15" smd circle
			(at 6.985 -5.715 90)
			(size 0.64 0.64)
			(layers "B.Cu" "B.Mask")
			(net 1 "GND")
			(pinfunction "K15")
			(pintype "passive")
		)
		(pad "K16" smd circle
			(at 5.715 -5.715 90)
			(size 0.64 0.64)
			(layers "B.Cu" "B.Mask")
			(net 338 "unconnected-(J18-PadK16)")
			(pinfunction "K16")
			(pintype "passive+no_connect")
		)
		(pad "K17" smd circle
			(at 4.445 -5.715 90)
			(size 0.64 0.64)
			(layers "B.Cu" "B.Mask")
			(net 323 "unconnected-(J18-PadK17)")
			(pinfunction "K17")
			(pintype "passive+no_connect")
		)
		(pad "K18" smd circle
			(at 3.175 -5.715 90)
			(size 0.64 0.64)
			(layers "B.Cu" "B.Mask")
			(net 1 "GND")
			(pinfunction "K18")
			(pintype "passive")
		)
		(pad "K19" smd circle
			(at 1.905 -5.715 90)
			(size 0.64 0.64)
			(layers "B.Cu" "B.Mask")
			(net 315 "unconnected-(J18-PadK19)")
			(pinfunction "K19")
			(pintype "passive+no_connect")
		)
		(pad "K20" smd circle
			(at 0.635 -5.715 90)
			(size 0.64 0.64)
			(layers "B.Cu" "B.Mask")
			(net 463 "unconnected-(J18-PadK20)")
			(pinfunction "K20")
			(pintype "passive+no_connect")
		)
		(pad "K21" smd circle
			(at -0.635 -5.715 90)
			(size 0.64 0.64)
			(layers "B.Cu" "B.Mask")
			(net 1 "GND")
			(pinfunction "K21")
			(pintype "passive")
		)
		(pad "K22" smd circle
			(at -1.905 -5.715 90)
			(size 0.64 0.64)
			(layers "B.Cu" "B.Mask")
			(net 291 "unconnected-(J18-PadK22)")
			(pinfunction "K22")
			(pintype "passive+no_connect")
		)
		(pad "K23" smd circle
			(at -3.175 -5.715 90)
			(size 0.64 0.64)
			(layers "B.Cu" "B.Mask")
			(net 286 "unconnected-(J18-PadK23)")
			(pinfunction "K23")
			(pintype "passive+no_connect")
		)
		(pad "K24" smd circle
			(at -4.445 -5.715 90)
			(size 0.64 0.64)
			(layers "B.Cu" "B.Mask")
			(net 1 "GND")
			(pinfunction "K24")
			(pintype "passive")
		)
		(pad "K25" smd circle
			(at -5.715 -5.715 90)
			(size 0.64 0.64)
			(layers "B.Cu" "B.Mask")
			(net 394 "unconnected-(J18-PadK25)")
			(pinfunction "K25")
			(pintype "passive+no_connect")
		)
		(pad "K26" smd circle
			(at -6.985 -5.715 90)
			(size 0.64 0.64)
			(layers "B.Cu" "B.Mask")
			(net 442 "unconnected-(J18-PadK26)")
			(pinfunction "K26")
			(pintype "passive+no_connect")
		)
		(pad "K27" smd circle
			(at -8.255 -5.715 90)
			(size 0.64 0.64)
			(layers "B.Cu" "B.Mask")
			(net 1 "GND")
			(pinfunction "K27")
			(pintype "passive")
		)
		(pad "K28" smd circle
			(at -9.525 -5.715 90)
			(size 0.64 0.64)
			(layers "B.Cu" "B.Mask")
			(net 301 "unconnected-(J18-PadK28)")
			(pinfunction "K28")
			(pintype "passive+no_connect")
		)
		(pad "K29" smd circle
			(at -10.795 -5.715 90)
			(size 0.64 0.64)
			(layers "B.Cu" "B.Mask")
			(net 369 "unconnected-(J18-PadK29)")
			(pinfunction "K29")
			(pintype "passive+no_connect")
		)
		(pad "K30" smd circle
			(at -12.065 -5.715 90)
			(size 0.64 0.64)
			(layers "B.Cu" "B.Mask")
			(net 1 "GND")
			(pinfunction "K30")
			(pintype "passive")
		)
		(pad "K31" smd circle
			(at -13.335 -5.715 90)
			(size 0.64 0.64)
			(layers "B.Cu" "B.Mask")
			(net 335 "unconnected-(J18-PadK31)")
			(pinfunction "K31")
			(pintype "passive+no_connect")
		)
		(pad "K32" smd circle
			(at -14.605 -5.715 90)
			(size 0.64 0.64)
			(layers "B.Cu" "B.Mask")
			(net 430 "unconnected-(J18-PadK32)")
			(pinfunction "K32")
			(pintype "passive+no_connect")
		)
		(pad "K33" smd circle
			(at -15.875 -5.715 90)
			(size 0.64 0.64)
			(layers "B.Cu" "B.Mask")
			(net 1 "GND")
			(pinfunction "K33")
			(pintype "passive")
		)
		(pad "K34" smd circle
			(at -17.145 -5.715 90)
			(size 0.64 0.64)
			(layers "B.Cu" "B.Mask")
			(net 373 "unconnected-(J18-PadK34)")
			(pinfunction "K34")
			(pintype "passive+no_connect")
		)
		(pad "K35" smd circle
			(at -18.415 -5.715 90)
			(size 0.64 0.64)
			(layers "B.Cu" "B.Mask")
			(net 306 "unconnected-(J18-PadK35)")
			(pinfunction "K35")
			(pintype "passive+no_connect")
		)
		(pad "K36" smd circle
			(at -19.685 -5.715 90)
			(size 0.64 0.64)
			(layers "B.Cu" "B.Mask")
			(net 1 "GND")
			(pinfunction "K36")
			(pintype "passive")
		)
		(pad "K37" smd circle
			(at -20.955 -5.715 90)
			(size 0.64 0.64)
			(layers "B.Cu" "B.Mask")
			(net 336 "unconnected-(J18-PadK37)")
			(pinfunction "K37")
			(pintype "passive+no_connect")
		)
		(pad "K38" smd circle
			(at -22.225 -5.715 90)
			(size 0.64 0.64)
			(layers "B.Cu" "B.Mask")
			(net 328 "unconnected-(J18-PadK38)")
			(pinfunction "K38")
			(pintype "passive+no_connect")
		)
		(pad "K39" smd circle
			(at -23.495 -5.715 90)
			(size 0.64 0.64)
			(layers "B.Cu" "B.Mask")
			(net 1 "GND")
			(pinfunction "K39")
			(pintype "passive")
		)
		(pad "K40" smd circle
			(at -24.765 -5.715 90)
			(size 0.64 0.64)
			(layers "B.Cu" "B.Mask")
			(net 360 "Net-(J18-PadK40)")
			(pinfunction "K40")
			(pintype "passive")
		)
		(pad "L01" smd circle
			(at 24.765 -6.985 90)
			(size 0.64 0.64)
			(layers "B.Cu" "B.Mask")
			(net 717 "Net-(J18-PadL01)")
			(pinfunction "L01")
			(pintype "passive")
		)
		(pad "L02" smd circle
			(at 23.495 -6.985 90)
			(size 0.64 0.64)
			(layers "B.Cu" "B.Mask")
			(net 1 "GND")
			(pinfunction "L02")
			(pintype "passive")
		)
		(pad "L03" smd circle
			(at 22.225 -6.985 90)
			(size 0.64 0.64)
			(layers "B.Cu" "B.Mask")
			(net 1 "GND")
			(pinfunction "L03")
			(pintype "passive")
		)
		(pad "L04" smd circle
			(at 20.955 -6.985 90)
			(size 0.64 0.64)
			(layers "B.Cu" "B.Mask")
			(net 462 "unconnected-(J18-PadL04)")
			(pinfunction "L04")
			(pintype "passive+no_connect")
		)
		(pad "L05" smd circle
			(at 19.685 -6.985 90)
			(size 0.64 0.64)
			(layers "B.Cu" "B.Mask")
			(net 419 "unconnected-(J18-PadL05)")
			(pinfunction "L05")
			(pintype "passive+no_connect")
		)
		(pad "L06" smd circle
			(at 18.415 -6.985 90)
			(size 0.64 0.64)
			(layers "B.Cu" "B.Mask")
			(net 1 "GND")
			(pinfunction "L06")
			(pintype "passive")
		)
		(pad "L07" smd circle
			(at 17.145 -6.985 90)
			(size 0.64 0.64)
			(layers "B.Cu" "B.Mask")
			(net 1 "GND")
			(pinfunction "L07")
			(pintype "passive")
		)
		(pad "L08" smd circle
			(at 15.875 -6.985 90)
			(size 0.64 0.64)
			(layers "B.Cu" "B.Mask")
			(net 1361 "unconnected-(J18-PadL08)")
			(pinfunction "L08")
			(pintype "passive+no_connect")
		)
		(pad "L09" smd circle
			(at 14.605 -6.985 90)
			(size 0.64 0.64)
			(layers "B.Cu" "B.Mask")
			(net 1343 "unconnected-(J18-PadL09)")
			(pinfunction "L09")
			(pintype "passive+no_connect")
		)
		(pad "L10" smd circle
			(at 13.335 -6.985 90)
			(size 0.64 0.64)
			(layers "B.Cu" "B.Mask")
			(net 1 "GND")
			(pinfunction "L10")
			(pintype "passive")
		)
		(pad "L11" smd circle
			(at 12.065 -6.985 90)
			(size 0.64 0.64)
			(layers "B.Cu" "B.Mask")
			(net 1 "GND")
			(pinfunction "L11")
			(pintype "passive")
		)
		(pad "L12" smd circle
			(at 10.795 -6.985 90)
			(size 0.64 0.64)
			(layers "B.Cu" "B.Mask")
			(net 1356 "unconnected-(J18-PadL12)")
			(pinfunction "L12")
			(pintype "passive+no_connect")
		)
		(pad "L13" smd circle
			(at 9.525 -6.985 90)
			(size 0.64 0.64)
			(layers "B.Cu" "B.Mask")
			(net 1342 "unconnected-(J18-PadL13)")
			(pinfunction "L13")
			(pintype "passive+no_connect")
		)
		(pad "L14" smd circle
			(at 8.255 -6.985 90)
			(size 0.64 0.64)
			(layers "B.Cu" "B.Mask")
			(net 1 "GND")
			(pinfunction "L14")
			(pintype "passive")
		)
		(pad "L15" smd circle
			(at 6.985 -6.985 90)
			(size 0.64 0.64)
			(layers "B.Cu" "B.Mask")
			(net 1 "GND")
			(pinfunction "L15")
			(pintype "passive")
		)
		(pad "L16" smd circle
			(at 5.715 -6.985 90)
			(size 0.64 0.64)
			(layers "B.Cu" "B.Mask")
			(net 389 "unconnected-(J18-PadL16)")
			(pinfunction "L16")
			(pintype "passive+no_connect")
		)
		(pad "L17" smd circle
			(at 4.445 -6.985 90)
			(size 0.64 0.64)
			(layers "B.Cu" "B.Mask")
			(net 433 "unconnected-(J18-PadL17)")
			(pinfunction "L17")
			(pintype "passive+no_connect")
		)
		(pad "L18" smd circle
			(at 3.175 -6.985 90)
			(size 0.64 0.64)
			(layers "B.Cu" "B.Mask")
			(net 1 "GND")
			(pinfunction "L18")
			(pintype "passive")
		)
		(pad "L19" smd circle
			(at 1.905 -6.985 90)
			(size 0.64 0.64)
			(layers "B.Cu" "B.Mask")
			(net 1 "GND")
			(pinfunction "L19")
			(pintype "passive")
		)
		(pad "L20" smd circle
			(at 0.635 -6.985 90)
			(size 0.64 0.64)
			(layers "B.Cu" "B.Mask")
			(net 327 "unconnected-(J18-PadL20)")
			(pinfunction "L20")
			(pintype "passive+no_connect")
		)
		(pad "L21" smd circle
			(at -0.635 -6.985 90)
			(size 0.64 0.64)
			(layers "B.Cu" "B.Mask")
			(net 303 "unconnected-(J18-PadL21)")
			(pinfunction "L21")
			(pintype "passive+no_connect")
		)
		(pad "L22" smd circle
			(at -1.905 -6.985 90)
			(size 0.64 0.64)
			(layers "B.Cu" "B.Mask")
			(net 1 "GND")
			(pinfunction "L22")
			(pintype "passive")
		)
		(pad "L23" smd circle
			(at -3.175 -6.985 90)
			(size 0.64 0.64)
			(layers "B.Cu" "B.Mask")
			(net 1 "GND")
			(pinfunction "L23")
			(pintype "passive")
		)
		(pad "L24" smd circle
			(at -4.445 -6.985 90)
			(size 0.64 0.64)
			(layers "B.Cu" "B.Mask")
			(net 1351 "unconnected-(J18-PadL24)")
			(pinfunction "L24")
			(pintype "passive+no_connect")
		)
		(pad "L25" smd circle
			(at -5.715 -6.985 90)
			(size 0.64 0.64)
			(layers "B.Cu" "B.Mask")
			(net 1346 "unconnected-(J18-PadL25)")
			(pinfunction "L25")
			(pintype "passive+no_connect")
		)
		(pad "L26" smd circle
			(at -6.985 -6.985 90)
			(size 0.64 0.64)
			(layers "B.Cu" "B.Mask")
			(net 1 "GND")
			(pinfunction "L26")
			(pintype "passive")
		)
		(pad "L27" smd circle
			(at -8.255 -6.985 90)
			(size 0.64 0.64)
			(layers "B.Cu" "B.Mask")
			(net 1 "GND")
			(pinfunction "L27")
			(pintype "passive")
		)
		(pad "L28" smd circle
			(at -9.525 -6.985 90)
			(size 0.64 0.64)
			(layers "B.Cu" "B.Mask")
			(net 1344 "unconnected-(J18-PadL28)")
			(pinfunction "L28")
			(pintype "passive+no_connect")
		)
		(pad "L29" smd circle
			(at -10.795 -6.985 90)
			(size 0.64 0.64)
			(layers "B.Cu" "B.Mask")
			(net 1352 "unconnected-(J18-PadL29)")
			(pinfunction "L29")
			(pintype "passive+no_connect")
		)
		(pad "L30" smd circle
			(at -12.065 -6.985 90)
			(size 0.64 0.64)
			(layers "B.Cu" "B.Mask")
			(net 1 "GND")
			(pinfunction "L30")
			(pintype "passive")
		)
		(pad "L31" smd circle
			(at -13.335 -6.985 90)
			(size 0.64 0.64)
			(layers "B.Cu" "B.Mask")
			(net 1 "GND")
			(pinfunction "L31")
			(pintype "passive")
		)
		(pad "L32" smd circle
			(at -14.605 -6.985 90)
			(size 0.64 0.64)
			(layers "B.Cu" "B.Mask")
			(net 571 "Net-(J18-PadL32)")
			(pinfunction "L32")
			(pintype "passive")
		)
		(pad "L33" smd circle
			(at -15.875 -6.985 90)
			(size 0.64 0.64)
			(layers "B.Cu" "B.Mask")
			(net 709 "Net-(J18-PadL33)")
			(pinfunction "L33")
			(pintype "passive")
		)
		(pad "L34" smd circle
			(at -17.145 -6.985 90)
			(size 0.64 0.64)
			(layers "B.Cu" "B.Mask")
			(net 1 "GND")
			(pinfunction "L34")
			(pintype "passive")
		)
		(pad "L35" smd circle
			(at -18.415 -6.985 90)
			(size 0.64 0.64)
			(layers "B.Cu" "B.Mask")
			(net 1 "GND")
			(pinfunction "L35")
			(pintype "passive")
		)
		(pad "L36" smd circle
			(at -19.685 -6.985 90)
			(size 0.64 0.64)
			(layers "B.Cu" "B.Mask")
			(net 289 "/Expansion connector/+12V_FMC")
			(pinfunction "L36")
			(pintype "passive")
		)
		(pad "L37" smd circle
			(at -20.955 -6.985 90)
			(size 0.64 0.64)
			(layers "B.Cu" "B.Mask")
			(net 289 "/Expansion connector/+12V_FMC")
			(pinfunction "L37")
			(pintype "passive")
		)
		(pad "L38" smd circle
			(at -22.225 -6.985 90)
			(size 0.64 0.64)
			(layers "B.Cu" "B.Mask")
			(net 1 "GND")
			(pinfunction "L38")
			(pintype "passive")
		)
		(pad "L39" smd circle
			(at -23.495 -6.985 90)
			(size 0.64 0.64)
			(layers "B.Cu" "B.Mask")
			(net 1 "GND")
			(pinfunction "L39")
			(pintype "passive")
		)
		(pad "L40" smd circle
			(at -24.765 -6.985 90)
			(size 0.64 0.64)
			(layers "B.Cu" "B.Mask")
			(net 289 "/Expansion connector/+12V_FMC")
			(pinfunction "L40")
			(pintype "passive")
		)
		(pad "M01" smd circle
			(at 24.765 -8.255 90)
			(size 0.64 0.64)
			(layers "B.Cu" "B.Mask")
			(net 1 "GND")
			(pinfunction "M01")
			(pintype "passive")
		)
		(pad "M02" smd circle
			(at 23.495 -8.255 90)
			(size 0.64 0.64)
			(layers "B.Cu" "B.Mask")
			(net 453 "unconnected-(J18-PadM02)")
			(pinfunction "M02")
			(pintype "passive+no_connect")
		)
		(pad "M03" smd circle
			(at 22.225 -8.255 90)
			(size 0.64 0.64)
			(layers "B.Cu" "B.Mask")
			(net 485 "unconnected-(J18-PadM03)")
			(pinfunction "M03")
			(pintype "passive+no_connect")
		)
		(pad "M04" smd circle
			(at 20.955 -8.255 90)
			(size 0.64 0.64)
			(layers "B.Cu" "B.Mask")
			(net 1 "GND")
			(pinfunction "M04")
			(pintype "passive")
		)
		(pad "M05" smd circle
			(at 19.685 -8.255 90)
			(size 0.64 0.64)
			(layers "B.Cu" "B.Mask")
			(net 1 "GND")
			(pinfunction "M05")
			(pintype "passive")
		)
		(pad "M06" smd circle
			(at 18.415 -8.255 90)
			(size 0.64 0.64)
			(layers "B.Cu" "B.Mask")
			(net 348 "unconnected-(J18-PadM06)")
			(pinfunction "M06")
			(pintype "passive+no_connect")
		)
		(pad "M07" smd circle
			(at 17.145 -8.255 90)
			(size 0.64 0.64)
			(layers "B.Cu" "B.Mask")
			(net 414 "unconnected-(J18-PadM07)")
			(pinfunction "M07")
			(pintype "passive+no_connect")
		)
		(pad "M08" smd circle
			(at 15.875 -8.255 90)
			(size 0.64 0.64)
			(layers "B.Cu" "B.Mask")
			(net 1 "GND")
			(pinfunction "M08")
			(pintype "passive")
		)
		(pad "M09" smd circle
			(at 14.605 -8.255 90)
			(size 0.64 0.64)
			(layers "B.Cu" "B.Mask")
			(net 1 "GND")
			(pinfunction "M09")
			(pintype "passive")
		)
		(pad "M10" smd circle
			(at 13.335 -8.255 90)
			(size 0.64 0.64)
			(layers "B.Cu" "B.Mask")
			(net 1341 "unconnected-(J18-PadM10)")
			(pinfunction "M10")
			(pintype "passive+no_connect")
		)
		(pad "M11" smd circle
			(at 12.065 -8.255 90)
			(size 0.64 0.64)
			(layers "B.Cu" "B.Mask")
			(net 1362 "unconnected-(J18-PadM11)")
			(pinfunction "M11")
			(pintype "passive+no_connect")
		)
		(pad "M12" smd circle
			(at 10.795 -8.255 90)
			(size 0.64 0.64)
			(layers "B.Cu" "B.Mask")
			(net 1 "GND")
			(pinfunction "M12")
			(pintype "passive")
		)
		(pad "M13" smd circle
			(at 9.525 -8.255 90)
			(size 0.64 0.64)
			(layers "B.Cu" "B.Mask")
			(net 1 "GND")
			(pinfunction "M13")
			(pintype "passive")
		)
		(pad "M14" smd circle
			(at 8.255 -8.255 90)
			(size 0.64 0.64)
			(layers "B.Cu" "B.Mask")
			(net 1359 "unconnected-(J18-PadM14)")
			(pinfunction "M14")
			(pintype "passive+no_connect")
		)
		(pad "M15" smd circle
			(at 6.985 -8.255 90)
			(size 0.64 0.64)
			(layers "B.Cu" "B.Mask")
			(net 1350 "unconnected-(J18-PadM15)")
			(pinfunction "M15")
			(pintype "passive+no_connect")
		)
		(pad "M16" smd circle
			(at 5.715 -8.255 90)
			(size 0.64 0.64)
			(layers "B.Cu" "B.Mask")
			(net 1 "GND")
			(pinfunction "M16")
			(pintype "passive")
		)
		(pad "M17" smd circle
			(at 4.445 -8.255 90)
			(size 0.64 0.64)
			(layers "B.Cu" "B.Mask")
			(net 1 "GND")
			(pinfunction "M17")
			(pintype "passive")
		)
		(pad "M18" smd circle
			(at 3.175 -8.255 90)
			(size 0.64 0.64)
			(layers "B.Cu" "B.Mask")
			(net 1345 "unconnected-(J18-PadM18)")
			(pinfunction "M18")
			(pintype "passive+no_connect")
		)
		(pad "M19" smd circle
			(at 1.905 -8.255 90)
			(size 0.64 0.64)
			(layers "B.Cu" "B.Mask")
			(net 1347 "unconnected-(J18-PadM19)")
			(pinfunction "M19")
			(pintype "passive+no_connect")
		)
		(pad "M20" smd circle
			(at 0.635 -8.255 90)
			(size 0.64 0.64)
			(layers "B.Cu" "B.Mask")
			(net 1 "GND")
			(pinfunction "M20")
			(pintype "passive")
		)
		(pad "M21" smd circle
			(at -0.635 -8.255 90)
			(size 0.64 0.64)
			(layers "B.Cu" "B.Mask")
			(net 1 "GND")
			(pinfunction "M21")
			(pintype "passive")
		)
		(pad "M22" smd circle
			(at -1.905 -8.255 90)
			(size 0.64 0.64)
			(layers "B.Cu" "B.Mask")
			(net 1349 "unconnected-(J18-PadM22)")
			(pinfunction "M22")
			(pintype "passive+no_connect")
		)
		(pad "M23" smd circle
			(at -3.175 -8.255 90)
			(size 0.64 0.64)
			(layers "B.Cu" "B.Mask")
			(net 1358 "unconnected-(J18-PadM23)")
			(pinfunction "M23")
			(pintype "passive+no_connect")
		)
		(pad "M24" smd circle
			(at -4.445 -8.255 90)
			(size 0.64 0.64)
			(layers "B.Cu" "B.Mask")
			(net 1 "GND")
			(pinfunction "M24")
			(pintype "passive")
		)
		(pad "M25" smd circle
			(at -5.715 -8.255 90)
			(size 0.64 0.64)
			(layers "B.Cu" "B.Mask")
			(net 1 "GND")
			(pinfunction "M25")
			(pintype "passive")
		)
		(pad "M26" smd circle
			(at -6.985 -8.255 90)
			(size 0.64 0.64)
			(layers "B.Cu" "B.Mask")
			(net 1365 "unconnected-(J18-PadM26)")
			(pinfunction "M26")
			(pintype "passive+no_connect")
		)
		(pad "M27" smd circle
			(at -8.255 -8.255 90)
			(size 0.64 0.64)
			(layers "B.Cu" "B.Mask")
			(net 1364 "unconnected-(J18-PadM27)")
			(pinfunction "M27")
			(pintype "passive+no_connect")
		)
		(pad "M28" smd circle
			(at -9.525 -8.255 90)
			(size 0.64 0.64)
			(layers "B.Cu" "B.Mask")
			(net 1 "GND")
			(pinfunction "M28")
			(pintype "passive")
		)
		(pad "M29" smd circle
			(at -10.795 -8.255 90)
			(size 0.64 0.64)
			(layers "B.Cu" "B.Mask")
			(net 1 "GND")
			(pinfunction "M29")
			(pintype "passive")
		)
		(pad "M30" smd circle
			(at -12.065 -8.255 90)
			(size 0.64 0.64)
			(layers "B.Cu" "B.Mask")
			(net 1363 "unconnected-(J18-PadM30)")
			(pinfunction "M30")
			(pintype "passive+no_connect")
		)
		(pad "M31" smd circle
			(at -13.335 -8.255 90)
			(size 0.64 0.64)
			(layers "B.Cu" "B.Mask")
			(net 1353 "unconnected-(J18-PadM31)")
			(pinfunction "M31")
			(pintype "passive+no_connect")
		)
		(pad "M32" smd circle
			(at -14.605 -8.255 90)
			(size 0.64 0.64)
			(layers "B.Cu" "B.Mask")
			(net 1 "GND")
			(pinfunction "M32")
			(pintype "passive")
		)
		(pad "M33" smd circle
			(at -15.875 -8.255 90)
			(size 0.64 0.64)
			(layers "B.Cu" "B.Mask")
			(net 1 "GND")
			(pinfunction "M33")
			(pintype "passive")
		)
		(pad "M34" smd circle
			(at -17.145 -8.255 90)
			(size 0.64 0.64)
			(layers "B.Cu" "B.Mask")
			(net 1348 "unconnected-(J18-PadM34)")
			(pinfunction "M34")
			(pintype "passive+no_connect")
		)
		(pad "M35" smd circle
			(at -18.415 -8.255 90)
			(size 0.64 0.64)
			(layers "B.Cu" "B.Mask")
			(net 1354 "unconnected-(J18-PadM35)")
			(pinfunction "M35")
			(pintype "passive+no_connect")
		)
		(pad "M36" smd circle
			(at -19.685 -8.255 90)
			(size 0.64 0.64)
			(layers "B.Cu" "B.Mask")
			(net 1 "GND")
			(pinfunction "M36")
			(pintype "passive")
		)
		(pad "M37" smd circle
			(at -20.955 -8.255 90)
			(size 0.64 0.64)
			(layers "B.Cu" "B.Mask")
			(net 1 "GND")
			(pinfunction "M37")
			(pintype "passive")
		)
		(pad "M38" smd circle
			(at -22.225 -8.255 90)
			(size 0.64 0.64)
			(layers "B.Cu" "B.Mask")
			(net 1355 "unconnected-(J18-PadM38)")
			(pinfunction "M38")
			(pintype "passive+no_connect")
		)
		(pad "M39" smd circle
			(at -23.495 -8.255 90)
			(size 0.64 0.64)
			(layers "B.Cu" "B.Mask")
			(net 1357 "unconnected-(J18-PadM39)")
			(pinfunction "M39")
			(pintype "passive+no_connect")
		)
		(pad "M40" smd circle
			(at -24.765 -8.255 90)
			(size 0.64 0.64)
			(layers "B.Cu" "B.Mask")
			(net 1 "GND")
			(pinfunction "M40")
			(pintype "passive")
		)
		(pad "Y01" smd circle
			(at 24.765 8.255 90)
			(size 0.64 0.64)
			(layers "B.Cu" "B.Mask")
			(net 1 "GND")
			(pinfunction "Y01")
			(pintype "passive")
		)
		(pad "Y02" smd circle
			(at 23.495 8.255 90)
			(size 0.64 0.64)
			(layers "B.Cu" "B.Mask")
			(net 350 "unconnected-(J18-PadY02)")
			(pinfunction "Y02")
			(pintype "passive+no_connect")
		)
		(pad "Y03" smd circle
			(at 22.225 8.255 90)
			(size 0.64 0.64)
			(layers "B.Cu" "B.Mask")
			(net 359 "unconnected-(J18-PadY03)")
			(pinfunction "Y03")
			(pintype "passive+no_connect")
		)
		(pad "Y04" smd circle
			(at 20.955 8.255 90)
			(size 0.64 0.64)
			(layers "B.Cu" "B.Mask")
			(net 1 "GND")
			(pinfunction "Y04")
			(pintype "passive")
		)
		(pad "Y05" smd circle
			(at 19.685 8.255 90)
			(size 0.64 0.64)
			(layers "B.Cu" "B.Mask")
			(net 1 "GND")
			(pinfunction "Y05")
			(pintype "passive")
		)
		(pad "Y06" smd circle
			(at 18.415 8.255 90)
			(size 0.64 0.64)
			(layers "B.Cu" "B.Mask")
			(net 325 "unconnected-(J18-PadY06)")
			(pinfunction "Y06")
			(pintype "passive+no_connect")
		)
		(pad "Y07" smd circle
			(at 17.145 8.255 90)
			(size 0.64 0.64)
			(layers "B.Cu" "B.Mask")
			(net 398 "unconnected-(J18-PadY07)")
			(pinfunction "Y07")
			(pintype "passive+no_connect")
		)
		(pad "Y08" smd circle
			(at 15.875 8.255 90)
			(size 0.64 0.64)
			(layers "B.Cu" "B.Mask")
			(net 1 "GND")
			(pinfunction "Y08")
			(pintype "passive")
		)
		(pad "Y09" smd circle
			(at 14.605 8.255 90)
			(size 0.64 0.64)
			(layers "B.Cu" "B.Mask")
			(net 1 "GND")
			(pinfunction "Y09")
			(pintype "passive")
		)
		(pad "Y10" smd circle
			(at 13.335 8.255 90)
			(size 0.64 0.64)
			(layers "B.Cu" "B.Mask")
			(net 729 "/Expansion connector/DP1.AUX+")
			(pinfunction "Y10")
			(pintype "passive")
		)
		(pad "Y11" smd circle
			(at 12.065 8.255 90)
			(size 0.64 0.64)
			(layers "B.Cu" "B.Mask")
			(net 738 "/Expansion connector/DP1.AUX-")
			(pinfunction "Y11")
			(pintype "passive")
		)
		(pad "Y12" smd circle
			(at 10.795 8.255 90)
			(size 0.64 0.64)
			(layers "B.Cu" "B.Mask")
			(net 1 "GND")
			(pinfunction "Y12")
			(pintype "passive")
		)
		(pad "Y13" smd circle
			(at 9.525 8.255 90)
			(size 0.64 0.64)
			(layers "B.Cu" "B.Mask")
			(net 1 "GND")
			(pinfunction "Y13")
			(pintype "passive")
		)
		(pad "Y14" smd circle
			(at 8.255 8.255 90)
			(size 0.64 0.64)
			(layers "B.Cu" "B.Mask")
			(net 707 "/Expansion connector/DP1.TX0+")
			(pinfunction "Y14")
			(pintype "passive")
		)
		(pad "Y15" smd circle
			(at 6.985 8.255 90)
			(size 0.64 0.64)
			(layers "B.Cu" "B.Mask")
			(net 603 "/Expansion connector/DP1.TX0-")
			(pinfunction "Y15")
			(pintype "passive")
		)
		(pad "Y16" smd circle
			(at 5.715 8.255 90)
			(size 0.64 0.64)
			(layers "B.Cu" "B.Mask")
			(net 1 "GND")
			(pinfunction "Y16")
			(pintype "passive")
		)
		(pad "Y17" smd circle
			(at 4.445 8.255 90)
			(size 0.64 0.64)
			(layers "B.Cu" "B.Mask")
			(net 1 "GND")
			(pinfunction "Y17")
			(pintype "passive")
		)
		(pad "Y18" smd circle
			(at 3.175 8.255 90)
			(size 0.64 0.64)
			(layers "B.Cu" "B.Mask")
			(net 771 "/Expansion connector/DP1.TX1+")
			(pinfunction "Y18")
			(pintype "passive")
		)
		(pad "Y19" smd circle
			(at 1.905 8.255 90)
			(size 0.64 0.64)
			(layers "B.Cu" "B.Mask")
			(net 713 "/Expansion connector/DP1.TX1-")
			(pinfunction "Y19")
			(pintype "passive")
		)
		(pad "Y20" smd circle
			(at 0.635 8.255 90)
			(size 0.64 0.64)
			(layers "B.Cu" "B.Mask")
			(net 1 "GND")
			(pinfunction "Y20")
			(pintype "passive")
		)
		(pad "Y21" smd circle
			(at -0.635 8.255 90)
			(size 0.64 0.64)
			(layers "B.Cu" "B.Mask")
			(net 1 "GND")
			(pinfunction "Y21")
			(pintype "passive")
		)
		(pad "Y22" smd circle
			(at -1.905 8.255 90)
			(size 0.64 0.64)
			(layers "B.Cu" "B.Mask")
			(net 732 "/Expansion connector/PCIe_{C3x2}.CLK-")
			(pinfunction "Y22")
			(pintype "passive")
		)
		(pad "Y23" smd circle
			(at -3.175 8.255 90)
			(size 0.64 0.64)
			(layers "B.Cu" "B.Mask")
			(net 699 "/Expansion connector/PCIe_{C3x2}.CLK+")
			(pinfunction "Y23")
			(pintype "passive")
		)
		(pad "Y24" smd circle
			(at -4.445 8.255 90)
			(size 0.64 0.64)
			(layers "B.Cu" "B.Mask")
			(net 1 "GND")
			(pinfunction "Y24")
			(pintype "passive")
		)
		(pad "Y25" smd circle
			(at -5.715 8.255 90)
			(size 0.64 0.64)
			(layers "B.Cu" "B.Mask")
			(net 1 "GND")
			(pinfunction "Y25")
			(pintype "passive")
		)
		(pad "Y26" smd circle
			(at -6.985 8.255 90)
			(size 0.64 0.64)
			(layers "B.Cu" "B.Mask")
			(net 797 "/Expansion connector/PCIe_{C3x2}.RX0+")
			(pinfunction "Y26")
			(pintype "passive")
		)
		(pad "Y27" smd circle
			(at -8.255 8.255 90)
			(size 0.64 0.64)
			(layers "B.Cu" "B.Mask")
			(net 752 "/Expansion connector/PCIe_{C3x2}.RX0-")
			(pinfunction "Y27")
			(pintype "passive")
		)
		(pad "Y28" smd circle
			(at -9.525 8.255 90)
			(size 0.64 0.64)
			(layers "B.Cu" "B.Mask")
			(net 1 "GND")
			(pinfunction "Y28")
			(pintype "passive")
		)
		(pad "Y29" smd circle
			(at -10.795 8.255 90)
			(size 0.64 0.64)
			(layers "B.Cu" "B.Mask")
			(net 1 "GND")
			(pinfunction "Y29")
			(pintype "passive")
		)
		(pad "Y30" smd circle
			(at -12.065 8.255 90)
			(size 0.64 0.64)
			(layers "B.Cu" "B.Mask")
			(net 782 "/Expansion connector/PCIe_{C3x2}.RX1+")
			(pinfunction "Y30")
			(pintype "passive")
		)
		(pad "Y31" smd circle
			(at -13.335 8.255 90)
			(size 0.64 0.64)
			(layers "B.Cu" "B.Mask")
			(net 722 "/Expansion connector/PCIe_{C3x2}.RX1-")
			(pinfunction "Y31")
			(pintype "passive")
		)
		(pad "Y32" smd circle
			(at -14.605 8.255 90)
			(size 0.64 0.64)
			(layers "B.Cu" "B.Mask")
			(net 1 "GND")
			(pinfunction "Y32")
			(pintype "passive")
		)
		(pad "Y33" smd circle
			(at -15.875 8.255 90)
			(size 0.64 0.64)
			(layers "B.Cu" "B.Mask")
			(net 1 "GND")
			(pinfunction "Y33")
			(pintype "passive")
		)
		(pad "Y34" smd circle
			(at -17.145 8.255 90)
			(size 0.64 0.64)
			(layers "B.Cu" "B.Mask")
			(net 518 "/Expansion connector/PET0_C3_N")
			(pinfunction "Y34")
			(pintype "passive")
		)
		(pad "Y35" smd circle
			(at -18.415 8.255 90)
			(size 0.64 0.64)
			(layers "B.Cu" "B.Mask")
			(net 452 "/Expansion connector/PET0_C3_P")
			(pinfunction "Y35")
			(pintype "passive")
		)
		(pad "Y36" smd circle
			(at -19.685 8.255 90)
			(size 0.64 0.64)
			(layers "B.Cu" "B.Mask")
			(net 1 "GND")
			(pinfunction "Y36")
			(pintype "passive")
		)
		(pad "Y37" smd circle
			(at -20.955 8.255 90)
			(size 0.64 0.64)
			(layers "B.Cu" "B.Mask")
			(net 1 "GND")
			(pinfunction "Y37")
			(pintype "passive")
		)
		(pad "Y38" smd circle
			(at -22.225 8.255 90)
			(size 0.64 0.64)
			(layers "B.Cu" "B.Mask")
			(net 475 "/Expansion connector/PET1_C3_P")
			(pinfunction "Y38")
			(pintype "passive")
		)
		(pad "Y39" smd circle
			(at -23.495 8.255 90)
			(size 0.64 0.64)
			(layers "B.Cu" "B.Mask")
			(net 520 "/Expansion connector/PET1_C3_N")
			(pinfunction "Y39")
			(pintype "passive")
		)
		(pad "Y40" smd circle
			(at -24.765 8.255 90)
			(size 0.64 0.64)
			(layers "B.Cu" "B.Mask")
			(net 1 "GND")
			(pinfunction "Y40")
			(pintype "passive")
		)
		(pad "Z01" smd circle
			(at 24.765 6.985 90)
			(size 0.64 0.64)
			(layers "B.Cu" "B.Mask")
			(net 341 "/Expansion connector/FMC_PRESENT")
			(pinfunction "Z01")
			(pintype "passive")
		)
		(pad "Z02" smd circle
			(at 23.495 6.985 90)
			(size 0.64 0.64)
			(layers "B.Cu" "B.Mask")
			(net 1 "GND")
			(pinfunction "Z02")
			(pintype "passive")
		)
		(pad "Z03" smd circle
			(at 22.225 6.985 90)
			(size 0.64 0.64)
			(layers "B.Cu" "B.Mask")
			(net 1 "GND")
			(pinfunction "Z03")
			(pintype "passive")
		)
		(pad "Z04" smd circle
			(at 20.955 6.985 90)
			(size 0.64 0.64)
			(layers "B.Cu" "B.Mask")
			(net 468 "unconnected-(J18-PadZ04)")
			(pinfunction "Z04")
			(pintype "passive+no_connect")
		)
		(pad "Z05" smd circle
			(at 19.685 6.985 90)
			(size 0.64 0.64)
			(layers "B.Cu" "B.Mask")
			(net 469 "unconnected-(J18-PadZ05)")
			(pinfunction "Z05")
			(pintype "passive+no_connect")
		)
		(pad "Z06" smd circle
			(at 18.415 6.985 90)
			(size 0.64 0.64)
			(layers "B.Cu" "B.Mask")
			(net 1 "GND")
			(pinfunction "Z06")
			(pintype "passive")
		)
		(pad "Z07" smd circle
			(at 17.145 6.985 90)
			(size 0.64 0.64)
			(layers "B.Cu" "B.Mask")
			(net 1 "GND")
			(pinfunction "Z07")
			(pintype "passive")
		)
		(pad "Z08" smd circle
			(at 15.875 6.985 90)
			(size 0.64 0.64)
			(layers "B.Cu" "B.Mask")
			(net 425 "unconnected-(J18-PadZ08)")
			(pinfunction "Z08")
			(pintype "passive+no_connect")
		)
		(pad "Z09" smd circle
			(at 14.605 6.985 90)
			(size 0.64 0.64)
			(layers "B.Cu" "B.Mask")
			(net 619 "unconnected-(J18-PadZ09)")
			(pinfunction "Z09")
			(pintype "passive+no_connect")
		)
		(pad "Z10" smd circle
			(at 13.335 6.985 90)
			(size 0.64 0.64)
			(layers "B.Cu" "B.Mask")
			(net 1 "GND")
			(pinfunction "Z10")
			(pintype "passive")
		)
		(pad "Z11" smd circle
			(at 12.065 6.985 90)
			(size 0.64 0.64)
			(layers "B.Cu" "B.Mask")
			(net 1 "GND")
			(pinfunction "Z11")
			(pintype "passive")
		)
		(pad "Z12" smd circle
			(at 10.795 6.985 90)
			(size 0.64 0.64)
			(layers "B.Cu" "B.Mask")
			(net 570 "/Expansion connector/DP1.TX2+")
			(pinfunction "Z12")
			(pintype "passive")
		)
		(pad "Z13" smd circle
			(at 9.525 6.985 90)
			(size 0.64 0.64)
			(layers "B.Cu" "B.Mask")
			(net 733 "/Expansion connector/DP1.TX2-")
			(pinfunction "Z13")
			(pintype "passive")
		)
		(pad "Z14" smd circle
			(at 8.255 6.985 90)
			(size 0.64 0.64)
			(layers "B.Cu" "B.Mask")
			(net 1 "GND")
			(pinfunction "Z14")
			(pintype "passive")
		)
		(pad "Z15" smd circle
			(at 6.985 6.985 90)
			(size 0.64 0.64)
			(layers "B.Cu" "B.Mask")
			(net 1 "GND")
			(pinfunction "Z15")
			(pintype "passive")
		)
		(pad "Z16" smd circle
			(at 5.715 6.985 90)
			(size 0.64 0.64)
			(layers "B.Cu" "B.Mask")
			(net 794 "/Expansion connector/DP1.TX3+")
			(pinfunction "Z16")
			(pintype "passive")
		)
		(pad "Z17" smd circle
			(at 4.445 6.985 90)
			(size 0.64 0.64)
			(layers "B.Cu" "B.Mask")
			(net 682 "/Expansion connector/DP1.TX3-")
			(pinfunction "Z17")
			(pintype "passive")
		)
		(pad "Z18" smd circle
			(at 3.175 6.985 90)
			(size 0.64 0.64)
			(layers "B.Cu" "B.Mask")
			(net 1 "GND")
			(pinfunction "Z18")
			(pintype "passive")
		)
		(pad "Z19" smd circle
			(at 1.905 6.985 90)
			(size 0.64 0.64)
			(layers "B.Cu" "B.Mask")
			(net 1 "GND")
			(pinfunction "Z19")
			(pintype "passive")
		)
		(pad "Z20" smd circle
			(at 0.635 6.985 90)
			(size 0.64 0.64)
			(layers "B.Cu" "B.Mask")
			(net 1137 "unconnected-(J18-PadZ20)")
			(pinfunction "Z20")
			(pintype "passive+no_connect")
		)
		(pad "Z21" smd circle
			(at -0.635 6.985 90)
			(size 0.64 0.64)
			(layers "B.Cu" "B.Mask")
			(net 1136 "unconnected-(J18-PadZ21)")
			(pinfunction "Z21")
			(pintype "passive+no_connect")
		)
		(pad "Z22" smd circle
			(at -1.905 6.985 90)
			(size 0.64 0.64)
			(layers "B.Cu" "B.Mask")
			(net 1 "GND")
			(pinfunction "Z22")
			(pintype "passive")
		)
		(pad "Z23" smd circle
			(at -3.175 6.985 90)
			(size 0.64 0.64)
			(layers "B.Cu" "B.Mask")
			(net 1 "GND")
			(pinfunction "Z23")
			(pintype "passive")
		)
		(pad "Z24" smd circle
			(at -4.445 6.985 90)
			(size 0.64 0.64)
			(layers "B.Cu" "B.Mask")
			(net 562 "unconnected-(J18-PadZ24)")
			(pinfunction "Z24")
			(pintype "passive+no_connect")
		)
		(pad "Z25" smd circle
			(at -5.715 6.985 90)
			(size 0.64 0.64)
			(layers "B.Cu" "B.Mask")
			(net 576 "unconnected-(J18-PadZ25)")
			(pinfunction "Z25")
			(pintype "passive+no_connect")
		)
		(pad "Z26" smd circle
			(at -6.985 6.985 90)
			(size 0.64 0.64)
			(layers "B.Cu" "B.Mask")
			(net 1 "GND")
			(pinfunction "Z26")
			(pintype "passive")
		)
		(pad "Z27" smd circle
			(at -8.255 6.985 90)
			(size 0.64 0.64)
			(layers "B.Cu" "B.Mask")
			(net 1 "GND")
			(pinfunction "Z27")
			(pintype "passive")
		)
		(pad "Z28" smd circle
			(at -9.525 6.985 90)
			(size 0.64 0.64)
			(layers "B.Cu" "B.Mask")
			(net 728 "/Expansion connector/PER0_C2_P")
			(pinfunction "Z28")
			(pintype "passive")
		)
		(pad "Z29" smd circle
			(at -10.795 6.985 90)
			(size 0.64 0.64)
			(layers "B.Cu" "B.Mask")
			(net 471 "/Expansion connector/PER0_C2_N")
			(pinfunction "Z29")
			(pintype "passive")
		)
		(pad "Z30" smd circle
			(at -12.065 6.985 90)
			(size 0.64 0.64)
			(layers "B.Cu" "B.Mask")
			(net 1 "GND")
			(pinfunction "Z30")
			(pintype "passive")
		)
		(pad "Z31" smd circle
			(at -13.335 6.985 90)
			(size 0.64 0.64)
			(layers "B.Cu" "B.Mask")
			(net 1 "GND")
			(pinfunction "Z31")
			(pintype "passive")
		)
		(pad "Z32" smd circle
			(at -14.605 6.985 90)
			(size 0.64 0.64)
			(layers "B.Cu" "B.Mask")
			(net 851 "/Expansion connector/PCIe_{C2x1}.CLK-")
			(pinfunction "Z32")
			(pintype "passive")
		)
		(pad "Z33" smd circle
			(at -15.875 6.985 90)
			(size 0.64 0.64)
			(layers "B.Cu" "B.Mask")
			(net 843 "/Expansion connector/PCIe_{C2x1}.CLK+")
			(pinfunction "Z33")
			(pintype "passive")
		)
		(pad "Z34" smd circle
			(at -17.145 6.985 90)
			(size 0.64 0.64)
			(layers "B.Cu" "B.Mask")
			(net 1 "GND")
			(pinfunction "Z34")
			(pintype "passive")
		)
		(pad "Z35" smd circle
			(at -18.415 6.985 90)
			(size 0.64 0.64)
			(layers "B.Cu" "B.Mask")
			(net 1 "GND")
			(pinfunction "Z35")
			(pintype "passive")
		)
		(pad "Z36" smd circle
			(at -19.685 6.985 90)
			(size 0.64 0.64)
			(layers "B.Cu" "B.Mask")
			(net 479 "/Expansion connector/PET0_C2_N")
			(pinfunction "Z36")
			(pintype "passive")
		)
		(pad "Z37" smd circle
			(at -20.955 6.985 90)
			(size 0.64 0.64)
			(layers "B.Cu" "B.Mask")
			(net 476 "/Expansion connector/PET0_C2_P")
			(pinfunction "Z37")
			(pintype "passive")
		)
		(pad "Z38" smd circle
			(at -22.225 6.985 90)
			(size 0.64 0.64)
			(layers "B.Cu" "B.Mask")
			(net 1 "GND")
			(pinfunction "Z38")
			(pintype "passive")
		)
		(pad "Z39" smd circle
			(at -23.495 6.985 90)
			(size 0.64 0.64)
			(layers "B.Cu" "B.Mask")
			(net 1 "GND")
			(pinfunction "Z39")
			(pintype "passive")
		)
		(pad "Z40" smd circle
			(at -24.765 6.985 90)
			(size 0.64 0.64)
			(layers "B.Cu" "B.Mask")
			(net 297 "/Expansion connector/+3V3_FMC")
			(pinfunction "Z40")
			(pintype "passive")
		)
	)
	(footprint "antmicro-footprints:R_0402_1005Metric"
		(layer "B.Cu")
		(at 238.095 82.500001 180)
		(descr "Resistor SMD 0402")
		(tags "resistor SMD 0402")
		(property "Reference" "R152"
			(at -1.605 -2.299999 0)
			(layer "B.SilkS")
			(effects
				(font
					(size 0.7 0.7)
					(thickness 0.15)
				)
				(justify left bottom mirror)
			)
		)
		(property "Value" "R_10k_0402"
			(at -1.011843 -1.772046 0)
			(layer "B.Fab")
			(effects
				(font
					(size 0.7 0.7)
					(thickness 0.15)
				)
				(justify left bottom mirror)
			)
		)
		(property "Datasheet" "https://www.bourns.com/docs/product-datasheets/cr.pdf"
			(at 0 0 0)
			(layer "B.Fab")
			(hide yes)
			(effects
				(font
					(size 1.27 1.27)
					(thickness 0.15)
				)
				(justify mirror)
			)
		)
		(property "Description" "SMD Chip Resistor, 10 kohm, ± 1%, 62.5 mW, 0402 [1005 Metric], Thick Film, General Purpose"
			(at 0 0 0)
			(layer "B.Fab")
			(hide yes)
			(effects
				(font
					(size 1.27 1.27)
					(thickness 0.15)
				)
				(justify mirror)
			)
		)
		(property "Manufacturer" "Bourns"
			(at 0 0 0)
			(unlocked yes)
			(layer "B.Fab")
			(hide yes)
			(effects
				(font
					(size 1 1)
					(thickness 0.15)
				)
				(justify mirror)
			)
		)
		(property "MPN" "CR0402-FX-1002GLF"
			(at 0 0 0)
			(unlocked yes)
			(layer "B.Fab")
			(hide yes)
			(effects
				(font
					(size 1 1)
					(thickness 0.15)
				)
				(justify mirror)
			)
		)
		(property "Val" "10k"
			(at 0 0 0)
			(unlocked yes)
			(layer "B.Fab")
			(hide yes)
			(effects
				(font
					(size 1 1)
					(thickness 0.15)
				)
				(justify mirror)
			)
		)
		(property "License" "Apache-2.0"
			(at 0 0 0)
			(unlocked yes)
			(layer "B.Fab")
			(hide yes)
			(effects
				(font
					(size 1 1)
					(thickness 0.15)
				)
				(justify mirror)
			)
		)
		(property "Author" "Antmicro"
			(at 0 0 0)
			(unlocked yes)
			(layer "B.Fab")
			(hide yes)
			(effects
				(font
					(size 1 1)
					(thickness 0.15)
				)
				(justify mirror)
			)
		)
		(property "Tolerance" "1%"
			(at 0 0 0)
			(unlocked yes)
			(layer "B.Fab")
			(hide yes)
			(effects
				(font
					(size 1 1)
					(thickness 0.15)
				)
				(justify mirror)
			)
		)
		(sheetname "/USB Debug, PD/")
		(sheetfile "usb_debug_pd.kicad_sch")
		(attr smd)
		(fp_poly
			(pts
				(xy -0.925 0.47) (xy -0.925 -0.47) (xy 0.925 -0.47) (xy 0.925 0.47)
			)
			(stroke
				(width 0.05)
				(type default)
			)
			(fill no)
			(layer "B.CrtYd")
		)
		(fp_poly
			(pts
				(xy -0.5 0.25) (xy -0.5 -0.25) (xy 0.5 -0.25) (xy 0.5 0.25)
			)
			(stroke
				(width 0.15)
				(type solid)
			)
			(fill no)
			(layer "B.Fab")
		)
		(fp_text user "${REFERENCE}"
			(at -0.95 -3.168 0)
			(layer "B.Fab")
			(effects
				(font
					(size 0.7 0.7)
					(thickness 0.15)
				)
				(justify left bottom mirror)
			)
		)
		(fp_text user "Author: Antmicro"
			(at -0.95 -4.169 0)
			(layer "B.Fab")
			(effects
				(font
					(size 0.7 0.7)
					(thickness 0.15)
				)
				(justify left bottom mirror)
			)
		)
		(fp_text user "License: Apache-2.0"
			(at -0.949999 -5.169 0)
			(layer "B.Fab")
			(effects
				(font
					(size 0.7 0.7)
					(thickness 0.15)
				)
				(justify left bottom mirror)
			)
		)
		(pad "1" smd roundrect
			(at -0.48 0 180)
			(size 0.59 0.64)
			(layers "B.Cu" "B.Mask" "B.Paste")
			(roundrect_rratio 0.25)
			(net 1 "GND")
			(pintype "passive")
		)
		(pad "2" smd roundrect
			(at 0.48 0 180)
			(size 0.59 0.64)
			(layers "B.Cu" "B.Mask" "B.Paste")
			(roundrect_rratio 0.25)
			(net 977 "Net-(U40-EN)")
			(pintype "passive")
		)
	)
	(footprint "antmicro-footprints:R_0402_1005Metric"
		(layer "B.Cu")
		(at 217.55 113.03)
		(descr "Resistor SMD 0402")
		(tags "resistor SMD 0402")
		(property "Reference" "R329"
			(at -1.76 1.79 0)
			(layer "B.SilkS")
			(effects
				(font
					(size 0.7 0.7)
					(thickness 0.15)
				)
				(justify right top mirror)
			)
		)
		(property "Value" "R_10k_0402"
			(at -1.011843 -1.772047 0)
			(layer "B.Fab")
			(effects
				(font
					(size 0.7 0.7)
					(thickness 0.15)
				)
				(justify right top mirror)
			)
		)
		(property "Datasheet" "https://www.bourns.com/docs/product-datasheets/cr.pdf"
			(at 0 0 0)
			(layer "B.Fab")
			(hide yes)
			(effects
				(font
					(size 1.27 1.27)
					(thickness 0.15)
				)
				(justify mirror)
			)
		)
		(property "Description" "SMD Chip Resistor, 10 kohm, ± 1%, 62.5 mW, 0402 [1005 Metric], Thick Film, General Purpose"
			(at 0 0 0)
			(layer "B.Fab")
			(hide yes)
			(effects
				(font
					(size 1.27 1.27)
					(thickness 0.15)
				)
				(justify mirror)
			)
		)
		(property "MPN" "CR0402-FX-1002GLF"
			(at 0 0 180)
			(unlocked yes)
			(layer "B.Fab")
			(hide yes)
			(effects
				(font
					(size 1 1)
					(thickness 0.15)
				)
				(justify mirror)
			)
		)
		(property "Manufacturer" "Bourns"
			(at 0 0 180)
			(unlocked yes)
			(layer "B.Fab")
			(hide yes)
			(effects
				(font
					(size 1 1)
					(thickness 0.15)
				)
				(justify mirror)
			)
		)
		(property "License" "Apache-2.0"
			(at 0 0 180)
			(unlocked yes)
			(layer "B.Fab")
			(hide yes)
			(effects
				(font
					(size 1 1)
					(thickness 0.15)
				)
				(justify mirror)
			)
		)
		(property "Author" "Antmicro"
			(at 0 0 180)
			(unlocked yes)
			(layer "B.Fab")
			(hide yes)
			(effects
				(font
					(size 1 1)
					(thickness 0.15)
				)
				(justify mirror)
			)
		)
		(property "Val" "10k"
			(at 0 0 180)
			(unlocked yes)
			(layer "B.Fab")
			(hide yes)
			(effects
				(font
					(size 1 1)
					(thickness 0.15)
				)
				(justify mirror)
			)
		)
		(property "Tolerance" "1%"
			(at 0 0 180)
			(unlocked yes)
			(layer "B.Fab")
			(hide yes)
			(effects
				(font
					(size 1 1)
					(thickness 0.15)
				)
				(justify mirror)
			)
		)
		(sheetname "/USB Hub/")
		(sheetfile "usb_hub.kicad_sch")
		(attr smd)
		(fp_rect
			(start -0.925 0.47)
			(end 0.925 -0.47)
			(stroke
				(width 0.05)
				(type default)
			)
			(fill no)
			(layer "B.CrtYd")
		)
		(fp_rect
			(start -0.5 0.25)
			(end 0.5 -0.25)
			(stroke
				(width 0.15)
				(type solid)
			)
			(fill no)
			(layer "B.Fab")
		)
		(fp_text user "Author: Antmicro"
			(at -0.95 -4.169 0)
			(layer "B.Fab")
			(effects
				(font
					(size 0.7 0.7)
					(thickness 0.15)
				)
				(justify right top mirror)
			)
		)
		(fp_text user "${REFERENCE}"
			(at -0.95 -3.168 0)
			(layer "B.Fab")
			(effects
				(font
					(size 0.7 0.7)
					(thickness 0.15)
				)
				(justify right top mirror)
			)
		)
		(fp_text user "License: Apache-2.0"
			(at -0.95 -5.169 0)
			(layer "B.Fab")
			(effects
				(font
					(size 0.7 0.7)
					(thickness 0.15)
				)
				(justify right top mirror)
			)
		)
		(pad "1" smd roundrect
			(at -0.48 0)
			(size 0.59 0.64)
			(layers "B.Cu" "B.Mask" "B.Paste")
			(roundrect_rratio 0.25)
			(net 1106 "/USB Hub/DP2_VCONN2")
			(pintype "passive")
		)
		(pad "2" smd roundrect
			(at 0.48 0)
			(size 0.59 0.64)
			(layers "B.Cu" "B.Mask" "B.Paste")
			(roundrect_rratio 0.25)
			(net 1 "GND")
			(pintype "passive")
		)
	)
	(footprint "antmicro-footprints:C_0402_1005Metric"
		(layer "B.Cu")
		(at 127.073 150.344)
		(descr "Capacitor SMD 0402")
		(tags "capacitor SMD 0402")
		(property "Reference" "C204"
			(at -3.773 -0.344 0)
			(layer "B.SilkS")
			(effects
				(font
					(size 0.7 0.7)
					(thickness 0.15)
				)
				(justify right top mirror)
			)
		)
		(property "Value" "C_100n_0402"
			(at -1.022927 -2.155213 0)
			(layer "B.Fab")
			(effects
				(font
					(size 0.7 0.7)
					(thickness 0.15)
				)
				(justify right top mirror)
			)
		)
		(property "Datasheet" "https://www.murata.com/products/productdetail?partno=GRM155R61H104KE14%23"
			(at 0 0 0)
			(layer "B.Fab")
			(hide yes)
			(effects
				(font
					(size 1.27 1.27)
					(thickness 0.15)
				)
				(justify mirror)
			)
		)
		(property "Description" "SMD Multilayer Ceramic Capacitor, 0.1 µF, 50 V, 0402 [1005 Metric], ± 10%, X5R, GRM Series"
			(at 0 0 0)
			(layer "B.Fab")
			(hide yes)
			(effects
				(font
					(size 1.27 1.27)
					(thickness 0.15)
				)
				(justify mirror)
			)
		)
		(property "MPN" "GRM155R61H104KE14D"
			(at 0 0 180)
			(unlocked yes)
			(layer "B.Fab")
			(hide yes)
			(effects
				(font
					(size 1 1)
					(thickness 0.15)
				)
				(justify mirror)
			)
		)
		(property "Val" "100n"
			(at 0 0 180)
			(unlocked yes)
			(layer "B.Fab")
			(hide yes)
			(effects
				(font
					(size 1 1)
					(thickness 0.15)
				)
				(justify mirror)
			)
		)
		(property "Voltage" "50V"
			(at 0 0 180)
			(unlocked yes)
			(layer "B.Fab")
			(hide yes)
			(effects
				(font
					(size 1 1)
					(thickness 0.15)
				)
				(justify mirror)
			)
		)
		(property "Dielectric" "X5R"
			(at 0 0 180)
			(unlocked yes)
			(layer "B.Fab")
			(hide yes)
			(effects
				(font
					(size 1 1)
					(thickness 0.15)
				)
				(justify mirror)
			)
		)
		(property "Manufacturer" "Murata"
			(at 0 0 180)
			(unlocked yes)
			(layer "B.Fab")
			(hide yes)
			(effects
				(font
					(size 1 1)
					(thickness 0.15)
				)
				(justify mirror)
			)
		)
		(property "License" "Apache-2.0"
			(at 0 0 180)
			(unlocked yes)
			(layer "B.Fab")
			(hide yes)
			(effects
				(font
					(size 1 1)
					(thickness 0.15)
				)
				(justify mirror)
			)
		)
		(property "Author" "Antmicro"
			(at 0 0 180)
			(unlocked yes)
			(layer "B.Fab")
			(hide yes)
			(effects
				(font
					(size 1 1)
					(thickness 0.15)
				)
				(justify mirror)
			)
		)
		(sheetname "/Peripherals/")
		(sheetfile "peripherals.kicad_sch")
		(attr smd)
		(fp_rect
			(start -0.925 0.47)
			(end 0.925 -0.47)
			(stroke
				(width 0.05)
				(type default)
			)
			(fill no)
			(layer "B.CrtYd")
		)
		(fp_line
			(start -0.494 -0.248)
			(end -0.494 0.25)
			(stroke
				(width 0.15)
				(type solid)
			)
			(layer "B.Fab")
		)
		(fp_line
			(start -0.494 0.25)
			(end 0.504 0.25)
			(stroke
				(width 0.15)
				(type solid)
			)
			(layer "B.Fab")
		)
		(fp_line
			(start 0.504 -0.248)
			(end -0.494 -0.248)
			(stroke
				(width 0.15)
				(type solid)
			)
			(layer "B.Fab")
		)
		(fp_line
			(start 0.504 0.25)
			(end 0.504 -0.248)
			(stroke
				(width 0.15)
				(type solid)
			)
			(layer "B.Fab")
		)
		(fp_text user "License: Apache-2.0"
			(at -0.939 -5.799 0)
			(layer "B.Fab")
			(effects
				(font
					(size 0.7 0.7)
					(thickness 0.15)
				)
				(justify right top mirror)
			)
		)
		(fp_text user "${REFERENCE}"
			(at -0.939 -4.599 0)
			(layer "B.Fab")
			(effects
				(font
					(size 0.7 0.7)
					(thickness 0.15)
				)
				(justify right top mirror)
			)
		)
		(fp_text user "Author: Antmicro"
			(at -0.939 -3.399 0)
			(layer "B.Fab")
			(effects
				(font
					(size 0.7 0.7)
					(thickness 0.15)
				)
				(justify right top mirror)
			)
		)
		(pad "1" smd roundrect
			(at -0.48 0)
			(size 0.59 0.64)
			(layers "B.Cu" "B.Mask" "B.Paste")
			(roundrect_rratio 0.25)
			(net 1 "GND")
			(pintype "passive")
		)
		(pad "2" smd roundrect
			(at 0.48 0)
			(size 0.59 0.64)
			(layers "B.Cu" "B.Mask" "B.Paste")
			(roundrect_rratio 0.25)
			(net 2 "+3V3")
			(pintype "passive")
		)
	)
	(footprint "antmicro-footprints:TP_SMD_0.75mm"
		(layer "B.Cu")
		(at 143.630532 78.81 90)
		(property "Reference" "TP49"
			(at -0.49 0.369468 90)
			(layer "B.SilkS")
			(effects
				(font
					(size 0.7 0.7)
					(thickness 0.15)
				)
				(justify left bottom mirror)
			)
		)
		(property "Value" "TP_0.75mm_SMD"
			(at 0 -1.2 90)
			(layer "B.Fab")
			(effects
				(font
					(size 0.7 0.7)
					(thickness 0.15)
				)
				(justify right top mirror)
			)
		)
		(property "Description" "SMT test point"
			(at 0 0 90)
			(layer "B.Fab")
			(hide yes)
			(effects
				(font
					(size 1.27 1.27)
					(thickness 0.15)
				)
				(justify mirror)
			)
		)
		(property "MPN" ""
			(at 0 0 270)
			(unlocked yes)
			(layer "B.Fab")
			(hide yes)
			(effects
				(font
					(size 1 1)
					(thickness 0.15)
				)
				(justify mirror)
			)
		)
		(property "Manufacturer" ""
			(at 0 0 270)
			(unlocked yes)
			(layer "B.Fab")
			(hide yes)
			(effects
				(font
					(size 1 1)
					(thickness 0.15)
				)
				(justify mirror)
			)
		)
		(property "Author" "Antmicro"
			(at 0 0 270)
			(unlocked yes)
			(layer "B.Fab")
			(hide yes)
			(effects
				(font
					(size 1 1)
					(thickness 0.15)
				)
				(justify mirror)
			)
		)
		(property "License" "Apache-2.0"
			(at 0 0 270)
			(unlocked yes)
			(layer "B.Fab")
			(hide yes)
			(effects
				(font
					(size 1 1)
					(thickness 0.15)
				)
				(justify mirror)
			)
		)
		(sheetname "/SoM_Power/")
		(sheetfile "som_power.kicad_sch")
		(attr exclude_from_pos_files exclude_from_bom)
		(fp_circle
			(center 0 0)
			(end 0.475 0)
			(stroke
				(width 0.05)
				(type default)
			)
			(fill no)
			(layer "B.CrtYd")
		)
		(fp_text user "${REFERENCE}"
			(at -0.4 -2.7 90)
			(layer "B.Fab")
			(effects
				(font
					(size 0.7 0.7)
					(thickness 0.15)
				)
				(justify right top mirror)
			)
		)
		(fp_text user "License: Apache-2.0"
			(at -0.4 -5.101 90)
			(layer "B.Fab")
			(effects
				(font
					(size 0.7 0.7)
					(thickness 0.15)
				)
				(justify right top mirror)
			)
		)
		(fp_text user "Author: Antmicro"
			(at -0.4 -3.901 90)
			(layer "B.Fab")
			(effects
				(font
					(size 0.7 0.7)
					(thickness 0.15)
				)
				(justify right top mirror)
			)
		)
		(pad "1" smd circle
			(at 0 0 90)
			(size 0.75 0.75)
			(layers "B.Cu" "B.Mask")
			(net 678 "Net-(J1A-VCOMP_ALERT_N)")
			(pinfunction "1")
			(pintype "passive")
		)
	)
	(footprint "antmicro-footprints:C_0805_2012Metric"
		(layer "B.Cu")
		(at 99.1 136.6 90)
		(descr "Capacitor SMD 0805")
		(tags "capacitor SMD 0805")
		(property "Reference" "C50"
			(at -2.10551 1.198678 90)
			(layer "B.SilkS")
			(effects
				(font
					(size 0.7 0.7)
					(thickness 0.15)
				)
				(justify right top mirror)
			)
		)
		(property "Value" "C_22u_25V_0805"
			(at -2.055717 -1.963153 90)
			(layer "B.Fab")
			(effects
				(font
					(size 0.7 0.7)
					(thickness 0.15)
				)
				(justify right top mirror)
			)
		)
		(property "Datasheet" "https://product.samsungsem.com/mlcc/CL21A226MAYNNN.do"
			(at 0 0 90)
			(layer "B.Fab")
			(hide yes)
			(effects
				(font
					(size 1.27 1.27)
					(thickness 0.15)
				)
				(justify mirror)
			)
		)
		(property "Description" "SMT Multilayer Ceramic Capacitor, 22uF, +/-20%, 25V, X5R, 0805 [2012 Metric]"
			(at 0 0 90)
			(layer "B.Fab")
			(hide yes)
			(effects
				(font
					(size 1.27 1.27)
					(thickness 0.15)
				)
				(justify mirror)
			)
		)
		(property "MPN" "CL21A226MAYNNNE"
			(at 0 0 90)
			(unlocked yes)
			(layer "B.Fab")
			(hide yes)
			(effects
				(font
					(size 1 1)
					(thickness 0.15)
				)
				(justify mirror)
			)
		)
		(property "Val" "22u"
			(at 0 0 90)
			(unlocked yes)
			(layer "B.Fab")
			(hide yes)
			(effects
				(font
					(size 1 1)
					(thickness 0.15)
				)
				(justify mirror)
			)
		)
		(property "Voltage" "25V"
			(at 0 0 90)
			(unlocked yes)
			(layer "B.Fab")
			(hide yes)
			(effects
				(font
					(size 1 1)
					(thickness 0.15)
				)
				(justify mirror)
			)
		)
		(property "Dielectric" "X5R"
			(at 0 0 90)
			(unlocked yes)
			(layer "B.Fab")
			(hide yes)
			(effects
				(font
					(size 1 1)
					(thickness 0.15)
				)
				(justify mirror)
			)
		)
		(property "Manufacturer" "Samsung Electro-Mechanics"
			(at 0 0 90)
			(unlocked yes)
			(layer "B.Fab")
			(hide yes)
			(effects
				(font
					(size 1 1)
					(thickness 0.15)
				)
				(justify mirror)
			)
		)
		(property "License" "Apache-2.0"
			(at 0 0 90)
			(unlocked yes)
			(layer "B.Fab")
			(hide yes)
			(effects
				(font
					(size 1 1)
					(thickness 0.15)
				)
				(justify mirror)
			)
		)
		(property "Author" "Antmicro"
			(at 0 0 90)
			(unlocked yes)
			(layer "B.Fab")
			(hide yes)
			(effects
				(font
					(size 1 1)
					(thickness 0.15)
				)
				(justify mirror)
			)
		)
		(property "Public" "False"
			(at 0 0 90)
			(unlocked yes)
			(layer "B.Fab")
			(hide yes)
			(effects
				(font
					(size 1 1)
					(thickness 0.15)
				)
				(justify mirror)
			)
		)
		(sheetname "/Expansion connector/")
		(sheetfile "expansion_connector.kicad_sch")
		(attr smd)
		(fp_line
			(start -0.3 -0.7)
			(end 0.3 -0.7)
			(stroke
				(width 0.15)
				(type solid)
			)
			(layer "B.SilkS")
		)
		(fp_line
			(start -0.3 0.7)
			(end 0.3 0.7)
			(stroke
				(width 0.15)
				(type solid)
			)
			(layer "B.SilkS")
		)
		(fp_poly
			(pts
				(xy 1.95 0.9) (xy -1.95 0.9) (xy -1.95 -0.9) (xy 1.95 -0.9)
			)
			(stroke
				(width 0.05)
				(type default)
			)
			(fill no)
			(layer "B.CrtYd")
		)
		(fp_poly
			(pts
				(xy -0.95 0.675001) (xy 0.95 0.675001) (xy 0.95 -0.675001) (xy -0.95 -0.675001)
			)
			(stroke
				(width 0.15)
				(type solid)
			)
			(fill no)
			(layer "B.Fab")
		)
		(fp_text user "Author: Antmicro"
			(at -1.9 -5.947 90)
			(layer "B.Fab")
			(effects
				(font
					(size 0.7 0.7)
					(thickness 0.15)
				)
				(justify right top mirror)
			)
		)
		(fp_text user "License: Apache-2.0"
			(at -1.9 -4.947 90)
			(layer "B.Fab")
			(effects
				(font
					(size 0.7 0.7)
					(thickness 0.15)
				)
				(justify right top mirror)
			)
		)
		(fp_text user "${REFERENCE}"
			(at -1.899999 -3.947 90)
			(layer "B.Fab")
			(effects
				(font
					(size 0.7 0.7)
					(thickness 0.15)
				)
				(justify right top mirror)
			)
		)
		(pad "1" smd roundrect
			(at -1.099999 0 90)
			(size 1.2 1.3)
			(layers "B.Cu" "B.Mask" "B.Paste")
			(roundrect_rratio 0.25)
			(net 1 "GND")
			(pintype "passive")
		)
		(pad "2" smd roundrect
			(at 1.099999 0 90)
			(size 1.2 1.3)
			(layers "B.Cu" "B.Mask" "B.Paste")
			(roundrect_rratio 0.25)
			(net 156 "/Expansion connector/+VCC_FMC")
			(pintype "passive")
		)
	)
	(footprint "antmicro-footprints:MS621FE-FL11E"
		(layer "B.Cu")
		(at 142.480532 148.21 90)
		(property "Reference" "BT1"
			(at -1.66 2.249468 0)
			(layer "B.SilkS")
			(effects
				(font
					(size 0.7 0.7)
					(thickness 0.15)
				)
				(justify right top mirror)
			)
		)
		(property "Value" "Battery_Holder_MS621FE-FL11E"
			(at -0.001 -6.2 90)
			(layer "B.Fab")
			(effects
				(font
					(size 0.7 0.7)
					(thickness 0.15)
				)
				(justify right top mirror)
			)
		)
		(property "Datasheet" "https://www.sii.co.jp/en/me/datasheets/ms-rechargeable/ms621fe/"
			(at 0 0 90)
			(layer "B.Fab")
			(hide yes)
			(effects
				(font
					(size 1.27 1.27)
					(thickness 0.15)
				)
				(justify mirror)
			)
		)
		(property "Description" "Rechargeable Battery, Coin Cell, Single Cell, 3 V, Lithium Manganese Dioxide, 5.5 mAh, Button Cell"
			(at 0 0 90)
			(layer "B.Fab")
			(hide yes)
			(effects
				(font
					(size 1.27 1.27)
					(thickness 0.15)
				)
				(justify mirror)
			)
		)
		(property "Manufacturer" "Seiko Instruments"
			(at 0 0 270)
			(unlocked yes)
			(layer "B.Fab")
			(hide yes)
			(effects
				(font
					(size 1 1)
					(thickness 0.15)
				)
				(justify mirror)
			)
		)
		(property "MPN" "MS621FE-FL11E"
			(at 0 0 270)
			(unlocked yes)
			(layer "B.Fab")
			(hide yes)
			(effects
				(font
					(size 1 1)
					(thickness 0.15)
				)
				(justify mirror)
			)
		)
		(property "Author" "Antmicro"
			(at 0 0 270)
			(unlocked yes)
			(layer "B.Fab")
			(hide yes)
			(effects
				(font
					(size 1 1)
					(thickness 0.15)
				)
				(justify mirror)
			)
		)
		(property "License" "Apache-2.0"
			(at 0 0 270)
			(unlocked yes)
			(layer "B.Fab")
			(hide yes)
			(effects
				(font
					(size 1 1)
					(thickness 0.15)
				)
				(justify mirror)
			)
		)
		(sheetname "/SoM_Power/")
		(sheetfile "som_power.kicad_sch")
		(attr smd)
		(fp_arc
			(start -1.2 2.15)
			(mid 0 -4.834)
			(end 1.2 2.15)
			(stroke
				(width 0.15)
				(type solid)
			)
			(layer "B.SilkS")
		)
		(fp_line
			(start 1.275 5.2)
			(end 1.275 2.425)
			(stroke
				(width 0.05)
				(type solid)
			)
			(layer "B.CrtYd")
		)
		(fp_line
			(start 1.275 5.2)
			(end -1.275 5.2)
			(stroke
				(width 0.05)
				(type solid)
			)
			(layer "B.CrtYd")
		)
		(fp_line
			(start -1.275 5.2)
			(end -1.275 2.425)
			(stroke
				(width 0.05)
				(type solid)
			)
			(layer "B.CrtYd")
		)
		(fp_arc
			(start -1.275 2.425)
			(mid 0 -5.143374)
			(end 1.275 2.425)
			(stroke
				(width 0.05)
				(type solid)
			)
			(layer "B.CrtYd")
		)
		(fp_line
			(start -1.2 4.65)
			(end -1.2 2.04)
			(stroke
				(width 0.15)
				(type solid)
			)
			(layer "B.Fab")
		)
		(fp_line
			(start 1.2 5.05)
			(end 1.2 2.04)
			(stroke
				(width 0.15)
				(type solid)
			)
			(layer "B.Fab")
		)
		(fp_line
			(start 1.2 5.05)
			(end -0.8 5.05)
			(stroke
				(width 0.15)
				(type solid)
			)
			(layer "B.Fab")
		)
		(fp_line
			(start -0.8 5.05)
			(end -1.2 4.65)
			(stroke
				(width 0.15)
				(type solid)
			)
			(layer "B.Fab")
		)
		(fp_circle
			(center -0.001 -1.25)
			(end -0.001 2.25)
			(stroke
				(width 0.15)
				(type solid)
			)
			(fill no)
			(layer "B.Fab")
		)
		(fp_text user "${REFERENCE}"
			(at -3.501 -11.8 90)
			(layer "B.Fab")
			(effects
				(font
					(size 0.7 0.7)
					(thickness 0.15)
				)
				(justify right top mirror)
			)
		)
		(fp_text user "COPPER KEEPOUT"
			(at -0.2 3.14 0)
			(unlocked yes)
			(layer "B.Fab")
			(effects
				(font
					(size 0.4 0.4)
					(thickness 0.1)
				)
				(justify left bottom mirror)
			)
		)
		(fp_text user "Author: Antmicro"
			(at -3.501 -9.4 90)
			(layer "B.Fab")
			(effects
				(font
					(size 0.7 0.7)
					(thickness 0.15)
				)
				(justify right top mirror)
			)
		)
		(fp_text user "License: Apache-2.0"
			(at -3.501 -8.2 90)
			(layer "B.Fab")
			(effects
				(font
					(size 0.7 0.7)
					(thickness 0.15)
				)
				(justify right top mirror)
			)
		)
		(pad "1" smd rect
			(at -0.75 4.05 180)
			(size 1.8 0.75)
			(layers "B.Cu" "B.Mask" "B.Paste")
			(net 10 "Net-(BT1-+)")
			(pinfunction "+")
			(pintype "passive")
		)
		(pad "2" smd rect
			(at 0.75 4.05 180)
			(size 1.8 0.75)
			(layers "B.Cu" "B.Mask" "B.Paste")
			(net 1 "GND")
			(pinfunction "-")
			(pintype "passive")
		)
		(zone
			(net 0)
			(net_name "")
			(layers "B.Cu" "B.CrtYd")
			(hatch edge 0.508)
			(connect_pads
				(clearance 0)
			)
			(min_thickness 0.254)
			(filled_areas_thickness no)
			(keepout
				(tracks allowed)
				(vias not_allowed)
				(pads not_allowed)
				(copperpour not_allowed)
				(footprints allowed)
			)
			(placement
				(enabled no)
				(sheetname "")
			)
			(fill
				(thermal_gap 0.508)
				(thermal_bridge_width 0.508)
			)
			(polygon
				(pts
					(xy 139.980532 149.37) (xy 145.620532 149.37) (xy 145.620532 147.05) (xy 139.980532 147.05)
				)
			)
		)
	)
	(footprint "antmicro-footprints:R_0402_1005Metric"
		(layer "B.Cu")
		(at 220.4 123.391698)
		(descr "Resistor SMD 0402")
		(tags "resistor SMD 0402")
		(property "Reference" "R335"
			(at -0.9 1.708302 0)
			(layer "B.SilkS")
			(effects
				(font
					(size 0.7 0.7)
					(thickness 0.15)
				)
				(justify right top mirror)
			)
		)
		(property "Value" "R_10k_0402"
			(at -1.011843 -1.772047 0)
			(layer "B.Fab")
			(effects
				(font
					(size 0.7 0.7)
					(thickness 0.15)
				)
				(justify right top mirror)
			)
		)
		(property "Datasheet" "https://www.bourns.com/docs/product-datasheets/cr.pdf"
			(at 0 0 0)
			(layer "B.Fab")
			(hide yes)
			(effects
				(font
					(size 1.27 1.27)
					(thickness 0.15)
				)
				(justify mirror)
			)
		)
		(property "Description" "SMD Chip Resistor, 10 kohm, ± 1%, 62.5 mW, 0402 [1005 Metric], Thick Film, General Purpose"
			(at 0 0 0)
			(layer "B.Fab")
			(hide yes)
			(effects
				(font
					(size 1.27 1.27)
					(thickness 0.15)
				)
				(justify mirror)
			)
		)
		(property "MPN" "CR0402-FX-1002GLF"
			(at 0 0 180)
			(unlocked yes)
			(layer "B.Fab")
			(hide yes)
			(effects
				(font
					(size 1 1)
					(thickness 0.15)
				)
				(justify mirror)
			)
		)
		(property "Manufacturer" "Bourns"
			(at 0 0 180)
			(unlocked yes)
			(layer "B.Fab")
			(hide yes)
			(effects
				(font
					(size 1 1)
					(thickness 0.15)
				)
				(justify mirror)
			)
		)
		(property "License" "Apache-2.0"
			(at 0 0 180)
			(unlocked yes)
			(layer "B.Fab")
			(hide yes)
			(effects
				(font
					(size 1 1)
					(thickness 0.15)
				)
				(justify mirror)
			)
		)
		(property "Author" "Antmicro"
			(at 0 0 180)
			(unlocked yes)
			(layer "B.Fab")
			(hide yes)
			(effects
				(font
					(size 1 1)
					(thickness 0.15)
				)
				(justify mirror)
			)
		)
		(property "Val" "10k"
			(at 0 0 180)
			(unlocked yes)
			(layer "B.Fab")
			(hide yes)
			(effects
				(font
					(size 1 1)
					(thickness 0.15)
				)
				(justify mirror)
			)
		)
		(property "Tolerance" "1%"
			(at 0 0 180)
			(unlocked yes)
			(layer "B.Fab")
			(hide yes)
			(effects
				(font
					(size 1 1)
					(thickness 0.15)
				)
				(justify mirror)
			)
		)
		(sheetname "/USB Hub/")
		(sheetfile "usb_hub.kicad_sch")
		(attr smd)
		(fp_rect
			(start -0.925 0.47)
			(end 0.925 -0.47)
			(stroke
				(width 0.05)
				(type default)
			)
			(fill no)
			(layer "B.CrtYd")
		)
		(fp_rect
			(start -0.5 0.25)
			(end 0.5 -0.25)
			(stroke
				(width 0.15)
				(type solid)
			)
			(fill no)
			(layer "B.Fab")
		)
		(fp_text user "${REFERENCE}"
			(at -0.95 -3.168 0)
			(layer "B.Fab")
			(effects
				(font
					(size 0.7 0.7)
					(thickness 0.15)
				)
				(justify right top mirror)
			)
		)
		(fp_text user "License: Apache-2.0"
			(at -0.95 -5.169 0)
			(layer "B.Fab")
			(effects
				(font
					(size 0.7 0.7)
					(thickness 0.15)
				)
				(justify right top mirror)
			)
		)
		(fp_text user "Author: Antmicro"
			(at -0.95 -4.169 0)
			(layer "B.Fab")
			(effects
				(font
					(size 0.7 0.7)
					(thickness 0.15)
				)
				(justify right top mirror)
			)
		)
		(pad "1" smd roundrect
			(at -0.48 0)
			(size 0.59 0.64)
			(layers "B.Cu" "B.Mask" "B.Paste")
			(roundrect_rratio 0.25)
			(net 1095 "/USB Hub/DP1_VCONN2")
			(pintype "passive")
		)
		(pad "2" smd roundrect
			(at 0.48 0)
			(size 0.59 0.64)
			(layers "B.Cu" "B.Mask" "B.Paste")
			(roundrect_rratio 0.25)
			(net 1 "GND")
			(pintype "passive")
		)
	)
	(footprint "antmicro-footprints:SOT-523"
		(layer "B.Cu")
		(at 169 60.8 -90)
		(property "Reference" "Q16"
			(at -1.2 -1 180)
			(layer "B.SilkS")
			(effects
				(font
					(size 0.7 0.7)
					(thickness 0.15)
				)
				(justify left bottom mirror)
			)
		)
		(property "Value" "DMG1012T-7"
			(at 0.1 -1.824 90)
			(layer "B.Fab")
			(effects
				(font
					(size 0.7 0.7)
					(thickness 0.15)
				)
				(justify left bottom mirror)
			)
		)
		(property "Datasheet" "https://www.diodes.com/assets/Datasheets/ds31783.pdf"
			(at 0 0 90)
			(layer "B.Fab")
			(hide yes)
			(effects
				(font
					(size 1.27 1.27)
					(thickness 0.15)
				)
				(justify mirror)
			)
		)
		(property "Description" "Power MOSFET, N Channel, 20 V, 630 mA, 0.3 ohm, SOT-523, Surface Mount"
			(at 0 0 90)
			(layer "B.Fab")
			(hide yes)
			(effects
				(font
					(size 1.27 1.27)
					(thickness 0.15)
				)
				(justify mirror)
			)
		)
		(property "MPN" "DMG1012T-7"
			(at 0 0 90)
			(unlocked yes)
			(layer "B.Fab")
			(hide yes)
			(effects
				(font
					(size 1 1)
					(thickness 0.15)
				)
				(justify mirror)
			)
		)
		(property "Manufacturer" "Diodes Incorporated"
			(at 0 0 90)
			(unlocked yes)
			(layer "B.Fab")
			(hide yes)
			(effects
				(font
					(size 1 1)
					(thickness 0.15)
				)
				(justify mirror)
			)
		)
		(property "Author" "Antmicro"
			(at 0 0 90)
			(unlocked yes)
			(layer "B.Fab")
			(hide yes)
			(effects
				(font
					(size 1 1)
					(thickness 0.15)
				)
				(justify mirror)
			)
		)
		(property "License" "Apache-2.0"
			(at 0 0 90)
			(unlocked yes)
			(layer "B.Fab")
			(hide yes)
			(effects
				(font
					(size 1 1)
					(thickness 0.15)
				)
				(justify mirror)
			)
		)
		(sheetname "/Power/")
		(sheetfile "power.kicad_sch")
		(attr smd)
		(fp_line
			(start -0.725 0.551)
			(end -0.277 0.551)
			(stroke
				(width 0.15)
				(type solid)
			)
			(layer "B.SilkS")
		)
		(fp_line
			(start -0.277 0.551)
			(end -0.277 0.75)
			(stroke
				(width 0.15)
				(type solid)
			)
			(layer "B.SilkS")
		)
		(fp_line
			(start -0.927 0.351)
			(end -0.725 0.551)
			(stroke
				(width 0.15)
				(type solid)
			)
			(layer "B.SilkS")
		)
		(fp_line
			(start -0.927 0.051)
			(end -0.927 0.351)
			(stroke
				(width 0.15)
				(type solid)
			)
			(layer "B.SilkS")
		)
		(fp_circle
			(center -0.9652 -0.9652)
			(end -0.9152 -0.9652)
			(stroke
				(width 0.15)
				(type solid)
			)
			(fill yes)
			(layer "B.SilkS")
		)
		(fp_line
			(start -1.12 1.16)
			(end 1.1 1.16)
			(stroke
				(width 0.05)
				(type solid)
			)
			(layer "B.CrtYd")
		)
		(fp_line
			(start -1.12 1.16)
			(end -1.12 -1.15)
			(stroke
				(width 0.05)
				(type solid)
			)
			(layer "B.CrtYd")
		)
		(fp_line
			(start 1.1 1.16)
			(end 1.1 -1.15)
			(stroke
				(width 0.05)
				(type solid)
			)
			(layer "B.CrtYd")
		)
		(fp_line
			(start -1.12 -1.15)
			(end 1.1 -1.15)
			(stroke
				(width 0.05)
				(type solid)
			)
			(layer "B.CrtYd")
		)
		(fp_line
			(start -0.652 0.425)
			(end -0.802 0.276)
			(stroke
				(width 0.15)
				(type solid)
			)
			(layer "B.Fab")
		)
		(fp_line
			(start 0.8 0.425)
			(end -0.652 0.425)
			(stroke
				(width 0.15)
				(type solid)
			)
			(layer "B.Fab")
		)
		(fp_line
			(start 0.8 0.425)
			(end 0.8 -0.424)
			(stroke
				(width 0.15)
				(type solid)
			)
			(layer "B.Fab")
		)
		(fp_line
			(start -0.802 0.276)
			(end -0.802 -0.424)
			(stroke
				(width 0.15)
				(type solid)
			)
			(layer "B.Fab")
		)
		(fp_line
			(start 0.8 -0.424)
			(end -0.802 -0.424)
			(stroke
				(width 0.15)
				(type solid)
			)
			(layer "B.Fab")
		)
		(fp_circle
			(center -0.9652 -0.9652)
			(end -0.9144 -0.9652)
			(stroke
				(width 0.15)
				(type solid)
			)
			(fill no)
			(layer "B.Fab")
		)
		(fp_text user "${REFERENCE}"
			(at -1.12 -3.824 90)
			(layer "B.Fab")
			(effects
				(font
					(size 0.7 0.7)
					(thickness 0.15)
				)
				(justify left bottom mirror)
			)
		)
		(fp_text user "Author: Antmicro"
			(at -1.12 -6.224 90)
			(layer "B.Fab")
			(effects
				(font
					(size 0.7 0.7)
					(thickness 0.15)
				)
				(justify left bottom mirror)
			)
		)
		(fp_text user "License: Apache-2.0"
			(at -1.12 -5.024 90)
			(layer "B.Fab")
			(effects
				(font
					(size 0.7 0.7)
					(thickness 0.15)
				)
				(justify left bottom mirror)
			)
		)
		(pad "1" smd rect
			(at -0.5 -0.65 270)
			(size 0.4 0.51)
			(layers "B.Cu" "B.Mask" "B.Paste")
			(net 11 "+1V8")
			(pinfunction "G")
			(pintype "input")
		)
		(pad "2" smd rect
			(at 0.498 -0.65 270)
			(size 0.4 0.51)
			(layers "B.Cu" "B.Mask" "B.Paste")
			(net 1 "GND")
			(pinfunction "S")
			(pintype "passive")
		)
		(pad "3" smd rect
			(at 0 0.652 270)
			(size 0.4 0.51)
			(layers "B.Cu" "B.Mask" "B.Paste")
			(net 644 "Net-(D43-C)")
			(pinfunction "D")
			(pintype "passive")
		)
	)
	(footprint "antmicro-footprints:C_0603_1608Metric_EIA"
		(layer "B.Cu")
		(at 124.6 139 180)
		(descr "Capacitor SMD 0603, IPC-7351 Density Level A")
		(tags "Capacitor 0603")
		(property "Reference" "C198"
			(at -4.6 -0.4 0)
			(layer "B.SilkS")
			(effects
				(font
					(size 0.7 0.7)
					(thickness 0.15)
				)
				(justify left bottom mirror)
			)
		)
		(property "Value" "C_22u_16V_0603"
			(at -1.42757 -1.770288 0)
			(layer "B.Fab")
			(effects
				(font
					(size 0.7 0.7)
					(thickness 0.15)
				)
				(justify left bottom mirror)
			)
		)
		(property "Datasheet" "https://product.samsungsem.com/mlcc/CL10A226MO7JZN.do"
			(at 0 0 0)
			(layer "B.Fab")
			(hide yes)
			(effects
				(font
					(size 1.27 1.27)
					(thickness 0.15)
				)
				(justify mirror)
			)
		)
		(property "Description" "SMD Multilayer Ceramic Capacitor"
			(at 0 0 0)
			(layer "B.Fab")
			(hide yes)
			(effects
				(font
					(size 1.27 1.27)
					(thickness 0.15)
				)
				(justify mirror)
			)
		)
		(property "MPN" "CL10A226MO7JZNC"
			(at 0 0 180)
			(unlocked yes)
			(layer "B.Fab")
			(hide yes)
			(effects
				(font
					(size 1 1)
					(thickness 0.15)
				)
				(justify mirror)
			)
		)
		(property "Manufacturer" "Samsung Electro-Mechanics"
			(at 0 0 180)
			(unlocked yes)
			(layer "B.Fab")
			(hide yes)
			(effects
				(font
					(size 1 1)
					(thickness 0.15)
				)
				(justify mirror)
			)
		)
		(property "License" "Apache-2.0"
			(at 0 0 180)
			(unlocked yes)
			(layer "B.Fab")
			(hide yes)
			(effects
				(font
					(size 1 1)
					(thickness 0.15)
				)
				(justify mirror)
			)
		)
		(property "Author" "Antmicro"
			(at 0 0 180)
			(unlocked yes)
			(layer "B.Fab")
			(hide yes)
			(effects
				(font
					(size 1 1)
					(thickness 0.15)
				)
				(justify mirror)
			)
		)
		(property "Val" "22u"
			(at 0 0 180)
			(unlocked yes)
			(layer "B.Fab")
			(hide yes)
			(effects
				(font
					(size 1 1)
					(thickness 0.15)
				)
				(justify mirror)
			)
		)
		(property "Voltage" "16V"
			(at 0 0 180)
			(unlocked yes)
			(layer "B.Fab")
			(hide yes)
			(effects
				(font
					(size 1 1)
					(thickness 0.15)
				)
				(justify mirror)
			)
		)
		(property "Dielectric" ""
			(at 0 0 180)
			(unlocked yes)
			(layer "B.Fab")
			(hide yes)
			(effects
				(font
					(size 1 1)
					(thickness 0.15)
				)
				(justify mirror)
			)
		)
		(sheetname "/M.2/")
		(sheetfile "m2.kicad_sch")
		(attr smd)
		(fp_line
			(start -0.15 0.55)
			(end 0.15 0.55)
			(stroke
				(width 0.15)
				(type solid)
			)
			(layer "B.SilkS")
		)
		(fp_line
			(start -0.15 -0.55)
			(end 0.15 -0.55)
			(stroke
				(width 0.15)
				(type solid)
			)
			(layer "B.SilkS")
		)
		(fp_rect
			(start -1.25 0.65)
			(end 1.25 -0.65)
			(stroke
				(width 0.05)
				(type solid)
			)
			(fill no)
			(layer "B.CrtYd")
		)
		(fp_rect
			(start -0.8 0.45)
			(end 0.8 -0.45)
			(stroke
				(width 0.15)
				(type solid)
			)
			(fill no)
			(layer "B.Fab")
		)
		(fp_text user "${REFERENCE}"
			(at -1.682 -3.895 0)
			(layer "B.Fab")
			(effects
				(font
					(size 0.7 0.7)
					(thickness 0.15)
				)
				(justify left bottom mirror)
			)
		)
		(fp_text user "License: Apache-2.0"
			(at -1.682 -5.895 0)
			(layer "B.Fab")
			(effects
				(font
					(size 0.7 0.7)
					(thickness 0.15)
				)
				(justify left bottom mirror)
			)
		)
		(fp_text user "Author: Antmicro"
			(at -1.682 -4.894 0)
			(layer "B.Fab")
			(effects
				(font
					(size 0.7 0.7)
					(thickness 0.15)
				)
				(justify left bottom mirror)
			)
		)
		(pad "1" smd roundrect
			(at -0.7 0 180)
			(size 0.8 1.1)
			(layers "B.Cu" "B.Mask" "B.Paste")
			(roundrect_rratio 0.2)
			(net 1 "GND")
			(pintype "passive")
		)
		(pad "2" smd roundrect
			(at 0.7 0 180)
			(size 0.8 1.1)
			(layers "B.Cu" "B.Mask" "B.Paste")
			(roundrect_rratio 0.2)
			(net 2 "+3V3")
			(pintype "passive")
		)
	)
	(footprint "antmicro-footprints:R_0402_1005Metric"
		(layer "B.Cu")
		(at 168 63.4 -90)
		(descr "Resistor SMD 0402")
		(tags "resistor SMD 0402")
		(property "Reference" "R341"
			(at 0.9 -0.4 90)
			(layer "B.SilkS")
			(effects
				(font
					(size 0.7 0.7)
					(thickness 0.15)
				)
				(justify left bottom mirror)
			)
		)
		(property "Value" "R_0R_0402"
			(at -1.011843 -1.772046 90)
			(layer "B.Fab")
			(effects
				(font
					(size 0.7 0.7)
					(thickness 0.15)
				)
				(justify left bottom mirror)
			)
		)
		(property "Datasheet" "https://industrial.panasonic.com/cdbs/www-data/pdf/RDA0000/AOA0000C301.pdf"
			(at 0 0 90)
			(layer "B.Fab")
			(hide yes)
			(effects
				(font
					(size 1.27 1.27)
					(thickness 0.15)
				)
				(justify mirror)
			)
		)
		(property "Description" "SMD Chip Resistor, Jumper, 0 ohm, 100 mW, 0402 [1005 Metric], Thick Film, General Purpose"
			(at 0 0 90)
			(layer "B.Fab")
			(hide yes)
			(effects
				(font
					(size 1.27 1.27)
					(thickness 0.15)
				)
				(justify mirror)
			)
		)
		(property "MPN" "ERJ2GE0R00X"
			(at 0 0 90)
			(unlocked yes)
			(layer "B.Fab")
			(hide yes)
			(effects
				(font
					(size 1 1)
					(thickness 0.15)
				)
				(justify mirror)
			)
		)
		(property "Manufacturer" "Panasonic"
			(at 0 0 90)
			(unlocked yes)
			(layer "B.Fab")
			(hide yes)
			(effects
				(font
					(size 1 1)
					(thickness 0.15)
				)
				(justify mirror)
			)
		)
		(property "License" "Apache-2.0"
			(at 0 0 90)
			(unlocked yes)
			(layer "B.Fab")
			(hide yes)
			(effects
				(font
					(size 1 1)
					(thickness 0.15)
				)
				(justify mirror)
			)
		)
		(property "Author" "Antmicro"
			(at 0 0 90)
			(unlocked yes)
			(layer "B.Fab")
			(hide yes)
			(effects
				(font
					(size 1 1)
					(thickness 0.15)
				)
				(justify mirror)
			)
		)
		(property "Val" "0R"
			(at 0 0 90)
			(unlocked yes)
			(layer "B.Fab")
			(hide yes)
			(effects
				(font
					(size 1 1)
					(thickness 0.15)
				)
				(justify mirror)
			)
		)
		(property "Tolerance" "~"
			(at 0 0 90)
			(unlocked yes)
			(layer "B.Fab")
			(hide yes)
			(effects
				(font
					(size 1 1)
					(thickness 0.15)
				)
				(justify mirror)
			)
		)
		(property "Current" "1A"
			(at 0 0 90)
			(unlocked yes)
			(layer "B.Fab")
			(hide yes)
			(effects
				(font
					(size 1 1)
					(thickness 0.15)
				)
				(justify mirror)
			)
		)
		(sheetname "/SoM_IO2/")
		(sheetfile "som_io2.kicad_sch")
		(attr smd exclude_from_pos_files exclude_from_bom dnp)
		(fp_poly
			(pts
				(xy -0.925 0.47) (xy -0.925 -0.47) (xy 0.925 -0.47) (xy 0.925 0.47)
			)
			(stroke
				(width 0.05)
				(type default)
			)
			(fill no)
			(layer "B.CrtYd")
		)
		(fp_poly
			(pts
				(xy -0.5 0.25) (xy -0.5 -0.25) (xy 0.5 -0.25) (xy 0.5 0.25)
			)
			(stroke
				(width 0.15)
				(type solid)
			)
			(fill no)
			(layer "B.Fab")
		)
		(fp_text user "${REFERENCE}"
			(at -0.95 -3.168 90)
			(layer "B.Fab")
			(effects
				(font
					(size 0.7 0.7)
					(thickness 0.15)
				)
				(justify left bottom mirror)
			)
		)
		(fp_text user "License: Apache-2.0"
			(at -0.949999 -5.169 90)
			(layer "B.Fab")
			(effects
				(font
					(size 0.7 0.7)
					(thickness 0.15)
				)
				(justify left bottom mirror)
			)
		)
		(fp_text user "Author: Antmicro"
			(at -0.95 -4.169 90)
			(layer "B.Fab")
			(effects
				(font
					(size 0.7 0.7)
					(thickness 0.15)
				)
				(justify left bottom mirror)
			)
		)
		(pad "1" smd roundrect
			(at -0.48 0 270)
			(size 0.59 0.64)
			(layers "B.Cu" "B.Mask" "B.Paste")
			(roundrect_rratio 0.25)
			(net 269 "/SoM_IO2/TC_VCC")
			(pintype "passive")
		)
		(pad "2" smd roundrect
			(at 0.48 0 270)
			(size 0.59 0.64)
			(layers "B.Cu" "B.Mask" "B.Paste")
			(roundrect_rratio 0.25)
			(net 2 "+3V3")
			(pintype "passive")
		)
	)
	(footprint "antmicro-footprints:R_0402_1005Metric"
		(layer "B.Cu")
		(at 215.5 84.3 90)
		(descr "Resistor SMD 0402")
		(tags "resistor SMD 0402")
		(property "Reference" "R137"
			(at -0.97 1.6 90)
			(layer "B.SilkS")
			(effects
				(font
					(size 0.7 0.7)
					(thickness 0.15)
				)
				(justify right top mirror)
			)
		)
		(property "Value" "R_1k_0402"
			(at -1.011843 -1.772047 90)
			(layer "B.Fab")
			(effects
				(font
					(size 0.7 0.7)
					(thickness 0.15)
				)
				(justify right top mirror)
			)
		)
		(property "Datasheet" "https://www.bourns.com/docs/product-datasheets/cr.pdf"
			(at 0 0 90)
			(layer "B.Fab")
			(hide yes)
			(effects
				(font
					(size 1.27 1.27)
					(thickness 0.15)
				)
				(justify mirror)
			)
		)
		(property "Description" "SMD Chip Resistor, 1 kohm, ± 1%, 63 mW, 0402 [1005 Metric], Thick Film, General Purpose"
			(at 0 0 90)
			(layer "B.Fab")
			(hide yes)
			(effects
				(font
					(size 1.27 1.27)
					(thickness 0.15)
				)
				(justify mirror)
			)
		)
		(property "Manufacturer" "Bourns"
			(at 0 0 270)
			(unlocked yes)
			(layer "B.Fab")
			(hide yes)
			(effects
				(font
					(size 1 1)
					(thickness 0.15)
				)
				(justify mirror)
			)
		)
		(property "MPN" "CR0402-FX-1001GLF"
			(at 0 0 270)
			(unlocked yes)
			(layer "B.Fab")
			(hide yes)
			(effects
				(font
					(size 1 1)
					(thickness 0.15)
				)
				(justify mirror)
			)
		)
		(property "Val" "1k"
			(at 0 0 270)
			(unlocked yes)
			(layer "B.Fab")
			(hide yes)
			(effects
				(font
					(size 1 1)
					(thickness 0.15)
				)
				(justify mirror)
			)
		)
		(property "License" "Apache-2.0"
			(at 0 0 270)
			(unlocked yes)
			(layer "B.Fab")
			(hide yes)
			(effects
				(font
					(size 1 1)
					(thickness 0.15)
				)
				(justify mirror)
			)
		)
		(property "Author" "Antmicro"
			(at 0 0 270)
			(unlocked yes)
			(layer "B.Fab")
			(hide yes)
			(effects
				(font
					(size 1 1)
					(thickness 0.15)
				)
				(justify mirror)
			)
		)
		(property "Tolerance" "1%"
			(at 0 0 270)
			(unlocked yes)
			(layer "B.Fab")
			(hide yes)
			(effects
				(font
					(size 1 1)
					(thickness 0.15)
				)
				(justify mirror)
			)
		)
		(sheetname "/USB DP Alt mode/")
		(sheetfile "usb_dp.kicad_sch")
		(attr smd)
		(fp_rect
			(start -0.925 0.47)
			(end 0.925 -0.47)
			(stroke
				(width 0.05)
				(type default)
			)
			(fill no)
			(layer "B.CrtYd")
		)
		(fp_rect
			(start -0.5 0.25)
			(end 0.5 -0.25)
			(stroke
				(width 0.15)
				(type solid)
			)
			(fill no)
			(layer "B.Fab")
		)
		(fp_text user "Author: Antmicro"
			(at -0.95 -4.169 90)
			(layer "B.Fab")
			(effects
				(font
					(size 0.7 0.7)
					(thickness 0.15)
				)
				(justify right top mirror)
			)
		)
		(fp_text user "${REFERENCE}"
			(at -0.95 -3.168 90)
			(layer "B.Fab")
			(effects
				(font
					(size 0.7 0.7)
					(thickness 0.15)
				)
				(justify right top mirror)
			)
		)
		(fp_text user "License: Apache-2.0"
			(at -0.95 -5.169 90)
			(layer "B.Fab")
			(effects
				(font
					(size 0.7 0.7)
					(thickness 0.15)
				)
				(justify right top mirror)
			)
		)
		(pad "1" smd roundrect
			(at -0.48 0 90)
			(size 0.59 0.64)
			(layers "B.Cu" "B.Mask" "B.Paste")
			(roundrect_rratio 0.25)
			(net 967 "/USB DP Alt mode/USBC1_DPEQ1")
			(pintype "passive")
		)
		(pad "2" smd roundrect
			(at 0.48 0 90)
			(size 0.59 0.64)
			(layers "B.Cu" "B.Mask" "B.Paste")
			(roundrect_rratio 0.25)
			(net 1 "GND")
			(pintype "passive")
		)
	)
	(footprint "antmicro-footprints:TP_SMD_0.75mm"
		(layer "B.Cu")
		(at 83.5 59.9 -90)
		(property "Reference" "TP84"
			(at 0.44 0.51 180)
			(layer "B.SilkS")
			(effects
				(font
					(size 0.7 0.7)
					(thickness 0.15)
				)
				(justify left bottom mirror)
			)
		)
		(property "Value" "TP_0.75mm_SMD"
			(at 0 -1.2 90)
			(layer "B.Fab")
			(effects
				(font
					(size 0.7 0.7)
					(thickness 0.15)
				)
				(justify left bottom mirror)
			)
		)
		(property "Description" "SMT test point"
			(at 0 0 90)
			(layer "B.Fab")
			(hide yes)
			(effects
				(font
					(size 1.27 1.27)
					(thickness 0.15)
				)
				(justify mirror)
			)
		)
		(property "MPN" ""
			(at 0 0 90)
			(unlocked yes)
			(layer "B.Fab")
			(hide yes)
			(effects
				(font
					(size 1 1)
					(thickness 0.15)
				)
				(justify mirror)
			)
		)
		(property "Manufacturer" ""
			(at 0 0 90)
			(unlocked yes)
			(layer "B.Fab")
			(hide yes)
			(effects
				(font
					(size 1 1)
					(thickness 0.15)
				)
				(justify mirror)
			)
		)
		(property "Author" "Antmicro"
			(at 0 0 90)
			(unlocked yes)
			(layer "B.Fab")
			(hide yes)
			(effects
				(font
					(size 1 1)
					(thickness 0.15)
				)
				(justify mirror)
			)
		)
		(property "License" "Apache-2.0"
			(at 0 0 90)
			(unlocked yes)
			(layer "B.Fab")
			(hide yes)
			(effects
				(font
					(size 1 1)
					(thickness 0.15)
				)
				(justify mirror)
			)
		)
		(sheetname "/SoM_Power/")
		(sheetfile "som_power.kicad_sch")
		(attr exclude_from_pos_files exclude_from_bom)
		(fp_circle
			(center 0 0)
			(end 0.475 0)
			(stroke
				(width 0.05)
				(type default)
			)
			(fill no)
			(layer "B.CrtYd")
		)
		(fp_text user "Author: Antmicro"
			(at -0.4 -3.901 90)
			(layer "B.Fab")
			(effects
				(font
					(size 0.7 0.7)
					(thickness 0.15)
				)
				(justify left bottom mirror)
			)
		)
		(fp_text user "${REFERENCE}"
			(at -0.4 -2.7 90)
			(layer "B.Fab")
			(effects
				(font
					(size 0.7 0.7)
					(thickness 0.15)
				)
				(justify left bottom mirror)
			)
		)
		(fp_text user "License: Apache-2.0"
			(at -0.4 -5.101 90)
			(layer "B.Fab")
			(effects
				(font
					(size 0.7 0.7)
					(thickness 0.15)
				)
				(justify left bottom mirror)
			)
		)
		(pad "1" smd circle
			(at 0 0 270)
			(size 0.75 0.75)
			(layers "B.Cu" "B.Mask")
			(net 683 "/SoM_Power/~{SOM_PRSNT}")
			(pinfunction "1")
			(pintype "passive")
		)
	)
	(footprint "antmicro-footprints:TP_SMD_0.75mm"
		(layer "B.Cu")
		(at 102.4 76.7 180)
		(property "Reference" "TP74"
			(at 0 0.6 0)
			(layer "B.SilkS")
			(effects
				(font
					(size 0.7 0.7)
					(thickness 0.15)
				)
				(justify left bottom mirror)
			)
		)
		(property "Value" "TP_0.75mm_SMD"
			(at 0 -1.2 0)
			(layer "B.Fab")
			(effects
				(font
					(size 0.7 0.7)
					(thickness 0.15)
				)
				(justify left bottom mirror)
			)
		)
		(property "Description" "SMT test point"
			(at 0 0 0)
			(layer "B.Fab")
			(hide yes)
			(effects
				(font
					(size 1.27 1.27)
					(thickness 0.15)
				)
				(justify mirror)
			)
		)
		(property "MPN" ""
			(at 0 0 0)
			(unlocked yes)
			(layer "B.Fab")
			(hide yes)
			(effects
				(font
					(size 1 1)
					(thickness 0.15)
				)
				(justify mirror)
			)
		)
		(property "Manufacturer" ""
			(at 0 0 0)
			(unlocked yes)
			(layer "B.Fab")
			(hide yes)
			(effects
				(font
					(size 1 1)
					(thickness 0.15)
				)
				(justify mirror)
			)
		)
		(property "Author" "Antmicro"
			(at 0 0 0)
			(unlocked yes)
			(layer "B.Fab")
			(hide yes)
			(effects
				(font
					(size 1 1)
					(thickness 0.15)
				)
				(justify mirror)
			)
		)
		(property "License" "Apache-2.0"
			(at 0 0 0)
			(unlocked yes)
			(layer "B.Fab")
			(hide yes)
			(effects
				(font
					(size 1 1)
					(thickness 0.15)
				)
				(justify mirror)
			)
		)
		(sheetname "/SoM_IO/")
		(sheetfile "som_io.kicad_sch")
		(attr exclude_from_pos_files exclude_from_bom)
		(fp_circle
			(center 0 0)
			(end 0.475 0)
			(stroke
				(width 0.05)
				(type default)
			)
			(fill no)
			(layer "B.CrtYd")
		)
		(fp_text user "Author: Antmicro"
			(at -0.4 -3.901 0)
			(layer "B.Fab")
			(effects
				(font
					(size 0.7 0.7)
					(thickness 0.15)
				)
				(justify left bottom mirror)
			)
		)
		(fp_text user "License: Apache-2.0"
			(at -0.4 -5.101 0)
			(layer "B.Fab")
			(effects
				(font
					(size 0.7 0.7)
					(thickness 0.15)
				)
				(justify left bottom mirror)
			)
		)
		(fp_text user "${REFERENCE}"
			(at -0.4 -2.7 0)
			(layer "B.Fab")
			(effects
				(font
					(size 0.7 0.7)
					(thickness 0.15)
				)
				(justify left bottom mirror)
			)
		)
		(pad "1" smd circle
			(at 0 0 180)
			(size 0.75 0.75)
			(layers "B.Cu" "B.Mask")
			(net 111 "/Expansion connector/I2S3.FS")
			(pinfunction "1")
			(pintype "passive")
		)
	)
	(footprint "antmicro-footprints:C_0805_2012Metric"
		(layer "B.Cu")
		(at 85.2 67.2)
		(descr "Capacitor SMD 0805")
		(tags "capacitor SMD 0805")
		(property "Reference" "C27"
			(at -1.06 1.09 0)
			(layer "B.SilkS")
			(effects
				(font
					(size 0.7 0.7)
					(thickness 0.15)
				)
				(justify right top mirror)
			)
		)
		(property "Value" "C_22u_25V_0805"
			(at -2.055717 -1.963153 0)
			(layer "B.Fab")
			(effects
				(font
					(size 0.7 0.7)
					(thickness 0.15)
				)
				(justify right top mirror)
			)
		)
		(property "Datasheet" "https://product.samsungsem.com/mlcc/CL21A226MAYNNN.do"
			(at 0 0 0)
			(layer "B.Fab")
			(hide yes)
			(effects
				(font
					(size 1.27 1.27)
					(thickness 0.15)
				)
				(justify mirror)
			)
		)
		(property "Description" "SMT Multilayer Ceramic Capacitor, 22uF, +/-20%, 25V, X5R, 0805 [2012 Metric]"
			(at 0 0 0)
			(layer "B.Fab")
			(hide yes)
			(effects
				(font
					(size 1.27 1.27)
					(thickness 0.15)
				)
				(justify mirror)
			)
		)
		(property "MPN" "CL21A226MAYNNNE"
			(at 0 0 180)
			(unlocked yes)
			(layer "B.Fab")
			(hide yes)
			(effects
				(font
					(size 1 1)
					(thickness 0.15)
				)
				(justify mirror)
			)
		)
		(property "Manufacturer" "Samsung Electro-Mechanics"
			(at 0 0 180)
			(unlocked yes)
			(layer "B.Fab")
			(hide yes)
			(effects
				(font
					(size 1 1)
					(thickness 0.15)
				)
				(justify mirror)
			)
		)
		(property "License" "Apache-2.0"
			(at 0 0 180)
			(unlocked yes)
			(layer "B.Fab")
			(hide yes)
			(effects
				(font
					(size 1 1)
					(thickness 0.15)
				)
				(justify mirror)
			)
		)
		(property "Author" "Antmicro"
			(at 0 0 180)
			(unlocked yes)
			(layer "B.Fab")
			(hide yes)
			(effects
				(font
					(size 1 1)
					(thickness 0.15)
				)
				(justify mirror)
			)
		)
		(property "Val" "22u"
			(at 0 0 180)
			(unlocked yes)
			(layer "B.Fab")
			(hide yes)
			(effects
				(font
					(size 1 1)
					(thickness 0.15)
				)
				(justify mirror)
			)
		)
		(property "Voltage" "25V"
			(at 0 0 180)
			(unlocked yes)
			(layer "B.Fab")
			(hide yes)
			(effects
				(font
					(size 1 1)
					(thickness 0.15)
				)
				(justify mirror)
			)
		)
		(property "Dielectric" "X5R"
			(at 0 0 180)
			(unlocked yes)
			(layer "B.Fab")
			(hide yes)
			(effects
				(font
					(size 1 1)
					(thickness 0.15)
				)
				(justify mirror)
			)
		)
		(property "Public" "False"
			(at 0 0 180)
			(unlocked yes)
			(layer "B.Fab")
			(hide yes)
			(effects
				(font
					(size 1 1)
					(thickness 0.15)
				)
				(justify mirror)
			)
		)
		(sheetname "/SoM_Power/")
		(sheetfile "som_power.kicad_sch")
		(attr smd)
		(fp_line
			(start -0.3 -0.7)
			(end 0.3 -0.7)
			(stroke
				(width 0.15)
				(type solid)
			)
			(layer "B.SilkS")
		)
		(fp_line
			(start -0.3 0.7)
			(end 0.3 0.7)
			(stroke
				(width 0.15)
				(type solid)
			)
			(layer "B.SilkS")
		)
		(fp_poly
			(pts
				(xy 1.95 0.9) (xy -1.95 0.9) (xy -1.95 -0.9) (xy 1.95 -0.9)
			)
			(stroke
				(width 0.05)
				(type default)
			)
			(fill no)
			(layer "B.CrtYd")
		)
		(fp_poly
			(pts
				(xy -0.95 0.675001) (xy 0.95 0.675001) (xy 0.95 -0.675001) (xy -0.95 -0.675001)
			)
			(stroke
				(width 0.15)
				(type solid)
			)
			(fill no)
			(layer "B.Fab")
		)
		(fp_text user "${REFERENCE}"
			(at -1.899999 -3.947 0)
			(layer "B.Fab")
			(effects
				(font
					(size 0.7 0.7)
					(thickness 0.15)
				)
				(justify right top mirror)
			)
		)
		(fp_text user "License: Apache-2.0"
			(at -1.9 -4.947 0)
			(layer "B.Fab")
			(effects
				(font
					(size 0.7 0.7)
					(thickness 0.15)
				)
				(justify right top mirror)
			)
		)
		(fp_text user "Author: Antmicro"
			(at -1.9 -5.947 0)
			(layer "B.Fab")
			(effects
				(font
					(size 0.7 0.7)
					(thickness 0.15)
				)
				(justify right top mirror)
			)
		)
		(pad "1" smd roundrect
			(at -1.099999 0)
			(size 1.2 1.3)
			(layers "B.Cu" "B.Mask" "B.Paste")
			(roundrect_rratio 0.25)
			(net 1 "GND")
			(pintype "passive")
		)
		(pad "2" smd roundrect
			(at 1.099999 0)
			(size 1.2 1.3)
			(layers "B.Cu" "B.Mask" "B.Paste")
			(roundrect_rratio 0.25)
			(net 12 "SYS_VIN_HV")
			(pintype "passive")
		)
	)
	(footprint "antmicro-footprints:C_0402_1005Metric"
		(layer "B.Cu")
		(at 180.285 78.175)
		(descr "Capacitor SMD 0402")
		(tags "capacitor SMD 0402")
		(property "Reference" "C266"
			(at -5.585 -0.375 0)
			(layer "B.SilkS")
			(effects
				(font
					(size 0.7 0.7)
					(thickness 0.15)
				)
				(justify right top mirror)
			)
		)
		(property "Value" "C_1u_25V_0402"
			(at -1.022927 -2.155213 0)
			(layer "B.Fab")
			(effects
				(font
					(size 0.7 0.7)
					(thickness 0.15)
				)
				(justify right top mirror)
			)
		)
		(property "Datasheet" "https://www.murata.com/products/productdetail?partno=GRM155R61E105KE11%23"
			(at 0 0 0)
			(layer "B.Fab")
			(hide yes)
			(effects
				(font
					(size 1.27 1.27)
					(thickness 0.15)
				)
				(justify mirror)
			)
		)
		(property "Description" "SMD Multilayer Ceramic Capacitor, 1 µF, 25 V, 0402 [1005 Metric], ± 10%, X5R, GRM Series"
			(at 0 0 0)
			(layer "B.Fab")
			(hide yes)
			(effects
				(font
					(size 1.27 1.27)
					(thickness 0.15)
				)
				(justify mirror)
			)
		)
		(property "MPN" "GRM155R61E105KE11J"
			(at 0 0 180)
			(unlocked yes)
			(layer "B.Fab")
			(hide yes)
			(effects
				(font
					(size 1 1)
					(thickness 0.15)
				)
				(justify mirror)
			)
		)
		(property "Manufacturer" "Murata"
			(at 0 0 180)
			(unlocked yes)
			(layer "B.Fab")
			(hide yes)
			(effects
				(font
					(size 1 1)
					(thickness 0.15)
				)
				(justify mirror)
			)
		)
		(property "License" "Apache-2.0"
			(at 0 0 180)
			(unlocked yes)
			(layer "B.Fab")
			(hide yes)
			(effects
				(font
					(size 1 1)
					(thickness 0.15)
				)
				(justify mirror)
			)
		)
		(property "Author" "Antmicro"
			(at 0 0 180)
			(unlocked yes)
			(layer "B.Fab")
			(hide yes)
			(effects
				(font
					(size 1 1)
					(thickness 0.15)
				)
				(justify mirror)
			)
		)
		(property "Val" "1u"
			(at 0 0 180)
			(unlocked yes)
			(layer "B.Fab")
			(hide yes)
			(effects
				(font
					(size 1 1)
					(thickness 0.15)
				)
				(justify mirror)
			)
		)
		(property "Voltage" "25V"
			(at 0 0 180)
			(unlocked yes)
			(layer "B.Fab")
			(hide yes)
			(effects
				(font
					(size 1 1)
					(thickness 0.15)
				)
				(justify mirror)
			)
		)
		(property "Dielectric" "X5R"
			(at 0 0 180)
			(unlocked yes)
			(layer "B.Fab")
			(hide yes)
			(effects
				(font
					(size 1 1)
					(thickness 0.15)
				)
				(justify mirror)
			)
		)
		(sheetname "/Power/")
		(sheetfile "power.kicad_sch")
		(attr smd)
		(fp_rect
			(start -0.925 0.47)
			(end 0.925 -0.47)
			(stroke
				(width 0.05)
				(type default)
			)
			(fill no)
			(layer "B.CrtYd")
		)
		(fp_line
			(start -0.494 -0.248)
			(end -0.494 0.25)
			(stroke
				(width 0.15)
				(type solid)
			)
			(layer "B.Fab")
		)
		(fp_line
			(start -0.494 0.25)
			(end 0.504 0.25)
			(stroke
				(width 0.15)
				(type solid)
			)
			(layer "B.Fab")
		)
		(fp_line
			(start 0.504 -0.248)
			(end -0.494 -0.248)
			(stroke
				(width 0.15)
				(type solid)
			)
			(layer "B.Fab")
		)
		(fp_line
			(start 0.504 0.25)
			(end 0.504 -0.248)
			(stroke
				(width 0.15)
				(type solid)
			)
			(layer "B.Fab")
		)
		(fp_text user "Author: Antmicro"
			(at -0.939 -3.399 0)
			(layer "B.Fab")
			(effects
				(font
					(size 0.7 0.7)
					(thickness 0.15)
				)
				(justify right top mirror)
			)
		)
		(fp_text user "${REFERENCE}"
			(at -0.939 -4.599 0)
			(layer "B.Fab")
			(effects
				(font
					(size 0.7 0.7)
					(thickness 0.15)
				)
				(justify right top mirror)
			)
		)
		(fp_text user "License: Apache-2.0"
			(at -0.939 -5.799 0)
			(layer "B.Fab")
			(effects
				(font
					(size 0.7 0.7)
					(thickness 0.15)
				)
				(justify right top mirror)
			)
		)
		(pad "1" smd roundrect
			(at -0.48 0)
			(size 0.59 0.64)
			(layers "B.Cu" "B.Mask" "B.Paste")
			(roundrect_rratio 0.25)
			(net 1 "GND")
			(pintype "passive")
		)
		(pad "2" smd roundrect
			(at 0.48 0)
			(size 0.59 0.64)
			(layers "B.Cu" "B.Mask" "B.Paste")
			(roundrect_rratio 0.25)
			(net 525 "/Power/USBPD2_HV")
			(pintype "passive")
		)
	)
	(footprint "antmicro-footprints:R_0402_1005Metric"
		(layer "B.Cu")
		(at 215.8 100.4 180)
		(descr "Resistor SMD 0402")
		(tags "resistor SMD 0402")
		(property "Reference" "R256"
			(at 1 -0.5 0)
			(layer "B.SilkS")
			(effects
				(font
					(size 0.7 0.7)
					(thickness 0.15)
				)
				(justify left bottom mirror)
			)
		)
		(property "Value" "R_10k_0402"
			(at -1.011843 -1.772047 0)
			(layer "B.Fab")
			(effects
				(font
					(size 0.7 0.7)
					(thickness 0.15)
				)
				(justify left bottom mirror)
			)
		)
		(property "Datasheet" "https://www.bourns.com/docs/product-datasheets/cr.pdf"
			(at 0 0 0)
			(layer "B.Fab")
			(hide yes)
			(effects
				(font
					(size 1.27 1.27)
					(thickness 0.15)
				)
				(justify mirror)
			)
		)
		(property "Description" "SMD Chip Resistor, 10 kohm, ± 1%, 62.5 mW, 0402 [1005 Metric], Thick Film, General Purpose"
			(at 0 0 0)
			(layer "B.Fab")
			(hide yes)
			(effects
				(font
					(size 1.27 1.27)
					(thickness 0.15)
				)
				(justify mirror)
			)
		)
		(property "Manufacturer" "Bourns"
			(at 0 0 0)
			(unlocked yes)
			(layer "B.Fab")
			(hide yes)
			(effects
				(font
					(size 1 1)
					(thickness 0.15)
				)
				(justify mirror)
			)
		)
		(property "MPN" "CR0402-FX-1002GLF"
			(at 0 0 0)
			(unlocked yes)
			(layer "B.Fab")
			(hide yes)
			(effects
				(font
					(size 1 1)
					(thickness 0.15)
				)
				(justify mirror)
			)
		)
		(property "Val" "10k"
			(at 0 0 0)
			(unlocked yes)
			(layer "B.Fab")
			(hide yes)
			(effects
				(font
					(size 1 1)
					(thickness 0.15)
				)
				(justify mirror)
			)
		)
		(property "License" "Apache-2.0"
			(at 0 0 0)
			(unlocked yes)
			(layer "B.Fab")
			(hide yes)
			(effects
				(font
					(size 1 1)
					(thickness 0.15)
				)
				(justify mirror)
			)
		)
		(property "Author" "Antmicro"
			(at 0 0 0)
			(unlocked yes)
			(layer "B.Fab")
			(hide yes)
			(effects
				(font
					(size 1 1)
					(thickness 0.15)
				)
				(justify mirror)
			)
		)
		(property "Tolerance" "1%"
			(at 0 0 0)
			(unlocked yes)
			(layer "B.Fab")
			(hide yes)
			(effects
				(font
					(size 1 1)
					(thickness 0.15)
				)
				(justify mirror)
			)
		)
		(sheetname "/Recovery USB/")
		(sheetfile "recovery_usb.kicad_sch")
		(attr smd)
		(fp_rect
			(start -0.925 0.47)
			(end 0.925 -0.47)
			(stroke
				(width 0.05)
				(type default)
			)
			(fill no)
			(layer "B.CrtYd")
		)
		(fp_rect
			(start -0.5 0.25)
			(end 0.5 -0.25)
			(stroke
				(width 0.15)
				(type solid)
			)
			(fill no)
			(layer "B.Fab")
		)
		(fp_text user "License: Apache-2.0"
			(at -0.95 -5.169 0)
			(layer "B.Fab")
			(effects
				(font
					(size 0.7 0.7)
					(thickness 0.15)
				)
				(justify left bottom mirror)
			)
		)
		(fp_text user "${REFERENCE}"
			(at -0.95 -3.168 0)
			(layer "B.Fab")
			(effects
				(font
					(size 0.7 0.7)
					(thickness 0.15)
				)
				(justify left bottom mirror)
			)
		)
		(fp_text user "Author: Antmicro"
			(at -0.95 -4.169 0)
			(layer "B.Fab")
			(effects
				(font
					(size 0.7 0.7)
					(thickness 0.15)
				)
				(justify left bottom mirror)
			)
		)
		(pad "1" smd roundrect
			(at -0.48 0 180)
			(size 0.59 0.64)
			(layers "B.Cu" "B.Mask" "B.Paste")
			(roundrect_rratio 0.25)
			(net 1014 "/Recovery USB/USBC2_FAULT_N")
			(pintype "passive")
		)
		(pad "2" smd roundrect
			(at 0.48 0 180)
			(size 0.59 0.64)
			(layers "B.Cu" "B.Mask" "B.Paste")
			(roundrect_rratio 0.25)
			(net 5 "+5V")
			(pintype "passive")
		)
	)
	(footprint "antmicro-footprints:R_0402_1005Metric"
		(layer "B.Cu")
		(at 196.68 77.16 180)
		(descr "Resistor SMD 0402")
		(tags "resistor SMD 0402")
		(property "Reference" "R106"
			(at -3.67 -0.44 0)
			(layer "B.SilkS")
			(effects
				(font
					(size 0.7 0.7)
					(thickness 0.15)
				)
				(justify left bottom mirror)
			)
		)
		(property "Value" "R_0R_0402"
			(at -1.011843 -1.772046 0)
			(layer "B.Fab")
			(effects
				(font
					(size 0.7 0.7)
					(thickness 0.15)
				)
				(justify left bottom mirror)
			)
		)
		(property "Datasheet" "https://industrial.panasonic.com/cdbs/www-data/pdf/RDA0000/AOA0000C301.pdf"
			(at 0 0 0)
			(layer "B.Fab")
			(hide yes)
			(effects
				(font
					(size 1.27 1.27)
					(thickness 0.15)
				)
				(justify mirror)
			)
		)
		(property "Description" "SMD Chip Resistor, Jumper, 0 ohm, 100 mW, 0402 [1005 Metric], Thick Film, General Purpose"
			(at 0 0 0)
			(layer "B.Fab")
			(hide yes)
			(effects
				(font
					(size 1.27 1.27)
					(thickness 0.15)
				)
				(justify mirror)
			)
		)
		(property "Manufacturer" "Panasonic"
			(at 0 0 0)
			(unlocked yes)
			(layer "B.Fab")
			(hide yes)
			(effects
				(font
					(size 1 1)
					(thickness 0.15)
				)
				(justify mirror)
			)
		)
		(property "MPN" "ERJ2GE0R00X"
			(at 0 0 0)
			(unlocked yes)
			(layer "B.Fab")
			(hide yes)
			(effects
				(font
					(size 1 1)
					(thickness 0.15)
				)
				(justify mirror)
			)
		)
		(property "Val" "0R"
			(at 0 0 0)
			(unlocked yes)
			(layer "B.Fab")
			(hide yes)
			(effects
				(font
					(size 1 1)
					(thickness 0.15)
				)
				(justify mirror)
			)
		)
		(property "License" "Apache-2.0"
			(at 0 0 0)
			(unlocked yes)
			(layer "B.Fab")
			(hide yes)
			(effects
				(font
					(size 1 1)
					(thickness 0.15)
				)
				(justify mirror)
			)
		)
		(property "Author" "Antmicro"
			(at 0 0 0)
			(unlocked yes)
			(layer "B.Fab")
			(hide yes)
			(effects
				(font
					(size 1 1)
					(thickness 0.15)
				)
				(justify mirror)
			)
		)
		(property "Tolerance" "~"
			(at 0 0 0)
			(unlocked yes)
			(layer "B.Fab")
			(hide yes)
			(effects
				(font
					(size 1 1)
					(thickness 0.15)
				)
				(justify mirror)
			)
		)
		(property "Current" "1A"
			(at 0 0 0)
			(unlocked yes)
			(layer "B.Fab")
			(hide yes)
			(effects
				(font
					(size 1 1)
					(thickness 0.15)
				)
				(justify mirror)
			)
		)
		(sheetname "/USB Debug, PD/")
		(sheetfile "usb_debug_pd.kicad_sch")
		(attr smd)
		(fp_poly
			(pts
				(xy -0.925 0.47) (xy 0.925 0.47) (xy 0.925 -0.47) (xy -0.925 -0.47)
			)
			(stroke
				(width 0.05)
				(type default)
			)
			(fill no)
			(layer "B.CrtYd")
		)
		(fp_poly
			(pts
				(xy -0.5 0.25) (xy 0.5 0.25) (xy 0.5 -0.25) (xy -0.5 -0.25)
			)
			(stroke
				(width 0.15)
				(type solid)
			)
			(fill no)
			(layer "B.Fab")
		)
		(fp_text user "License: Apache-2.0"
			(at -0.949999 -5.169 0)
			(layer "B.Fab")
			(effects
				(font
					(size 0.7 0.7)
					(thickness 0.15)
				)
				(justify left bottom mirror)
			)
		)
		(fp_text user "${REFERENCE}"
			(at -0.95 -3.168 0)
			(layer "B.Fab")
			(effects
				(font
					(size 0.7 0.7)
					(thickness 0.15)
				)
				(justify left bottom mirror)
			)
		)
		(fp_text user "Author: Antmicro"
			(at -0.95 -4.169 0)
			(layer "B.Fab")
			(effects
				(font
					(size 0.7 0.7)
					(thickness 0.15)
				)
				(justify left bottom mirror)
			)
		)
		(pad "1" smd roundrect
			(at -0.48 0 180)
			(size 0.59 0.64)
			(layers "B.Cu" "B.Mask" "B.Paste")
			(roundrect_rratio 0.25)
			(net 948 "/USB DP Alt mode/USBC_HPD")
			(pintype "passive")
		)
		(pad "2" smd roundrect
			(at 0.48 0 180)
			(size 0.59 0.64)
			(layers "B.Cu" "B.Mask" "B.Paste")
			(roundrect_rratio 0.25)
			(net 949 "/USB Debug, PD/PDC_HPD2")
			(pintype "passive")
		)
	)
	(footprint "antmicro-footprints:R_0402_1005Metric"
		(layer "B.Cu")
		(at 76 65.5 180)
		(descr "Resistor SMD 0402")
		(tags "resistor SMD 0402")
		(property "Reference" "R319"
			(at -1.6 -2.4 0)
			(layer "B.SilkS")
			(effects
				(font
					(size 0.7 0.7)
					(thickness 0.15)
				)
				(justify left bottom mirror)
			)
		)
		(property "Value" "R_10k_0402"
			(at -1.011843 -1.772046 0)
			(layer "B.Fab")
			(effects
				(font
					(size 0.7 0.7)
					(thickness 0.15)
				)
				(justify left bottom mirror)
			)
		)
		(property "Datasheet" "https://www.bourns.com/docs/product-datasheets/cr.pdf"
			(at 0 0 0)
			(layer "B.Fab")
			(hide yes)
			(effects
				(font
					(size 1.27 1.27)
					(thickness 0.15)
				)
				(justify mirror)
			)
		)
		(property "Description" "SMD Chip Resistor, 10 kohm, ± 1%, 62.5 mW, 0402 [1005 Metric], Thick Film, General Purpose"
			(at 0 0 0)
			(layer "B.Fab")
			(hide yes)
			(effects
				(font
					(size 1.27 1.27)
					(thickness 0.15)
				)
				(justify mirror)
			)
		)
		(property "MPN" "CR0402-FX-1002GLF"
			(at 0 0 0)
			(unlocked yes)
			(layer "B.Fab")
			(hide yes)
			(effects
				(font
					(size 1 1)
					(thickness 0.15)
				)
				(justify mirror)
			)
		)
		(property "Manufacturer" "Bourns"
			(at 0 0 0)
			(unlocked yes)
			(layer "B.Fab")
			(hide yes)
			(effects
				(font
					(size 1 1)
					(thickness 0.15)
				)
				(justify mirror)
			)
		)
		(property "License" "Apache-2.0"
			(at 0 0 0)
			(unlocked yes)
			(layer "B.Fab")
			(hide yes)
			(effects
				(font
					(size 1 1)
					(thickness 0.15)
				)
				(justify mirror)
			)
		)
		(property "Author" "Antmicro"
			(at 0 0 0)
			(unlocked yes)
			(layer "B.Fab")
			(hide yes)
			(effects
				(font
					(size 1 1)
					(thickness 0.15)
				)
				(justify mirror)
			)
		)
		(property "Val" "10k"
			(at 0 0 0)
			(unlocked yes)
			(layer "B.Fab")
			(hide yes)
			(effects
				(font
					(size 1 1)
					(thickness 0.15)
				)
				(justify mirror)
			)
		)
		(property "Tolerance" "1%"
			(at 0 0 0)
			(unlocked yes)
			(layer "B.Fab")
			(hide yes)
			(effects
				(font
					(size 1 1)
					(thickness 0.15)
				)
				(justify mirror)
			)
		)
		(sheetname "/Expansion connector/")
		(sheetfile "expansion_connector.kicad_sch")
		(attr smd)
		(fp_poly
			(pts
				(xy -0.925 0.47) (xy 0.925 0.47) (xy 0.925 -0.47) (xy -0.925 -0.47)
			)
			(stroke
				(width 0.05)
				(type default)
			)
			(fill no)
			(layer "B.CrtYd")
		)
		(fp_poly
			(pts
				(xy -0.5 0.25) (xy 0.5 0.25) (xy 0.5 -0.25) (xy -0.5 -0.25)
			)
			(stroke
				(width 0.15)
				(type solid)
			)
			(fill no)
			(layer "B.Fab")
		)
		(fp_text user "${REFERENCE}"
			(at -0.95 -3.168 0)
			(layer "B.Fab")
			(effects
				(font
					(size 0.7 0.7)
					(thickness 0.15)
				)
				(justify left bottom mirror)
			)
		)
		(fp_text user "License: Apache-2.0"
			(at -0.949999 -5.169 0)
			(layer "B.Fab")
			(effects
				(font
					(size 0.7 0.7)
					(thickness 0.15)
				)
				(justify left bottom mirror)
			)
		)
		(fp_text user "Author: Antmicro"
			(at -0.95 -4.169 0)
			(layer "B.Fab")
			(effects
				(font
					(size 0.7 0.7)
					(thickness 0.15)
				)
				(justify left bottom mirror)
			)
		)
		(pad "1" smd roundrect
			(at -0.48 0 180)
			(size 0.59 0.64)
			(layers "B.Cu" "B.Mask" "B.Paste")
			(roundrect_rratio 0.25)
			(net 341 "/Expansion connector/FMC_PRESENT")
			(pintype "passive")
		)
		(pad "2" smd roundrect
			(at 0.48 0 180)
			(size 0.59 0.64)
			(layers "B.Cu" "B.Mask" "B.Paste")
			(roundrect_rratio 0.25)
			(net 1 "GND")
			(pintype "passive")
		)
	)
	(footprint "antmicro-footprints:R_0402_1005Metric"
		(layer "B.Cu")
		(at 208.726 144)
		(descr "Resistor SMD 0402")
		(tags "resistor SMD 0402")
		(property "Reference" "R197"
			(at 0.95 -0.31 0)
			(layer "B.SilkS")
			(effects
				(font
					(size 0.7 0.7)
					(thickness 0.15)
				)
				(justify right top mirror)
			)
		)
		(property "Value" "R_1k_0402"
			(at -1.011843 -1.772047 0)
			(layer "B.Fab")
			(effects
				(font
					(size 0.7 0.7)
					(thickness 0.15)
				)
				(justify right top mirror)
			)
		)
		(property "Datasheet" "https://www.bourns.com/docs/product-datasheets/cr.pdf"
			(at 0 0 0)
			(layer "B.Fab")
			(hide yes)
			(effects
				(font
					(size 1.27 1.27)
					(thickness 0.15)
				)
				(justify mirror)
			)
		)
		(property "Description" "SMD Chip Resistor, 1 kohm, ± 1%, 63 mW, 0402 [1005 Metric], Thick Film, General Purpose"
			(at 0 0 0)
			(layer "B.Fab")
			(hide yes)
			(effects
				(font
					(size 1.27 1.27)
					(thickness 0.15)
				)
				(justify mirror)
			)
		)
		(property "MPN" "CR0402-FX-1001GLF"
			(at 0 0 180)
			(unlocked yes)
			(layer "B.Fab")
			(hide yes)
			(effects
				(font
					(size 1 1)
					(thickness 0.15)
				)
				(justify mirror)
			)
		)
		(property "Manufacturer" "Bourns"
			(at 0 0 180)
			(unlocked yes)
			(layer "B.Fab")
			(hide yes)
			(effects
				(font
					(size 1 1)
					(thickness 0.15)
				)
				(justify mirror)
			)
		)
		(property "License" "Apache-2.0"
			(at 0 0 180)
			(unlocked yes)
			(layer "B.Fab")
			(hide yes)
			(effects
				(font
					(size 1 1)
					(thickness 0.15)
				)
				(justify mirror)
			)
		)
		(property "Author" "Antmicro"
			(at 0 0 180)
			(unlocked yes)
			(layer "B.Fab")
			(hide yes)
			(effects
				(font
					(size 1 1)
					(thickness 0.15)
				)
				(justify mirror)
			)
		)
		(property "Val" "1k"
			(at 0 0 180)
			(unlocked yes)
			(layer "B.Fab")
			(hide yes)
			(effects
				(font
					(size 1 1)
					(thickness 0.15)
				)
				(justify mirror)
			)
		)
		(property "Tolerance" "1%"
			(at 0 0 180)
			(unlocked yes)
			(layer "B.Fab")
			(hide yes)
			(effects
				(font
					(size 1 1)
					(thickness 0.15)
				)
				(justify mirror)
			)
		)
		(sheetname "/SFP/")
		(sheetfile "sfp.kicad_sch")
		(attr smd)
		(fp_rect
			(start -0.925 0.47)
			(end 0.925 -0.47)
			(stroke
				(width 0.05)
				(type default)
			)
			(fill no)
			(layer "B.CrtYd")
		)
		(fp_rect
			(start -0.5 0.25)
			(end 0.5 -0.25)
			(stroke
				(width 0.15)
				(type solid)
			)
			(fill no)
			(layer "B.Fab")
		)
		(fp_text user "License: Apache-2.0"
			(at -0.95 -5.169 0)
			(layer "B.Fab")
			(effects
				(font
					(size 0.7 0.7)
					(thickness 0.15)
				)
				(justify right top mirror)
			)
		)
		(fp_text user "Author: Antmicro"
			(at -0.95 -4.169 0)
			(layer "B.Fab")
			(effects
				(font
					(size 0.7 0.7)
					(thickness 0.15)
				)
				(justify right top mirror)
			)
		)
		(fp_text user "${REFERENCE}"
			(at -0.95 -3.168 0)
			(layer "B.Fab")
			(effects
				(font
					(size 0.7 0.7)
					(thickness 0.15)
				)
				(justify right top mirror)
			)
		)
		(pad "1" smd roundrect
			(at -0.48 0)
			(size 0.59 0.64)
			(layers "B.Cu" "B.Mask" "B.Paste")
			(roundrect_rratio 0.25)
			(net 1296 "/SFP/SFP_MOD_ABS")
			(pintype "passive")
		)
		(pad "2" smd roundrect
			(at 0.48 0)
			(size 0.59 0.64)
			(layers "B.Cu" "B.Mask" "B.Paste")
			(roundrect_rratio 0.25)
			(net 11 "+1V8")
			(pintype "passive")
		)
	)
	(footprint "antmicro-footprints:USON-10_2.5x1mm_P0.5mm"
		(layer "B.Cu")
		(at 205.796 145.01)
		(descr "USON-10 2.5x1mm_ Pitch 0.5mm")
		(tags "USON-10 2.5x1mm Pitch 0.5mm")
		(property "Reference" "U73"
			(at -3.17 0.89 0)
			(layer "B.SilkS")
			(effects
				(font
					(size 0.7 0.7)
					(thickness 0.15)
				)
				(justify right top mirror)
			)
		)
		(property "Value" "TPD4E05U06QDQARQ1"
			(at 0.018 -2.499 0)
			(layer "B.Fab")
			(effects
				(font
					(size 0.7 0.7)
					(thickness 0.15)
				)
				(justify right top mirror)
			)
		)
		(property "Datasheet" "https://www.ti.com/lit/ds/symlink/tpd4e05u06-q1.pdf?HQS=dis-mous-null-mousermode-dsf-pf-null-wwe&ts=1663591265741&ref_url=https%253A%252F%252Fwww.mouser.com%252F"
			(at 0 0 0)
			(layer "B.Fab")
			(hide yes)
			(effects
				(font
					(size 1.27 1.27)
					(thickness 0.15)
				)
				(justify mirror)
			)
		)
		(property "Description" "TVS diode array, 12 kV, USON-10, 5.5 V, 0.5 pF"
			(at 0 0 0)
			(layer "B.Fab")
			(hide yes)
			(effects
				(font
					(size 1.27 1.27)
					(thickness 0.15)
				)
				(justify mirror)
			)
		)
		(property "Manufacturer" "Texas Instruments"
			(at 0 0 180)
			(unlocked yes)
			(layer "B.Fab")
			(hide yes)
			(effects
				(font
					(size 1 1)
					(thickness 0.15)
				)
				(justify mirror)
			)
		)
		(property "MPN" "TPD4E05U06QDQARQ1"
			(at 0 0 180)
			(unlocked yes)
			(layer "B.Fab")
			(hide yes)
			(effects
				(font
					(size 1 1)
					(thickness 0.15)
				)
				(justify mirror)
			)
		)
		(property "Author" "Antmicro"
			(at 0 0 180)
			(unlocked yes)
			(layer "B.Fab")
			(hide yes)
			(effects
				(font
					(size 1 1)
					(thickness 0.15)
				)
				(justify mirror)
			)
		)
		(property "License" "Apache-2.0"
			(at 0 0 180)
			(unlocked yes)
			(layer "B.Fab")
			(hide yes)
			(effects
				(font
					(size 1 1)
					(thickness 0.15)
				)
				(justify mirror)
			)
		)
		(sheetname "/SFP/")
		(sheetfile "sfp.kicad_sch")
		(attr smd)
		(fp_line
			(start 0.498 -1.398)
			(end -0.5 -1.398)
			(stroke
				(width 0.15)
				(type solid)
			)
			(layer "B.SilkS")
		)
		(fp_line
			(start 0.498 1.401)
			(end -0.5 1.401)
			(stroke
				(width 0.15)
				(type solid)
			)
			(layer "B.SilkS")
		)
		(fp_circle
			(center -0.68 1.27)
			(end -0.63 1.27)
			(stroke
				(width 0.15)
				(type solid)
			)
			(fill yes)
			(layer "B.SilkS")
		)
		(fp_poly
			(pts
				(xy -0.8 1.5) (xy 0.8 1.5) (xy 0.799999 -1.499) (xy -0.799999 -1.499)
			)
			(stroke
				(width 0.05)
				(type solid)
			)
			(fill no)
			(layer "B.CrtYd")
		)
		(fp_line
			(start -0.5 -1.249)
			(end 0.498 -1.249)
			(stroke
				(width 0.15)
				(type solid)
			)
			(layer "B.Fab")
		)
		(fp_line
			(start -0.5 1)
			(end -0.5 -1.249)
			(stroke
				(width 0.15)
				(type solid)
			)
			(layer "B.Fab")
		)
		(fp_line
			(start -0.25 1.25)
			(end -0.5 1)
			(stroke
				(width 0.15)
				(type solid)
			)
			(layer "B.Fab")
		)
		(fp_line
			(start 0.498 1.25)
			(end -0.25 1.25)
			(stroke
				(width 0.15)
				(type solid)
			)
			(layer "B.Fab")
		)
		(fp_line
			(start 0.498 1.25)
			(end 0.498 -1.249)
			(stroke
				(width 0.15)
				(type solid)
			)
			(layer "B.Fab")
		)
		(fp_text user "${REFERENCE}"
			(at -0.802 -4.498 0)
			(layer "B.Fab")
			(effects
				(font
					(size 0.7 0.7)
					(thickness 0.15)
				)
				(justify right top mirror)
			)
		)
		(fp_text user "License: Apache-2.0"
			(at -0.802 -6.9 0)
			(layer "B.Fab")
			(effects
				(font
					(size 0.7 0.7)
					(thickness 0.15)
				)
				(justify right top mirror)
			)
		)
		(fp_text user "Author: Antmicro"
			(at -0.802 -5.7 0)
			(layer "B.Fab")
			(effects
				(font
					(size 0.7 0.7)
					(thickness 0.15)
				)
				(justify right top mirror)
			)
		)
		(pad "1" smd roundrect
			(at -0.387 1 90)
			(size 0.25 0.55)
			(layers "B.Cu" "B.Mask" "B.Paste")
			(roundrect_rratio 0.25)
			(net 824 "/SFP/SDA_SFP")
			(pintype "passive")
		)
		(pad "2" smd roundrect
			(at -0.387 0.5 90)
			(size 0.25 0.55)
			(layers "B.Cu" "B.Mask" "B.Paste")
			(roundrect_rratio 0.25)
			(net 823 "/SFP/SCL_SFP")
			(pintype "passive")
		)
		(pad "3" smd roundrect
			(at -0.387 0 90)
			(size 0.4 0.55)
			(layers "B.Cu" "B.Mask" "B.Paste")
			(roundrect_rratio 0.25)
			(net 1 "GND")
			(pintype "power_in")
		)
		(pad "4" smd roundrect
			(at -0.387 -0.498 90)
			(size 0.25 0.55)
			(layers "B.Cu" "B.Mask" "B.Paste")
			(roundrect_rratio 0.25)
			(net 1296 "/SFP/SFP_MOD_ABS")
			(pintype "passive")
		)
		(pad "5" smd roundrect
			(at -0.387 -0.998 90)
			(size 0.25 0.55)
			(layers "B.Cu" "B.Mask" "B.Paste")
			(roundrect_rratio 0.25)
			(net 1 "GND")
			(pintype "passive")
		)
		(pad "6" smd roundrect
			(at 0.385001 -0.998 90)
			(size 0.25 0.55)
			(layers "B.Cu" "B.Mask" "B.Paste")
			(roundrect_rratio 0.25)
			(net 1 "GND")
			(pintype "passive")
		)
		(pad "7" smd roundrect
			(at 0.385 -0.498 90)
			(size 0.25 0.55)
			(layers "B.Cu" "B.Mask" "B.Paste")
			(roundrect_rratio 0.25)
			(net 1296 "/SFP/SFP_MOD_ABS")
			(pintype "passive")
		)
		(pad "8" smd roundrect
			(at 0.385 0 90)
			(size 0.4 0.55)
			(layers "B.Cu" "B.Mask" "B.Paste")
			(roundrect_rratio 0.25)
			(net 1 "GND")
			(pintype "passive")
		)
		(pad "9" smd roundrect
			(at 0.385001 0.5 90)
			(size 0.25 0.55)
			(layers "B.Cu" "B.Mask" "B.Paste")
			(roundrect_rratio 0.25)
			(net 823 "/SFP/SCL_SFP")
			(pintype "passive")
		)
		(pad "10" smd roundrect
			(at 0.385 1 90)
			(size 0.25 0.55)
			(layers "B.Cu" "B.Mask" "B.Paste")
			(roundrect_rratio 0.25)
			(net 824 "/SFP/SDA_SFP")
			(pintype "passive")
		)
	)
	(footprint "antmicro-footprints:C_0402_1005Metric"
		(layer "B.Cu")
		(at 117.89 70.6)
		(descr "Capacitor SMD 0402")
		(tags "capacitor SMD 0402")
		(property "Reference" "C15"
			(at -0.69 0.7 0)
			(layer "B.SilkS")
			(effects
				(font
					(size 0.7 0.7)
					(thickness 0.15)
				)
				(justify right top mirror)
			)
		)
		(property "Value" "C_10u_0402"
			(at -1.022927 -2.155213 0)
			(layer "B.Fab")
			(effects
				(font
					(size 0.7 0.7)
					(thickness 0.15)
				)
				(justify right top mirror)
			)
		)
		(property "Datasheet" "https://www.yageo.com/en/Chart/Download/pdf/CC0402MRX5R5BB106"
			(at 0 0 0)
			(layer "B.Fab")
			(hide yes)
			(effects
				(font
					(size 1.27 1.27)
					(thickness 0.15)
				)
				(justify mirror)
			)
		)
		(property "Description" "SMD Multilayer Ceramic Capacitor, 10 µF, 6.3 V, 0402 [1005 Metric], ± 20%, X5R, CC Series"
			(at 0 0 0)
			(layer "B.Fab")
			(hide yes)
			(effects
				(font
					(size 1.27 1.27)
					(thickness 0.15)
				)
				(justify mirror)
			)
		)
		(property "MPN" "CC0402MRX5R5BB106"
			(at 0 0 0)
			(unlocked yes)
			(layer "B.Fab")
			(hide yes)
			(effects
				(font
					(size 1 1)
					(thickness 0.15)
				)
				(justify mirror)
			)
		)
		(property "Manufacturer" "YAGEO"
			(at 0 0 0)
			(unlocked yes)
			(layer "B.Fab")
			(hide yes)
			(effects
				(font
					(size 1 1)
					(thickness 0.15)
				)
				(justify mirror)
			)
		)
		(property "License" "Apache-2.0"
			(at 0 0 0)
			(unlocked yes)
			(layer "B.Fab")
			(hide yes)
			(effects
				(font
					(size 1 1)
					(thickness 0.15)
				)
				(justify mirror)
			)
		)
		(property "Author" "Antmicro"
			(at 0 0 0)
			(unlocked yes)
			(layer "B.Fab")
			(hide yes)
			(effects
				(font
					(size 1 1)
					(thickness 0.15)
				)
				(justify mirror)
			)
		)
		(property "Val" "10u"
			(at 0 0 0)
			(unlocked yes)
			(layer "B.Fab")
			(hide yes)
			(effects
				(font
					(size 1 1)
					(thickness 0.15)
				)
				(justify mirror)
			)
		)
		(property "Voltage" ""
			(at 0 0 0)
			(unlocked yes)
			(layer "B.Fab")
			(hide yes)
			(effects
				(font
					(size 1 1)
					(thickness 0.15)
				)
				(justify mirror)
			)
		)
		(property "Dielectric" "template_dielectric"
			(at 0 0 0)
			(unlocked yes)
			(layer "B.Fab")
			(hide yes)
			(effects
				(font
					(size 1 1)
					(thickness 0.15)
				)
				(justify mirror)
			)
		)
		(sheetname "/SoM_Power/")
		(sheetfile "som_power.kicad_sch")
		(attr smd)
		(fp_rect
			(start -0.925 0.47)
			(end 0.925 -0.47)
			(stroke
				(width 0.05)
				(type default)
			)
			(fill no)
			(layer "B.CrtYd")
		)
		(fp_line
			(start -0.494 -0.248)
			(end -0.494 0.25)
			(stroke
				(width 0.15)
				(type solid)
			)
			(layer "B.Fab")
		)
		(fp_line
			(start -0.494 0.25)
			(end 0.504 0.25)
			(stroke
				(width 0.15)
				(type solid)
			)
			(layer "B.Fab")
		)
		(fp_line
			(start 0.504 -0.248)
			(end -0.494 -0.248)
			(stroke
				(width 0.15)
				(type solid)
			)
			(layer "B.Fab")
		)
		(fp_line
			(start 0.504 0.25)
			(end 0.504 -0.248)
			(stroke
				(width 0.15)
				(type solid)
			)
			(layer "B.Fab")
		)
		(fp_text user "License: Apache-2.0"
			(at -0.939 -5.799 0)
			(layer "B.Fab")
			(effects
				(font
					(size 0.7 0.7)
					(thickness 0.15)
				)
				(justify right top mirror)
			)
		)
		(fp_text user "${REFERENCE}"
			(at -0.939 -4.599 0)
			(layer "B.Fab")
			(effects
				(font
					(size 0.7 0.7)
					(thickness 0.15)
				)
				(justify right top mirror)
			)
		)
		(fp_text user "Author: Antmicro"
			(at -0.939 -3.399 0)
			(layer "B.Fab")
			(effects
				(font
					(size 0.7 0.7)
					(thickness 0.15)
				)
				(justify right top mirror)
			)
		)
		(pad "1" smd roundrect
			(at -0.48 0)
			(size 0.59 0.64)
			(layers "B.Cu" "B.Mask" "B.Paste")
			(roundrect_rratio 0.25)
			(net 1 "GND")
			(pintype "passive")
		)
		(pad "2" smd roundrect
			(at 0.48 0)
			(size 0.59 0.64)
			(layers "B.Cu" "B.Mask" "B.Paste")
			(roundrect_rratio 0.25)
			(net 213 "+5V_SOM")
			(pintype "passive")
		)
	)
	(footprint "antmicro-footprints:R_0402_1005Metric"
		(layer "B.Cu")
		(at 208.726 143)
		(descr "Resistor SMD 0402")
		(tags "resistor SMD 0402")
		(property "Reference" "R188"
			(at 1 -0.3 0)
			(layer "B.SilkS")
			(effects
				(font
					(size 0.7 0.7)
					(thickness 0.15)
				)
				(justify right top mirror)
			)
		)
		(property "Value" "R_1k_0402"
			(at -1.011843 -1.772047 0)
			(layer "B.Fab")
			(effects
				(font
					(size 0.7 0.7)
					(thickness 0.15)
				)
				(justify right top mirror)
			)
		)
		(property "Datasheet" "https://www.bourns.com/docs/product-datasheets/cr.pdf"
			(at 0 0 0)
			(layer "B.Fab")
			(hide yes)
			(effects
				(font
					(size 1.27 1.27)
					(thickness 0.15)
				)
				(justify mirror)
			)
		)
		(property "Description" "SMD Chip Resistor, 1 kohm, ± 1%, 63 mW, 0402 [1005 Metric], Thick Film, General Purpose"
			(at 0 0 0)
			(layer "B.Fab")
			(hide yes)
			(effects
				(font
					(size 1.27 1.27)
					(thickness 0.15)
				)
				(justify mirror)
			)
		)
		(property "MPN" "CR0402-FX-1001GLF"
			(at 0 0 180)
			(unlocked yes)
			(layer "B.Fab")
			(hide yes)
			(effects
				(font
					(size 1 1)
					(thickness 0.15)
				)
				(justify mirror)
			)
		)
		(property "Manufacturer" "Bourns"
			(at 0 0 180)
			(unlocked yes)
			(layer "B.Fab")
			(hide yes)
			(effects
				(font
					(size 1 1)
					(thickness 0.15)
				)
				(justify mirror)
			)
		)
		(property "License" "Apache-2.0"
			(at 0 0 180)
			(unlocked yes)
			(layer "B.Fab")
			(hide yes)
			(effects
				(font
					(size 1 1)
					(thickness 0.15)
				)
				(justify mirror)
			)
		)
		(property "Author" "Antmicro"
			(at 0 0 180)
			(unlocked yes)
			(layer "B.Fab")
			(hide yes)
			(effects
				(font
					(size 1 1)
					(thickness 0.15)
				)
				(justify mirror)
			)
		)
		(property "Val" "1k"
			(at 0 0 180)
			(unlocked yes)
			(layer "B.Fab")
			(hide yes)
			(effects
				(font
					(size 1 1)
					(thickness 0.15)
				)
				(justify mirror)
			)
		)
		(property "Tolerance" "1%"
			(at 0 0 180)
			(unlocked yes)
			(layer "B.Fab")
			(hide yes)
			(effects
				(font
					(size 1 1)
					(thickness 0.15)
				)
				(justify mirror)
			)
		)
		(sheetname "/SFP/")
		(sheetfile "sfp.kicad_sch")
		(attr smd)
		(fp_rect
			(start -0.925 0.47)
			(end 0.925 -0.47)
			(stroke
				(width 0.05)
				(type default)
			)
			(fill no)
			(layer "B.CrtYd")
		)
		(fp_rect
			(start -0.5 0.25)
			(end 0.5 -0.25)
			(stroke
				(width 0.15)
				(type solid)
			)
			(fill no)
			(layer "B.Fab")
		)
		(fp_text user "${REFERENCE}"
			(at -0.95 -3.168 0)
			(layer "B.Fab")
			(effects
				(font
					(size 0.7 0.7)
					(thickness 0.15)
				)
				(justify right top mirror)
			)
		)
		(fp_text user "Author: Antmicro"
			(at -0.95 -4.169 0)
			(layer "B.Fab")
			(effects
				(font
					(size 0.7 0.7)
					(thickness 0.15)
				)
				(justify right top mirror)
			)
		)
		(fp_text user "License: Apache-2.0"
			(at -0.95 -5.169 0)
			(layer "B.Fab")
			(effects
				(font
					(size 0.7 0.7)
					(thickness 0.15)
				)
				(justify right top mirror)
			)
		)
		(pad "1" smd roundrect
			(at -0.48 0)
			(size 0.59 0.64)
			(layers "B.Cu" "B.Mask" "B.Paste")
			(roundrect_rratio 0.25)
			(net 1368 "Net-(J12-RS0)")
			(pintype "passive")
		)
		(pad "2" smd roundrect
			(at 0.48 0)
			(size 0.59 0.64)
			(layers "B.Cu" "B.Mask" "B.Paste")
			(roundrect_rratio 0.25)
			(net 2 "+3V3")
			(pintype "passive")
		)
	)
	(footprint "antmicro-footprints:Conn_FFC_WE_68715014x22"
		(locked yes)
		(layer "B.Cu")
		(at 62.44 103.71 90)
		(property "Reference" "J11"
			(at -15.49 2.56 0)
			(layer "B.SilkS")
			(effects
				(font
					(size 0.7 0.7)
					(thickness 0.15)
				)
				(justify right top mirror)
			)
		)
		(property "Value" "Conn_FFC_WE_68715014522"
			(at 0 -4.5 90)
			(layer "B.Fab")
			(effects
				(font
					(size 0.7 0.7)
					(thickness 0.15)
				)
				(justify right top mirror)
			)
		)
		(property "Datasheet" "https://www.we-online.com/components/products/datasheet/68715014522.pdf"
			(at 0 0 90)
			(layer "B.Fab")
			(hide yes)
			(effects
				(font
					(size 1.27 1.27)
					(thickness 0.15)
				)
				(justify mirror)
			)
		)
		(property "Description" "FFC connector"
			(at 0 0 90)
			(layer "B.Fab")
			(hide yes)
			(effects
				(font
					(size 1.27 1.27)
					(thickness 0.15)
				)
				(justify mirror)
			)
		)
		(property "MPN" "68715014522"
			(at 0 0 270)
			(unlocked yes)
			(layer "B.Fab")
			(hide yes)
			(effects
				(font
					(size 1 1)
					(thickness 0.15)
				)
				(justify mirror)
			)
		)
		(property "Manufacturer" "Würth Elektronik"
			(at 0 0 270)
			(unlocked yes)
			(layer "B.Fab")
			(hide yes)
			(effects
				(font
					(size 1 1)
					(thickness 0.15)
				)
				(justify mirror)
			)
		)
		(property "Author" "Antmicro"
			(at 0 0 270)
			(unlocked yes)
			(layer "B.Fab")
			(hide yes)
			(effects
				(font
					(size 1 1)
					(thickness 0.15)
				)
				(justify mirror)
			)
		)
		(property "License" "Apache-2.0"
			(at 0 0 270)
			(unlocked yes)
			(layer "B.Fab")
			(hide yes)
			(effects
				(font
					(size 1 1)
					(thickness 0.15)
				)
				(justify mirror)
			)
		)
		(sheetname "/CSI/")
		(sheetfile "csi.kicad_sch")
		(attr smd)
		(fp_line
			(start 15.85 -2.7)
			(end -15.85 -2.7)
			(stroke
				(width 0.15)
				(type solid)
			)
			(layer "B.SilkS")
		)
		(fp_line
			(start 15.85 -2.7)
			(end 15.85 2.15)
			(stroke
				(width 0.15)
				(type solid)
			)
			(layer "B.SilkS")
		)
		(fp_line
			(start -15.85 -2.7)
			(end -15.85 2.15)
			(stroke
				(width 0.15)
				(type solid)
			)
			(layer "B.SilkS")
		)
		(fp_line
			(start 15.85 2.15)
			(end 12.499 2.15)
			(stroke
				(width 0.15)
				(type solid)
			)
			(layer "B.SilkS")
		)
		(fp_line
			(start 12.499 2.15)
			(end 12.499 2.976)
			(stroke
				(width 0.15)
				(type solid)
			)
			(layer "B.SilkS")
		)
		(fp_line
			(start -12.5 2.15)
			(end -12.5 2.976)
			(stroke
				(width 0.15)
				(type solid)
			)
			(layer "B.SilkS")
		)
		(fp_line
			(start -15.85 2.15)
			(end -12.5 2.15)
			(stroke
				(width 0.15)
				(type solid)
			)
			(layer "B.SilkS")
		)
		(fp_line
			(start -12.5 2.976)
			(end 12.499 2.976)
			(stroke
				(width 0.15)
				(type solid)
			)
			(layer "B.SilkS")
		)
		(fp_circle
			(center -12.9 2.9)
			(end -12.85 2.85)
			(stroke
				(width 0.15)
				(type solid)
			)
			(fill yes)
			(layer "B.SilkS")
		)
		(fp_rect
			(start -16.2 3.25)
			(end 16.2 -3.55)
			(stroke
				(width 0.05)
				(type solid)
			)
			(fill no)
			(layer "B.CrtYd")
		)
		(fp_text user "Author: Antmicro"
			(at -16.2 -6.9 90)
			(layer "B.Fab")
			(effects
				(font
					(size 0.7 0.7)
					(thickness 0.15)
				)
				(justify right top mirror)
			)
		)
		(fp_text user "License: Apache-2.0"
			(at -16.2 -7.9 90)
			(layer "B.Fab")
			(effects
				(font
					(size 0.7 0.7)
					(thickness 0.15)
				)
				(justify right top mirror)
			)
		)
		(fp_text user "${REFERENCE}"
			(at -16.2 -5.9 90)
			(layer "B.Fab")
			(effects
				(font
					(size 0.7 0.7)
					(thickness 0.15)
				)
				(justify right top mirror)
			)
		)
		(pad "1" smd roundrect
			(at -12.25 2.15 90)
			(size 0.3 1.2)
			(layers "B.Cu" "B.Mask" "B.Paste")
			(roundrect_rratio 0.25)
			(net 154 "/CSI/CAM0.CSI3_D1-")
			(pintype "passive")
		)
		(pad "2" smd roundrect
			(at -11.75 2.15 90)
			(size 0.3 1.2)
			(layers "B.Cu" "B.Mask" "B.Paste")
			(roundrect_rratio 0.25)
			(net 161 "/CSI/CAM0.CSI3_D1+")
			(pintype "passive")
		)
		(pad "3" smd roundrect
			(at -11.25 2.15 90)
			(size 0.3 1.2)
			(layers "B.Cu" "B.Mask" "B.Paste")
			(roundrect_rratio 0.25)
			(net 63 "/CSI/CAM0.CSI3_D0-")
			(pintype "passive")
		)
		(pad "4" smd roundrect
			(at -10.75 2.15 90)
			(size 0.3 1.2)
			(layers "B.Cu" "B.Mask" "B.Paste")
			(roundrect_rratio 0.25)
			(net 52 "/CSI/CAM0.CSI3_D0+")
			(pintype "passive")
		)
		(pad "5" smd roundrect
			(at -10.25 2.15 90)
			(size 0.3 1.2)
			(layers "B.Cu" "B.Mask" "B.Paste")
			(roundrect_rratio 0.25)
			(net 170 "/CSI/CAM0.CSI2_D1-")
			(pintype "passive")
		)
		(pad "6" smd roundrect
			(at -9.75 2.15 90)
			(size 0.3 1.2)
			(layers "B.Cu" "B.Mask" "B.Paste")
			(roundrect_rratio 0.25)
			(net 89 "/CSI/CAM0.CSI2_D1+")
			(pintype "passive")
		)
		(pad "7" smd roundrect
			(at -9.25 2.15 90)
			(size 0.3 1.2)
			(layers "B.Cu" "B.Mask" "B.Paste")
			(roundrect_rratio 0.25)
			(net 64 "/CSI/CAM0.CSI2_D0-")
			(pintype "passive")
		)
		(pad "8" smd roundrect
			(at -8.75 2.15 90)
			(size 0.3 1.2)
			(layers "B.Cu" "B.Mask" "B.Paste")
			(roundrect_rratio 0.25)
			(net 88 "/CSI/CAM0.CSI2_D0+")
			(pintype "passive")
		)
		(pad "9" smd roundrect
			(at -8.25 2.15 90)
			(size 0.3 1.2)
			(layers "B.Cu" "B.Mask" "B.Paste")
			(roundrect_rratio 0.25)
			(net 1 "GND")
			(pintype "passive")
		)
		(pad "10" smd roundrect
			(at -7.75 2.15 90)
			(size 0.3 1.2)
			(layers "B.Cu" "B.Mask" "B.Paste")
			(roundrect_rratio 0.25)
			(net 68 "/CSI/CAM0.CSI2_CLK-")
			(pintype "passive")
		)
		(pad "11" smd roundrect
			(at -7.25 2.15 90)
			(size 0.3 1.2)
			(layers "B.Cu" "B.Mask" "B.Paste")
			(roundrect_rratio 0.25)
			(net 249 "/CSI/CAM0.CSI2_CLK+")
			(pintype "passive")
		)
		(pad "12" smd roundrect
			(at -6.75 2.15 90)
			(size 0.3 1.2)
			(layers "B.Cu" "B.Mask" "B.Paste")
			(roundrect_rratio 0.25)
			(net 1 "GND")
			(pintype "passive")
		)
		(pad "13" smd roundrect
			(at -6.25 2.15 90)
			(size 0.3 1.2)
			(layers "B.Cu" "B.Mask" "B.Paste")
			(roundrect_rratio 0.25)
			(net 203 "unconnected-(J11-Pad13)")
			(pintype "passive+no_connect")
		)
		(pad "14" smd roundrect
			(at -5.75 2.15 90)
			(size 0.3 1.2)
			(layers "B.Cu" "B.Mask" "B.Paste")
			(roundrect_rratio 0.25)
			(net 199 "unconnected-(J11-Pad14)")
			(pintype "passive+no_connect")
		)
		(pad "15" smd roundrect
			(at -5.25 2.15 90)
			(size 0.3 1.2)
			(layers "B.Cu" "B.Mask" "B.Paste")
			(roundrect_rratio 0.25)
			(net 1 "GND")
			(pintype "passive")
		)
		(pad "16" smd roundrect
			(at -4.75 2.15 90)
			(size 0.3 1.2)
			(layers "B.Cu" "B.Mask" "B.Paste")
			(roundrect_rratio 0.25)
			(net 196 "unconnected-(J11-Pad16)")
			(pintype "passive+no_connect")
		)
		(pad "17" smd roundrect
			(at -4.25 2.15 90)
			(size 0.3 1.2)
			(layers "B.Cu" "B.Mask" "B.Paste")
			(roundrect_rratio 0.25)
			(net 208 "unconnected-(J11-Pad17)")
			(pintype "passive+no_connect")
		)
		(pad "18" smd roundrect
			(at -3.75 2.15 90)
			(size 0.3 1.2)
			(layers "B.Cu" "B.Mask" "B.Paste")
			(roundrect_rratio 0.25)
			(net 1 "GND")
			(pintype "passive")
		)
		(pad "19" smd roundrect
			(at -3.25 2.15 90)
			(size 0.3 1.2)
			(layers "B.Cu" "B.Mask" "B.Paste")
			(roundrect_rratio 0.25)
			(net 143 "/CSI/CAM1.CSI1_D1-")
			(pintype "passive")
		)
		(pad "20" smd roundrect
			(at -2.75 2.15 90)
			(size 0.3 1.2)
			(layers "B.Cu" "B.Mask" "B.Paste")
			(roundrect_rratio 0.25)
			(net 93 "/CSI/CAM1.CSI1_D1+")
			(pintype "passive")
		)
		(pad "21" smd roundrect
			(at -2.25 2.15 90)
			(size 0.3 1.2)
			(layers "B.Cu" "B.Mask" "B.Paste")
			(roundrect_rratio 0.25)
			(net 134 "/CSI/CAM1.CSI1_D0-")
			(pintype "passive")
		)
		(pad "22" smd roundrect
			(at -1.75 2.15 90)
			(size 0.3 1.2)
			(layers "B.Cu" "B.Mask" "B.Paste")
			(roundrect_rratio 0.25)
			(net 77 "/CSI/CAM1.CSI1_D0+")
			(pintype "passive")
		)
		(pad "23" smd roundrect
			(at -1.25 2.15 90)
			(size 0.3 1.2)
			(layers "B.Cu" "B.Mask" "B.Paste")
			(roundrect_rratio 0.25)
			(net 153 "/CSI/CAM1.CSI0_D1-")
			(pintype "passive")
		)
		(pad "24" smd roundrect
			(at -0.75 2.15 90)
			(size 0.3 1.2)
			(layers "B.Cu" "B.Mask" "B.Paste")
			(roundrect_rratio 0.25)
			(net 54 "/CSI/CAM1.CSI0_D1+")
			(pintype "passive")
		)
		(pad "25" smd roundrect
			(at -0.25 2.15 90)
			(size 0.3 1.2)
			(layers "B.Cu" "B.Mask" "B.Paste")
			(roundrect_rratio 0.25)
			(net 113 "/CSI/CAM1.CSI0_D0-")
			(pintype "passive")
		)
		(pad "26" smd roundrect
			(at 0.248 2.15 90)
			(size 0.3 1.2)
			(layers "B.Cu" "B.Mask" "B.Paste")
			(roundrect_rratio 0.25)
			(net 157 "/CSI/CAM1.CSI0_D0+")
			(pintype "passive")
		)
		(pad "27" smd roundrect
			(at 0.748 2.15 90)
			(size 0.3 1.2)
			(layers "B.Cu" "B.Mask" "B.Paste")
			(roundrect_rratio 0.25)
			(net 1 "GND")
			(pintype "passive")
		)
		(pad "28" smd roundrect
			(at 1.249 2.15 90)
			(size 0.3 1.2)
			(layers "B.Cu" "B.Mask" "B.Paste")
			(roundrect_rratio 0.25)
			(net 66 "/CSI/CAM1.CSI0_CLK-")
			(pintype "passive")
		)
		(pad "29" smd roundrect
			(at 1.749 2.15 90)
			(size 0.3 1.2)
			(layers "B.Cu" "B.Mask" "B.Paste")
			(roundrect_rratio 0.25)
			(net 136 "/CSI/CAM1.CSI0_CLK+")
			(pintype "passive")
		)
		(pad "30" smd roundrect
			(at 2.249 2.15 90)
			(size 0.3 1.2)
			(layers "B.Cu" "B.Mask" "B.Paste")
			(roundrect_rratio 0.25)
			(net 1 "GND")
			(pintype "passive")
		)
		(pad "31" smd roundrect
			(at 2.749 2.15 90)
			(size 0.3 1.2)
			(layers "B.Cu" "B.Mask" "B.Paste")
			(roundrect_rratio 0.25)
			(net 202 "unconnected-(J11-Pad31)")
			(pintype "passive+no_connect")
		)
		(pad "32" smd roundrect
			(at 3.249 2.15 90)
			(size 0.3 1.2)
			(layers "B.Cu" "B.Mask" "B.Paste")
			(roundrect_rratio 0.25)
			(net 186 "/CSI/VSYNC_CAM0_3V3")
			(pintype "passive")
		)
		(pad "33" smd roundrect
			(at 3.749 2.15 90)
			(size 0.3 1.2)
			(layers "B.Cu" "B.Mask" "B.Paste")
			(roundrect_rratio 0.25)
			(net 198 "unconnected-(J11-Pad33)")
			(pintype "passive+no_connect")
		)
		(pad "34" smd roundrect
			(at 4.248 2.15 90)
			(size 0.3 1.2)
			(layers "B.Cu" "B.Mask" "B.Paste")
			(roundrect_rratio 0.25)
			(net 194 "/CSI/VSYNC_CAM1_3V3")
			(pintype "passive")
		)
		(pad "35" smd roundrect
			(at 4.748 2.15 90)
			(size 0.3 1.2)
			(layers "B.Cu" "B.Mask" "B.Paste")
			(roundrect_rratio 0.25)
			(net 200 "unconnected-(J11-Pad35)")
			(pintype "passive+no_connect")
		)
		(pad "36" smd roundrect
			(at 5.248 2.15 90)
			(size 0.3 1.2)
			(layers "B.Cu" "B.Mask" "B.Paste")
			(roundrect_rratio 0.25)
			(net 209 "unconnected-(J11-Pad36)")
			(pintype "passive+no_connect")
		)
		(pad "37" smd roundrect
			(at 5.749 2.15 90)
			(size 0.3 1.2)
			(layers "B.Cu" "B.Mask" "B.Paste")
			(roundrect_rratio 0.25)
			(net 204 "unconnected-(J11-Pad37)")
			(pintype "passive+no_connect")
		)
		(pad "38" smd roundrect
			(at 6.249 2.15 90)
			(size 0.3 1.2)
			(layers "B.Cu" "B.Mask" "B.Paste")
			(roundrect_rratio 0.25)
			(net 197 "unconnected-(J11-Pad38)")
			(pintype "passive+no_connect")
		)
		(pad "39" smd roundrect
			(at 6.749 2.15 90)
			(size 0.3 1.2)
			(layers "B.Cu" "B.Mask" "B.Paste")
			(roundrect_rratio 0.25)
			(net 1374 "Net-(J11-Pad39)")
			(pintype "passive")
		)
		(pad "40" smd roundrect
			(at 7.249 2.15 90)
			(size 0.3 1.2)
			(layers "B.Cu" "B.Mask" "B.Paste")
			(roundrect_rratio 0.25)
			(net 1377 "Net-(J11-Pad40)")
			(pintype "passive")
		)
		(pad "41" smd roundrect
			(at 7.749 2.15 90)
			(size 0.3 1.2)
			(layers "B.Cu" "B.Mask" "B.Paste")
			(roundrect_rratio 0.25)
			(net 1376 "Net-(J11-Pad41)")
			(pintype "passive")
		)
		(pad "42" smd roundrect
			(at 8.249 2.15 90)
			(size 0.3 1.2)
			(layers "B.Cu" "B.Mask" "B.Paste")
			(roundrect_rratio 0.25)
			(net 1375 "Net-(J11-Pad42)")
			(pintype "passive")
		)
		(pad "43" smd roundrect
			(at 8.749 2.15 90)
			(size 0.3 1.2)
			(layers "B.Cu" "B.Mask" "B.Paste")
			(roundrect_rratio 0.25)
			(net 207 "unconnected-(J11-Pad43)")
			(pintype "passive+no_connect")
		)
		(pad "44" smd roundrect
			(at 9.249 2.15 90)
			(size 0.3 1.2)
			(layers "B.Cu" "B.Mask" "B.Paste")
			(roundrect_rratio 0.25)
			(net 205 "unconnected-(J11-Pad44)")
			(pintype "passive+no_connect")
		)
		(pad "45" smd roundrect
			(at 9.749 2.15 90)
			(size 0.3 1.2)
			(layers "B.Cu" "B.Mask" "B.Paste")
			(roundrect_rratio 0.25)
			(net 211 "unconnected-(J11-Pad45)")
			(pintype "passive+no_connect")
		)
		(pad "46" smd roundrect
			(at 10.249 2.15 90)
			(size 0.3 1.2)
			(layers "B.Cu" "B.Mask" "B.Paste")
			(roundrect_rratio 0.25)
			(net 206 "unconnected-(J11-Pad46)")
			(pintype "passive+no_connect")
		)
		(pad "47" smd roundrect
			(at 10.749 2.15 90)
			(size 0.3 1.2)
			(layers "B.Cu" "B.Mask" "B.Paste")
			(roundrect_rratio 0.25)
			(net 6 "/CSI/CSIA_3V3")
			(pintype "passive")
		)
		(pad "48" smd roundrect
			(at 11.249 2.15 90)
			(size 0.3 1.2)
			(layers "B.Cu" "B.Mask" "B.Paste")
			(roundrect_rratio 0.25)
			(net 6 "/CSI/CSIA_3V3")
			(pintype "passive")
		)
		(pad "49" smd roundrect
			(at 11.749 2.15 90)
			(size 0.3 1.2)
			(layers "B.Cu" "B.Mask" "B.Paste")
			(roundrect_rratio 0.25)
			(net 7 "/CSI/CSIA_5V")
			(pintype "passive")
		)
		(pad "50" smd roundrect
			(at 12.249 2.15 90)
			(size 0.3 1.2)
			(layers "B.Cu" "B.Mask" "B.Paste")
			(roundrect_rratio 0.25)
			(net 7 "/CSI/CSIA_5V")
			(pintype "passive")
		)
		(pad "MP1" smd roundrect
			(at -14.198 0.3 90)
			(size 2.7 3)
			(layers "B.Cu" "B.Mask" "B.Paste")
			(roundrect_rratio 0.05)
			(net 1 "GND")
			(pinfunction "MP")
			(pintype "passive")
		)
		(pad "MP2" smd roundrect
			(at 14.198 0.3 90)
			(size 2.7 3)
			(layers "B.Cu" "B.Mask" "B.Paste")
			(roundrect_rratio 0.05)
			(net 1 "GND")
			(pinfunction "MP")
			(pintype "passive")
		)
	)
	(footprint "antmicro-footprints:R_0402_1005Metric"
		(layer "B.Cu")
		(at 202.3 130.5 90)
		(descr "Resistor SMD 0402")
		(tags "resistor SMD 0402")
		(property "Reference" "R21"
			(at -3.1 -0.3 90)
			(layer "B.SilkS")
			(effects
				(font
					(size 0.7 0.7)
					(thickness 0.15)
				)
				(justify right top mirror)
			)
		)
		(property "Value" "R_0R_0402"
			(at -1.011843 -1.772047 90)
			(layer "B.Fab")
			(effects
				(font
					(size 0.7 0.7)
					(thickness 0.15)
				)
				(justify right top mirror)
			)
		)
		(property "Datasheet" "https://industrial.panasonic.com/cdbs/www-data/pdf/RDA0000/AOA0000C301.pdf"
			(at 0 0 90)
			(layer "B.Fab")
			(hide yes)
			(effects
				(font
					(size 1.27 1.27)
					(thickness 0.15)
				)
				(justify mirror)
			)
		)
		(property "Description" "SMD Chip Resistor, Jumper, 0 ohm, 100 mW, 0402 [1005 Metric], Thick Film, General Purpose"
			(at 0 0 90)
			(layer "B.Fab")
			(hide yes)
			(effects
				(font
					(size 1.27 1.27)
					(thickness 0.15)
				)
				(justify mirror)
			)
		)
		(property "Manufacturer" "Panasonic"
			(at 0 0 270)
			(unlocked yes)
			(layer "B.Fab")
			(hide yes)
			(effects
				(font
					(size 1 1)
					(thickness 0.15)
				)
				(justify mirror)
			)
		)
		(property "MPN" "ERJ2GE0R00X"
			(at 0 0 270)
			(unlocked yes)
			(layer "B.Fab")
			(hide yes)
			(effects
				(font
					(size 1 1)
					(thickness 0.15)
				)
				(justify mirror)
			)
		)
		(property "Val" "0R"
			(at 0 0 270)
			(unlocked yes)
			(layer "B.Fab")
			(hide yes)
			(effects
				(font
					(size 1 1)
					(thickness 0.15)
				)
				(justify mirror)
			)
		)
		(property "License" "Apache-2.0"
			(at 0 0 270)
			(unlocked yes)
			(layer "B.Fab")
			(hide yes)
			(effects
				(font
					(size 1 1)
					(thickness 0.15)
				)
				(justify mirror)
			)
		)
		(property "Author" "Antmicro"
			(at 0 0 270)
			(unlocked yes)
			(layer "B.Fab")
			(hide yes)
			(effects
				(font
					(size 1 1)
					(thickness 0.15)
				)
				(justify mirror)
			)
		)
		(property "Tolerance" "~"
			(at 0 0 270)
			(unlocked yes)
			(layer "B.Fab")
			(hide yes)
			(effects
				(font
					(size 1 1)
					(thickness 0.15)
				)
				(justify mirror)
			)
		)
		(property "Current" "1A"
			(at 0 0 270)
			(unlocked yes)
			(layer "B.Fab")
			(hide yes)
			(effects
				(font
					(size 1 1)
					(thickness 0.15)
				)
				(justify mirror)
			)
		)
		(sheetname "/USB Hub/")
		(sheetfile "usb_hub.kicad_sch")
		(attr smd)
		(fp_rect
			(start -0.925 0.47)
			(end 0.925 -0.47)
			(stroke
				(width 0.05)
				(type default)
			)
			(fill no)
			(layer "B.CrtYd")
		)
		(fp_rect
			(start -0.5 0.25)
			(end 0.5 -0.25)
			(stroke
				(width 0.15)
				(type solid)
			)
			(fill no)
			(layer "B.Fab")
		)
		(fp_text user "License: Apache-2.0"
			(at -0.95 -5.169 90)
			(layer "B.Fab")
			(effects
				(font
					(size 0.7 0.7)
					(thickness 0.15)
				)
				(justify right top mirror)
			)
		)
		(fp_text user "${REFERENCE}"
			(at -0.95 -3.168 90)
			(layer "B.Fab")
			(effects
				(font
					(size 0.7 0.7)
					(thickness 0.15)
				)
				(justify right top mirror)
			)
		)
		(fp_text user "Author: Antmicro"
			(at -0.95 -4.169 90)
			(layer "B.Fab")
			(effects
				(font
					(size 0.7 0.7)
					(thickness 0.15)
				)
				(justify right top mirror)
			)
		)
		(pad "1" smd roundrect
			(at -0.48 0 90)
			(size 0.59 0.64)
			(layers "B.Cu" "B.Mask" "B.Paste")
			(roundrect_rratio 0.25)
			(net 1111 "Net-(U21-USB2DN_DP3)")
			(pintype "passive")
		)
		(pad "2" smd roundrect
			(at 0.48 0 90)
			(size 0.59 0.64)
			(layers "B.Cu" "B.Mask" "B.Paste")
			(roundrect_rratio 0.25)
			(net 2 "+3V3")
			(pintype "passive")
		)
	)
	(footprint "antmicro-footprints:TP_SMD_0.75mm"
		(layer "B.Cu")
		(at 133 69.5 90)
		(property "Reference" "TP32"
			(at 0.53 -0.36 90)
			(layer "B.SilkS")
			(effects
				(font
					(size 0.7 0.7)
					(thickness 0.15)
				)
				(justify right top mirror)
			)
		)
		(property "Value" "TP_0.75mm_SMD"
			(at 0 -1.2 90)
			(layer "B.Fab")
			(effects
				(font
					(size 0.7 0.7)
					(thickness 0.15)
				)
				(justify right top mirror)
			)
		)
		(property "Description" "SMT test point"
			(at 0 0 90)
			(layer "B.Fab")
			(hide yes)
			(effects
				(font
					(size 1.27 1.27)
					(thickness 0.15)
				)
				(justify mirror)
			)
		)
		(property "MPN" ""
			(at 0 0 270)
			(unlocked yes)
			(layer "B.Fab")
			(hide yes)
			(effects
				(font
					(size 1 1)
					(thickness 0.15)
				)
				(justify mirror)
			)
		)
		(property "Manufacturer" ""
			(at 0 0 270)
			(unlocked yes)
			(layer "B.Fab")
			(hide yes)
			(effects
				(font
					(size 1 1)
					(thickness 0.15)
				)
				(justify mirror)
			)
		)
		(property "Author" "Antmicro"
			(at 0 0 270)
			(unlocked yes)
			(layer "B.Fab")
			(hide yes)
			(effects
				(font
					(size 1 1)
					(thickness 0.15)
				)
				(justify mirror)
			)
		)
		(property "License" "Apache-2.0"
			(at 0 0 270)
			(unlocked yes)
			(layer "B.Fab")
			(hide yes)
			(effects
				(font
					(size 1 1)
					(thickness 0.15)
				)
				(justify mirror)
			)
		)
		(sheetname "/SoM_Power/")
		(sheetfile "som_power.kicad_sch")
		(attr exclude_from_pos_files exclude_from_bom)
		(fp_circle
			(center 0 0)
			(end 0.475 0)
			(stroke
				(width 0.05)
				(type default)
			)
			(fill no)
			(layer "B.CrtYd")
		)
		(fp_text user "Author: Antmicro"
			(at -0.4 -3.901 90)
			(layer "B.Fab")
			(effects
				(font
					(size 0.7 0.7)
					(thickness 0.15)
				)
				(justify right top mirror)
			)
		)
		(fp_text user "License: Apache-2.0"
			(at -0.4 -5.101 90)
			(layer "B.Fab")
			(effects
				(font
					(size 0.7 0.7)
					(thickness 0.15)
				)
				(justify right top mirror)
			)
		)
		(fp_text user "${REFERENCE}"
			(at -0.4 -2.7 90)
			(layer "B.Fab")
			(effects
				(font
					(size 0.7 0.7)
					(thickness 0.15)
				)
				(justify right top mirror)
			)
		)
		(pad "1" smd circle
			(at 0 0 90)
			(size 0.75 0.75)
			(layers "B.Cu" "B.Mask")
			(net 601 "Net-(J1A-VM_INT_N)")
			(pinfunction "1")
			(pintype "passive")
		)
	)
	(footprint "antmicro-footprints:R_0402_1005Metric"
		(layer "B.Cu")
		(at 134.6 59 -90)
		(descr "Resistor SMD 0402")
		(tags "resistor SMD 0402")
		(property "Reference" "R242"
			(at -1.8 0.6 90)
			(layer "B.SilkS")
			(effects
				(font
					(size 0.7 0.7)
					(thickness 0.15)
				)
				(justify left bottom mirror)
			)
		)
		(property "Value" "R_200R_0402"
			(at -1.011843 -1.772046 90)
			(layer "B.Fab")
			(effects
				(font
					(size 0.7 0.7)
					(thickness 0.15)
				)
				(justify left bottom mirror)
			)
		)
		(property "Datasheet" "https://www.bourns.com/docs/product-datasheets/cr.pdf"
			(at 0 0 90)
			(layer "B.Fab")
			(hide yes)
			(effects
				(font
					(size 1.27 1.27)
					(thickness 0.15)
				)
				(justify mirror)
			)
		)
		(property "Description" "SMD Chip Resistor, 200 ohm, ± 1%, 62.5 mW, 0402 [1005 Metric], Thick Film, General Purpose"
			(at 0 0 90)
			(layer "B.Fab")
			(hide yes)
			(effects
				(font
					(size 1.27 1.27)
					(thickness 0.15)
				)
				(justify mirror)
			)
		)
		(property "Manufacturer" "Bourns"
			(at 0 0 90)
			(unlocked yes)
			(layer "B.Fab")
			(hide yes)
			(effects
				(font
					(size 1 1)
					(thickness 0.15)
				)
				(justify mirror)
			)
		)
		(property "MPN" "CR0402-FX-2000GLF"
			(at 0 0 90)
			(unlocked yes)
			(layer "B.Fab")
			(hide yes)
			(effects
				(font
					(size 1 1)
					(thickness 0.15)
				)
				(justify mirror)
			)
		)
		(property "Val" "200R"
			(at 0 0 90)
			(unlocked yes)
			(layer "B.Fab")
			(hide yes)
			(effects
				(font
					(size 1 1)
					(thickness 0.15)
				)
				(justify mirror)
			)
		)
		(property "License" "Apache-2.0"
			(at 0 0 90)
			(unlocked yes)
			(layer "B.Fab")
			(hide yes)
			(effects
				(font
					(size 1 1)
					(thickness 0.15)
				)
				(justify mirror)
			)
		)
		(property "Author" "Antmicro"
			(at 0 0 90)
			(unlocked yes)
			(layer "B.Fab")
			(hide yes)
			(effects
				(font
					(size 1 1)
					(thickness 0.15)
				)
				(justify mirror)
			)
		)
		(property "Tolerance" "1%"
			(at 0 0 90)
			(unlocked yes)
			(layer "B.Fab")
			(hide yes)
			(effects
				(font
					(size 1 1)
					(thickness 0.15)
				)
				(justify mirror)
			)
		)
		(sheetname "/Peripherals/")
		(sheetfile "peripherals.kicad_sch")
		(attr smd)
		(fp_poly
			(pts
				(xy -0.925 0.47) (xy -0.925 -0.47) (xy 0.925 -0.47) (xy 0.925 0.47)
			)
			(stroke
				(width 0.05)
				(type default)
			)
			(fill no)
			(layer "B.CrtYd")
		)
		(fp_poly
			(pts
				(xy -0.5 0.25) (xy -0.5 -0.25) (xy 0.5 -0.25) (xy 0.5 0.25)
			)
			(stroke
				(width 0.15)
				(type solid)
			)
			(fill no)
			(layer "B.Fab")
		)
		(fp_text user "${REFERENCE}"
			(at -0.95 -3.168 90)
			(layer "B.Fab")
			(effects
				(font
					(size 0.7 0.7)
					(thickness 0.15)
				)
				(justify left bottom mirror)
			)
		)
		(fp_text user "License: Apache-2.0"
			(at -0.949999 -5.169 90)
			(layer "B.Fab")
			(effects
				(font
					(size 0.7 0.7)
					(thickness 0.15)
				)
				(justify left bottom mirror)
			)
		)
		(fp_text user "Author: Antmicro"
			(at -0.95 -4.169 90)
			(layer "B.Fab")
			(effects
				(font
					(size 0.7 0.7)
					(thickness 0.15)
				)
				(justify left bottom mirror)
			)
		)
		(pad "1" smd roundrect
			(at -0.48 0 270)
			(size 0.59 0.64)
			(layers "B.Cu" "B.Mask" "B.Paste")
			(roundrect_rratio 0.25)
			(net 547 "Net-(D41-A)")
			(pintype "passive")
		)
		(pad "2" smd roundrect
			(at 0.48 0 270)
			(size 0.59 0.64)
			(layers "B.Cu" "B.Mask" "B.Paste")
			(roundrect_rratio 0.25)
			(net 838 "/Peripherals/I2C_CONN1_3V3")
			(pintype "passive")
		)
	)
	(footprint "antmicro-footprints:R_0402_1005Metric"
		(layer "B.Cu")
		(at 212.8 90.785001)
		(descr "Resistor SMD 0402")
		(tags "resistor SMD 0402")
		(property "Reference" "R128"
			(at -3.9 -0.3 0)
			(layer "B.SilkS")
			(effects
				(font
					(size 0.7 0.7)
					(thickness 0.15)
				)
				(justify right top mirror)
			)
		)
		(property "Value" "R_1k_0402"
			(at -1.011843 -1.772046 0)
			(layer "B.Fab")
			(effects
				(font
					(size 0.7 0.7)
					(thickness 0.15)
				)
				(justify right top mirror)
			)
		)
		(property "Datasheet" "https://www.bourns.com/docs/product-datasheets/cr.pdf"
			(at 0 0 0)
			(layer "B.Fab")
			(hide yes)
			(effects
				(font
					(size 1.27 1.27)
					(thickness 0.15)
				)
				(justify mirror)
			)
		)
		(property "Description" "SMD Chip Resistor, 1 kohm, ± 1%, 63 mW, 0402 [1005 Metric], Thick Film, General Purpose"
			(at 0 0 0)
			(layer "B.Fab")
			(hide yes)
			(effects
				(font
					(size 1.27 1.27)
					(thickness 0.15)
				)
				(justify mirror)
			)
		)
		(property "Manufacturer" "Bourns"
			(at 0 0 180)
			(unlocked yes)
			(layer "B.Fab")
			(hide yes)
			(effects
				(font
					(size 1 1)
					(thickness 0.15)
				)
				(justify mirror)
			)
		)
		(property "MPN" "CR0402-FX-1001GLF"
			(at 0 0 180)
			(unlocked yes)
			(layer "B.Fab")
			(hide yes)
			(effects
				(font
					(size 1 1)
					(thickness 0.15)
				)
				(justify mirror)
			)
		)
		(property "Val" "1k"
			(at 0 0 180)
			(unlocked yes)
			(layer "B.Fab")
			(hide yes)
			(effects
				(font
					(size 1 1)
					(thickness 0.15)
				)
				(justify mirror)
			)
		)
		(property "License" "Apache-2.0"
			(at 0 0 180)
			(unlocked yes)
			(layer "B.Fab")
			(hide yes)
			(effects
				(font
					(size 1 1)
					(thickness 0.15)
				)
				(justify mirror)
			)
		)
		(property "Author" "Antmicro"
			(at 0 0 180)
			(unlocked yes)
			(layer "B.Fab")
			(hide yes)
			(effects
				(font
					(size 1 1)
					(thickness 0.15)
				)
				(justify mirror)
			)
		)
		(property "Tolerance" "1%"
			(at 0 0 180)
			(unlocked yes)
			(layer "B.Fab")
			(hide yes)
			(effects
				(font
					(size 1 1)
					(thickness 0.15)
				)
				(justify mirror)
			)
		)
		(sheetname "/USB DP Alt mode/")
		(sheetfile "usb_dp.kicad_sch")
		(attr smd exclude_from_pos_files exclude_from_bom dnp)
		(fp_poly
			(pts
				(xy -0.925 0.47) (xy 0.925 0.47) (xy 0.925 -0.47) (xy -0.925 -0.47)
			)
			(stroke
				(width 0.05)
				(type default)
			)
			(fill no)
			(layer "B.CrtYd")
		)
		(fp_poly
			(pts
				(xy -0.5 0.25) (xy 0.5 0.25) (xy 0.5 -0.25) (xy -0.5 -0.25)
			)
			(stroke
				(width 0.15)
				(type solid)
			)
			(fill no)
			(layer "B.Fab")
		)
		(fp_text user "${REFERENCE}"
			(at -0.95 -3.168 0)
			(layer "B.Fab")
			(effects
				(font
					(size 0.7 0.7)
					(thickness 0.15)
				)
				(justify right top mirror)
			)
		)
		(fp_text user "License: Apache-2.0"
			(at -0.949999 -5.169 0)
			(layer "B.Fab")
			(effects
				(font
					(size 0.7 0.7)
					(thickness 0.15)
				)
				(justify right top mirror)
			)
		)
		(fp_text user "Author: Antmicro"
			(at -0.95 -4.169 0)
			(layer "B.Fab")
			(effects
				(font
					(size 0.7 0.7)
					(thickness 0.15)
				)
				(justify right top mirror)
			)
		)
		(pad "1" smd roundrect
			(at -0.48 0)
			(size 0.59 0.64)
			(layers "B.Cu" "B.Mask" "B.Paste")
			(roundrect_rratio 0.25)
			(net 963 "/USB DP Alt mode/USBC1_I2C_EN")
			(pintype "passive")
		)
		(pad "2" smd roundrect
			(at 0.48 0)
			(size 0.59 0.64)
			(layers "B.Cu" "B.Mask" "B.Paste")
			(roundrect_rratio 0.25)
			(net 2 "+3V3")
			(pintype "passive")
		)
	)
	(footprint "antmicro-footprints:Vishay_PowerPAK_1212-8_Single"
		(layer "B.Cu")
		(at 183.08 79.794 90)
		(descr "PowerPAK 1212-8 Single")
		(tags "Vishay PowerPAK 1212-8 Single")
		(property "Reference" "Q23"
			(at -0.006 1.92 90)
			(layer "B.SilkS")
			(effects
				(font
					(size 0.7 0.7)
					(thickness 0.15)
				)
				(justify right top mirror)
			)
		)
		(property "Value" "SISS05DN-T1-GE3"
			(at 0 -2.7 90)
			(layer "B.Fab")
			(effects
				(font
					(size 0.7 0.7)
					(thickness 0.15)
				)
				(justify right top mirror)
			)
		)
		(property "Datasheet" "https://www.vishay.com/docs/77029/siss05dn.pdf"
			(at 0 0 90)
			(layer "B.Fab")
			(hide yes)
			(effects
				(font
					(size 1.27 1.27)
					(thickness 0.15)
				)
				(justify mirror)
			)
		)
		(property "Description" "Power MOSFET, P Channel, 30 V, 108 A, 0.0035 ohm, PowerPAK 1212, Surface Mount"
			(at 0 0 90)
			(layer "B.Fab")
			(hide yes)
			(effects
				(font
					(size 1.27 1.27)
					(thickness 0.15)
				)
				(justify mirror)
			)
		)
		(property "MPN" "SISS05DN-T1-GE3"
			(at 0 0 270)
			(unlocked yes)
			(layer "B.Fab")
			(hide yes)
			(effects
				(font
					(size 1 1)
					(thickness 0.15)
				)
				(justify mirror)
			)
		)
		(property "Manufacturer" "Vishay"
			(at 0 0 270)
			(unlocked yes)
			(layer "B.Fab")
			(hide yes)
			(effects
				(font
					(size 1 1)
					(thickness 0.15)
				)
				(justify mirror)
			)
		)
		(property "Author" "Antmicro"
			(at 0 0 270)
			(unlocked yes)
			(layer "B.Fab")
			(hide yes)
			(effects
				(font
					(size 1 1)
					(thickness 0.15)
				)
				(justify mirror)
			)
		)
		(property "License" "Apache-2.0"
			(at 0 0 270)
			(unlocked yes)
			(layer "B.Fab")
			(hide yes)
			(effects
				(font
					(size 1 1)
					(thickness 0.15)
				)
				(justify mirror)
			)
		)
		(sheetname "/Power/")
		(sheetfile "power.kicad_sch")
		(attr smd exclude_from_pos_files exclude_from_bom dnp)
		(fp_line
			(start -1.635 -1.634)
			(end 1.634 -1.634)
			(stroke
				(width 0.15)
				(type solid)
			)
			(layer "B.SilkS")
		)
		(fp_line
			(start 1.634 -1.3)
			(end 1.634 -1.634)
			(stroke
				(width 0.15)
				(type solid)
			)
			(layer "B.SilkS")
		)
		(fp_line
			(start -1.635 -1.3)
			(end -1.635 -1.634)
			(stroke
				(width 0.15)
				(type solid)
			)
			(layer "B.SilkS")
		)
		(fp_line
			(start 1.648 1.651)
			(end 1.648 1.317)
			(stroke
				(width 0.15)
				(type solid)
			)
			(layer "B.SilkS")
		)
		(fp_line
			(start -1.651 1.651)
			(end -1.651 1.317)
			(stroke
				(width 0.15)
				(type solid)
			)
			(layer "B.SilkS")
		)
		(fp_line
			(start -1.651 1.651)
			(end 1.648 1.651)
			(stroke
				(width 0.15)
				(type solid)
			)
			(layer "B.SilkS")
		)
		(fp_circle
			(center -1.9 1.4)
			(end -1.85 1.4)
			(stroke
				(width 0.15)
				(type solid)
			)
			(fill yes)
			(layer "B.SilkS")
		)
		(fp_rect
			(start -2 1.8)
			(end 2 -1.798)
			(stroke
				(width 0.05)
				(type solid)
			)
			(fill no)
			(layer "B.CrtYd")
		)
		(fp_line
			(start -1.6425 1.4175)
			(end -1.4175 1.6425)
			(stroke
				(width 0.15)
				(type solid)
			)
			(layer "B.Fab")
		)
		(fp_rect
			(start -1.651 1.651)
			(end 1.648 -1.648)
			(stroke
				(width 0.15)
				(type solid)
			)
			(fill no)
			(layer "B.Fab")
		)
		(fp_text user "Author: Antmicro"
			(at -8 -5.9 90)
			(layer "B.Fab")
			(effects
				(font
					(size 0.7 0.7)
					(thickness 0.15)
				)
				(justify right top mirror)
			)
		)
		(fp_text user "${REFERENCE}"
			(at -8 -4.7 90)
			(layer "B.Fab")
			(effects
				(font
					(size 0.7 0.7)
					(thickness 0.15)
				)
				(justify right top mirror)
			)
		)
		(fp_text user "License: Apache-2.0"
			(at -8 -7.1 90)
			(layer "B.Fab")
			(effects
				(font
					(size 0.7 0.7)
					(thickness 0.15)
				)
				(justify right top mirror)
			)
		)
		(pad "1" smd rect
			(at -1.436 0.99 90)
			(size 0.99 0.405)
			(layers "B.Cu" "B.Mask" "B.Paste")
			(net 13 "VCC")
			(pinfunction "S")
			(pintype "passive")
		)
		(pad "2" smd rect
			(at -1.436 0.332 90)
			(size 0.99 0.405)
			(layers "B.Cu" "B.Mask" "B.Paste")
			(net 13 "VCC")
			(pinfunction "S")
			(pintype "passive")
		)
		(pad "3" smd rect
			(at -1.436 -0.33 90)
			(size 0.99 0.405)
			(layers "B.Cu" "B.Mask" "B.Paste")
			(net 13 "VCC")
			(pinfunction "S")
			(pintype "passive")
		)
		(pad "4" smd rect
			(at -1.436 -0.988 90)
			(size 0.99 0.405)
			(layers "B.Cu" "B.Mask" "B.Paste")
			(net 1201 "Net-(Q23-G)")
			(pinfunction "G")
			(pintype "input")
		)
		(pad "5" smd custom
			(at 0.557 0 90)
			(size 1.725 2.235)
			(layers "B.Cu" "B.Mask" "B.Paste")
			(net 525 "/Power/USBPD2_HV")
			(pinfunction "D")
			(pintype "passive")
			(zone_connect 2)
			(options
				(clearance outline)
				(anchor rect)
			)
			(primitives
				(gr_poly
					(pts
						(xy 0.8625 -0.1275) (xy 0.8625 0.1275) (xy 1.3725 0.1275) (xy 1.3725 0.5325) (xy 0.8625 0.5325)
						(xy 0.8625 0.7875) (xy 1.3725 0.7875) (xy 1.3725 1.195) (xy 0.6125 1.195) (xy 0.6125 -1.195) (xy 1.3725 -1.195)
						(xy 1.3725 -0.7875) (xy 0.8625 -0.7875) (xy 0.8625 -0.5325) (xy 1.3725 -0.5325) (xy 1.3725 -0.1275)
					)
					(width 0)
					(fill yes)
				)
			)
		)
	)
	(footprint "antmicro-footprints:LED_0603_1608Metric_G"
		(layer "B.Cu")
		(at 133.2 55.3 -90)
		(descr "LED SMD 0603 Green")
		(tags "LED SMD 0603 Green")
		(property "Reference" "D41"
			(at -1.08 1.82 90)
			(layer "B.SilkS")
			(effects
				(font
					(size 0.7 0.7)
					(thickness 0.15)
				)
				(justify left bottom mirror)
			)
		)
		(property "Value" "LED_G_0603_LTST-C190GKT"
			(at -0.001 -1.599 90)
			(layer "B.Fab")
			(effects
				(font
					(size 0.7 0.7)
					(thickness 0.15)
				)
				(justify left bottom mirror)
			)
		)
		(property "Datasheet" "https://media.digikey.com/pdf/Data%20Sheets/Lite-On%20PDFs/LTST-C190GKT.pdf"
			(at 0 0 90)
			(layer "B.Fab")
			(hide yes)
			(effects
				(font
					(size 1.27 1.27)
					(thickness 0.15)
				)
				(justify mirror)
			)
		)
		(property "Description" "LED, Green, SMD, 0603, 20 mA, 2.1 V, 569 nm"
			(at 0 0 90)
			(layer "B.Fab")
			(hide yes)
			(effects
				(font
					(size 1.27 1.27)
					(thickness 0.15)
				)
				(justify mirror)
			)
		)
		(property "MPN" "LTST-C190GKT"
			(at 0 0 90)
			(unlocked yes)
			(layer "B.Fab")
			(hide yes)
			(effects
				(font
					(size 1 1)
					(thickness 0.15)
				)
				(justify mirror)
			)
		)
		(property "Manufacturer" "Lite-On"
			(at 0 0 90)
			(unlocked yes)
			(layer "B.Fab")
			(hide yes)
			(effects
				(font
					(size 1 1)
					(thickness 0.15)
				)
				(justify mirror)
			)
		)
		(property "Author" "Antmicro"
			(at 0 0 90)
			(unlocked yes)
			(layer "B.Fab")
			(hide yes)
			(effects
				(font
					(size 1 1)
					(thickness 0.15)
				)
				(justify mirror)
			)
		)
		(property "License" "Apache-2.0"
			(at 0 0 90)
			(unlocked yes)
			(layer "B.Fab")
			(hide yes)
			(effects
				(font
					(size 1 1)
					(thickness 0.15)
				)
				(justify mirror)
			)
		)
		(property "Color" "Green"
			(at 0 0 90)
			(unlocked yes)
			(layer "B.Fab")
			(hide yes)
			(effects
				(font
					(size 1 1)
					(thickness 0.15)
				)
				(justify mirror)
			)
		)
		(sheetname "/Peripherals/")
		(sheetfile "peripherals.kicad_sch")
		(attr smd)
		(fp_line
			(start 0.22 0.35)
			(end -0.22 0.35)
			(stroke
				(width 0.15)
				(type solid)
			)
			(layer "B.SilkS")
		)
		(fp_line
			(start -1.18 0.319)
			(end -1.18 -0.321)
			(stroke
				(width 0.15)
				(type solid)
			)
			(layer "B.SilkS")
		)
		(fp_line
			(start -0.094672 -0.001008)
			(end 0.105328 0.198992)
			(stroke
				(width 0.1)
				(type solid)
			)
			(layer "B.SilkS")
		)
		(fp_line
			(start -0.094672 -0.001008)
			(end -0.24 -0.001008)
			(stroke
				(width 0.1)
				(type solid)
			)
			(layer "B.SilkS")
		)
		(fp_line
			(start 0.105328 -0.001008)
			(end 0.24 -0.001)
			(stroke
				(width 0.1)
				(type solid)
			)
			(layer "B.SilkS")
		)
		(fp_line
			(start -0.094672 -0.201008)
			(end -0.094672 0.198992)
			(stroke
				(width 0.1)
				(type solid)
			)
			(layer "B.SilkS")
		)
		(fp_line
			(start 0.105328 -0.201008)
			(end 0.105328 0.198992)
			(stroke
				(width 0.1)
				(type solid)
			)
			(layer "B.SilkS")
		)
		(fp_line
			(start 0.105328 -0.201008)
			(end -0.094672 -0.001008)
			(stroke
				(width 0.1)
				(type solid)
			)
			(layer "B.SilkS")
		)
		(fp_line
			(start 0.22 -0.35)
			(end -0.22 -0.35)
			(stroke
				(width 0.15)
				(type solid)
			)
			(layer "B.SilkS")
		)
		(fp_rect
			(start 1.25 -0.65)
			(end -1.25 0.65)
			(stroke
				(width 0.05)
				(type solid)
			)
			(fill no)
			(layer "B.CrtYd")
		)
		(fp_line
			(start -0.199 0.202)
			(end -0.199 -0.1)
			(stroke
				(width 0.15)
				(type solid)
			)
			(layer "B.Fab")
		)
		(fp_line
			(start 0.201 0.202)
			(end -0.101 0)
			(stroke
				(width 0.15)
				(type solid)
			)
			(layer "B.Fab")
		)
		(fp_line
			(start -0.199 0)
			(end -0.597 0)
			(stroke
				(width 0.15)
				(type solid)
			)
			(layer "B.Fab")
		)
		(fp_line
			(start -0.101 0)
			(end 0.201 -0.2)
			(stroke
				(width 0.15)
				(type solid)
			)
			(layer "B.Fab")
		)
		(fp_line
			(start 0.201 0)
			(end 0.201 0.202)
			(stroke
				(width 0.15)
				(type solid)
			)
			(layer "B.Fab")
		)
		(fp_line
			(start 0.599 0)
			(end 0.201 0)
			(stroke
				(width 0.15)
				(type solid)
			)
			(layer "B.Fab")
		)
		(fp_line
			(start -0.199 -0.2)
			(end -0.199 -0.1)
			(stroke
				(width 0.15)
				(type solid)
			)
			(layer "B.Fab")
		)
		(fp_line
			(start 0.201 -0.2)
			(end 0.201 0)
			(stroke
				(width 0.15)
				(type solid)
			)
			(layer "B.Fab")
		)
		(fp_rect
			(start 0.848 -0.4)
			(end -0.85 0.402)
			(stroke
				(width 0.15)
				(type solid)
			)
			(fill no)
			(layer "B.Fab")
		)
		(fp_text user "License: Apache-2.0"
			(at -1.4224 -3.599 90)
			(layer "B.Fab")
			(effects
				(font
					(size 0.7 0.7)
					(thickness 0.15)
				)
				(justify left bottom mirror)
			)
		)
		(fp_text user "${REFERENCE}"
			(at -1.4224 -5.999 90)
			(layer "B.Fab")
			(effects
				(font
					(size 0.7 0.7)
					(thickness 0.15)
				)
				(justify left bottom mirror)
			)
		)
		(fp_text user "Author: Antmicro"
			(at -1.4224 -4.799 90)
			(layer "B.Fab")
			(effects
				(font
					(size 0.7 0.7)
					(thickness 0.15)
				)
				(justify left bottom mirror)
			)
		)
		(pad "1" smd roundrect
			(at -0.7 0 90)
			(size 0.8 1)
			(layers "B.Cu" "B.Mask" "B.Paste")
			(roundrect_rratio 0.2)
			(net 1 "GND")
			(pinfunction "C")
			(pintype "passive")
		)
		(pad "2" smd roundrect
			(at 0.7 0 90)
			(size 0.8 1)
			(layers "B.Cu" "B.Mask" "B.Paste")
			(roundrect_rratio 0.2)
			(net 547 "Net-(D41-A)")
			(pinfunction "A")
			(pintype "passive")
		)
	)
	(footprint "antmicro-footprints:C_0402_1005Metric"
		(layer "B.Cu")
		(at 105.98 70.66)
		(descr "Capacitor SMD 0402")
		(tags "capacitor SMD 0402")
		(property "Reference" "C3"
			(at -0.68 0.64 0)
			(layer "B.SilkS")
			(effects
				(font
					(size 0.7 0.7)
					(thickness 0.15)
				)
				(justify right top mirror)
			)
		)
		(property "Value" "C_10u_0402"
			(at -1.022927 -2.155213 0)
			(layer "B.Fab")
			(effects
				(font
					(size 0.7 0.7)
					(thickness 0.15)
				)
				(justify right top mirror)
			)
		)
		(property "Datasheet" "https://www.yageo.com/en/Chart/Download/pdf/CC0402MRX5R5BB106"
			(at 0 0 0)
			(layer "B.Fab")
			(hide yes)
			(effects
				(font
					(size 1.27 1.27)
					(thickness 0.15)
				)
				(justify mirror)
			)
		)
		(property "Description" "SMD Multilayer Ceramic Capacitor, 10 µF, 6.3 V, 0402 [1005 Metric], ± 20%, X5R, CC Series"
			(at 0 0 0)
			(layer "B.Fab")
			(hide yes)
			(effects
				(font
					(size 1.27 1.27)
					(thickness 0.15)
				)
				(justify mirror)
			)
		)
		(property "MPN" "CC0402MRX5R5BB106"
			(at 0 0 180)
			(unlocked yes)
			(layer "B.Fab")
			(hide yes)
			(effects
				(font
					(size 1 1)
					(thickness 0.15)
				)
				(justify mirror)
			)
		)
		(property "Manufacturer" "YAGEO"
			(at 0 0 180)
			(unlocked yes)
			(layer "B.Fab")
			(hide yes)
			(effects
				(font
					(size 1 1)
					(thickness 0.15)
				)
				(justify mirror)
			)
		)
		(property "License" "Apache-2.0"
			(at 0 0 180)
			(unlocked yes)
			(layer "B.Fab")
			(hide yes)
			(effects
				(font
					(size 1 1)
					(thickness 0.15)
				)
				(justify mirror)
			)
		)
		(property "Author" "Antmicro"
			(at 0 0 180)
			(unlocked yes)
			(layer "B.Fab")
			(hide yes)
			(effects
				(font
					(size 1 1)
					(thickness 0.15)
				)
				(justify mirror)
			)
		)
		(property "Val" "10u"
			(at 0 0 180)
			(unlocked yes)
			(layer "B.Fab")
			(hide yes)
			(effects
				(font
					(size 1 1)
					(thickness 0.15)
				)
				(justify mirror)
			)
		)
		(property "Voltage" ""
			(at 0 0 180)
			(unlocked yes)
			(layer "B.Fab")
			(hide yes)
			(effects
				(font
					(size 1 1)
					(thickness 0.15)
				)
				(justify mirror)
			)
		)
		(property "Dielectric" "template_dielectric"
			(at 0 0 180)
			(unlocked yes)
			(layer "B.Fab")
			(hide yes)
			(effects
				(font
					(size 1 1)
					(thickness 0.15)
				)
				(justify mirror)
			)
		)
		(sheetname "/SoM_Power/")
		(sheetfile "som_power.kicad_sch")
		(attr smd)
		(fp_rect
			(start -0.925 0.47)
			(end 0.925 -0.47)
			(stroke
				(width 0.05)
				(type default)
			)
			(fill no)
			(layer "B.CrtYd")
		)
		(fp_line
			(start -0.494 -0.248)
			(end -0.494 0.25)
			(stroke
				(width 0.15)
				(type solid)
			)
			(layer "B.Fab")
		)
		(fp_line
			(start -0.494 0.25)
			(end 0.504 0.25)
			(stroke
				(width 0.15)
				(type solid)
			)
			(layer "B.Fab")
		)
		(fp_line
			(start 0.504 -0.248)
			(end -0.494 -0.248)
			(stroke
				(width 0.15)
				(type solid)
			)
			(layer "B.Fab")
		)
		(fp_line
			(start 0.504 0.25)
			(end 0.504 -0.248)
			(stroke
				(width 0.15)
				(type solid)
			)
			(layer "B.Fab")
		)
		(fp_text user "Author: Antmicro"
			(at -0.939 -3.399 0)
			(layer "B.Fab")
			(effects
				(font
					(size 0.7 0.7)
					(thickness 0.15)
				)
				(justify right top mirror)
			)
		)
		(fp_text user "${REFERENCE}"
			(at -0.939 -4.599 0)
			(layer "B.Fab")
			(effects
				(font
					(size 0.7 0.7)
					(thickness 0.15)
				)
				(justify right top mirror)
			)
		)
		(fp_text user "License: Apache-2.0"
			(at -0.939 -5.799 0)
			(layer "B.Fab")
			(effects
				(font
					(size 0.7 0.7)
					(thickness 0.15)
				)
				(justify right top mirror)
			)
		)
		(pad "1" smd roundrect
			(at -0.48 0)
			(size 0.59 0.64)
			(layers "B.Cu" "B.Mask" "B.Paste")
			(roundrect_rratio 0.25)
			(net 1 "GND")
			(pintype "passive")
		)
		(pad "2" smd roundrect
			(at 0.48 0)
			(size 0.59 0.64)
			(layers "B.Cu" "B.Mask" "B.Paste")
			(roundrect_rratio 0.25)
			(net 213 "+5V_SOM")
			(pintype "passive")
		)
	)
	(footprint "antmicro-footprints:R_0402_1005Metric"
		(layer "B.Cu")
		(at 99 67.25)
		(descr "Resistor SMD 0402")
		(tags "resistor SMD 0402")
		(property "Reference" "R50"
			(at -1.122484 0.772697 0)
			(layer "B.SilkS")
			(effects
				(font
					(size 0.7 0.7)
					(thickness 0.15)
				)
				(justify right top mirror)
			)
		)
		(property "Value" "R_470R_0402"
			(at -1.011843 -1.772047 0)
			(layer "B.Fab")
			(effects
				(font
					(size 0.7 0.7)
					(thickness 0.15)
				)
				(justify right top mirror)
			)
		)
		(property "Datasheet" "https://www.bourns.com/docs/product-datasheets/cr.pdf"
			(at 0 0 0)
			(layer "B.Fab")
			(hide yes)
			(effects
				(font
					(size 1.27 1.27)
					(thickness 0.15)
				)
				(justify mirror)
			)
		)
		(property "Description" "SMD Chip Resistor, 470 ohm, ± 1%, 62.5 mW, 0402 [1005 Metric], Thick Film, General Purpose"
			(at 0 0 0)
			(layer "B.Fab")
			(hide yes)
			(effects
				(font
					(size 1.27 1.27)
					(thickness 0.15)
				)
				(justify mirror)
			)
		)
		(property "MPN" "CR0402-FX-4700GLF"
			(at 0 0 180)
			(unlocked yes)
			(layer "B.Fab")
			(hide yes)
			(effects
				(font
					(size 1 1)
					(thickness 0.15)
				)
				(justify mirror)
			)
		)
		(property "Manufacturer" "Bourns"
			(at 0 0 180)
			(unlocked yes)
			(layer "B.Fab")
			(hide yes)
			(effects
				(font
					(size 1 1)
					(thickness 0.15)
				)
				(justify mirror)
			)
		)
		(property "License" "Apache-2.0"
			(at 0 0 180)
			(unlocked yes)
			(layer "B.Fab")
			(hide yes)
			(effects
				(font
					(size 1 1)
					(thickness 0.15)
				)
				(justify mirror)
			)
		)
		(property "Author" "Antmicro"
			(at 0 0 180)
			(unlocked yes)
			(layer "B.Fab")
			(hide yes)
			(effects
				(font
					(size 1 1)
					(thickness 0.15)
				)
				(justify mirror)
			)
		)
		(property "Val" "470R"
			(at 0 0 180)
			(unlocked yes)
			(layer "B.Fab")
			(hide yes)
			(effects
				(font
					(size 1 1)
					(thickness 0.15)
				)
				(justify mirror)
			)
		)
		(property "Tolerance" "1%"
			(at 0 0 180)
			(unlocked yes)
			(layer "B.Fab")
			(hide yes)
			(effects
				(font
					(size 1 1)
					(thickness 0.15)
				)
				(justify mirror)
			)
		)
		(sheetname "/SoM_Power/")
		(sheetfile "som_power.kicad_sch")
		(attr smd)
		(fp_rect
			(start -0.925 0.47)
			(end 0.925 -0.47)
			(stroke
				(width 0.05)
				(type default)
			)
			(fill no)
			(layer "B.CrtYd")
		)
		(fp_rect
			(start -0.5 0.25)
			(end 0.5 -0.25)
			(stroke
				(width 0.15)
				(type solid)
			)
			(fill no)
			(layer "B.Fab")
		)
		(fp_text user "License: Apache-2.0"
			(at -0.95 -5.169 0)
			(layer "B.Fab")
			(effects
				(font
					(size 0.7 0.7)
					(thickness 0.15)
				)
				(justify right top mirror)
			)
		)
		(fp_text user "${REFERENCE}"
			(at -0.95 -3.168 0)
			(layer "B.Fab")
			(effects
				(font
					(size 0.7 0.7)
					(thickness 0.15)
				)
				(justify right top mirror)
			)
		)
		(fp_text user "Author: Antmicro"
			(at -0.95 -4.169 0)
			(layer "B.Fab")
			(effects
				(font
					(size 0.7 0.7)
					(thickness 0.15)
				)
				(justify right top mirror)
			)
		)
		(pad "1" smd roundrect
			(at -0.48 0)
			(size 0.59 0.64)
			(layers "B.Cu" "B.Mask" "B.Paste")
			(roundrect_rratio 0.25)
			(net 1302 "Net-(Q37-D)")
			(pintype "passive")
		)
		(pad "2" smd roundrect
			(at 0.48 0)
			(size 0.59 0.64)
			(layers "B.Cu" "B.Mask" "B.Paste")
			(roundrect_rratio 0.25)
			(net 213 "+5V_SOM")
			(pintype "passive")
		)
	)
	(footprint "antmicro-footprints:TP_SMD_0.75mm"
		(layer "B.Cu")
		(at 133.2 72.6 -90)
		(property "Reference" "TP108"
			(at 0.5 0.4 0)
			(layer "B.SilkS")
			(effects
				(font
					(size 0.7 0.7)
					(thickness 0.15)
				)
				(justify left bottom mirror)
			)
		)
		(property "Value" "TP_0.75mm_SMD"
			(at 0 -1.2 90)
			(layer "B.Fab")
			(effects
				(font
					(size 0.7 0.7)
					(thickness 0.15)
				)
				(justify left bottom mirror)
			)
		)
		(property "Description" "SMT test point"
			(at 0 0 90)
			(layer "B.Fab")
			(hide yes)
			(effects
				(font
					(size 1.27 1.27)
					(thickness 0.15)
				)
				(justify mirror)
			)
		)
		(property "MPN" ""
			(at 0 0 90)
			(unlocked yes)
			(layer "B.Fab")
			(hide yes)
			(effects
				(font
					(size 1 1)
					(thickness 0.15)
				)
				(justify mirror)
			)
		)
		(property "Manufacturer" ""
			(at 0 0 90)
			(unlocked yes)
			(layer "B.Fab")
			(hide yes)
			(effects
				(font
					(size 1 1)
					(thickness 0.15)
				)
				(justify mirror)
			)
		)
		(property "Author" "Antmicro"
			(at 0 0 90)
			(unlocked yes)
			(layer "B.Fab")
			(hide yes)
			(effects
				(font
					(size 1 1)
					(thickness 0.15)
				)
				(justify mirror)
			)
		)
		(property "License" "Apache-2.0"
			(at 0 0 90)
			(unlocked yes)
			(layer "B.Fab")
			(hide yes)
			(effects
				(font
					(size 1 1)
					(thickness 0.15)
				)
				(justify mirror)
			)
		)
		(sheetname "/SoM_IO/")
		(sheetfile "som_io.kicad_sch")
		(attr exclude_from_pos_files exclude_from_bom)
		(fp_circle
			(center 0 0)
			(end 0.475 0)
			(stroke
				(width 0.05)
				(type default)
			)
			(fill no)
			(layer "B.CrtYd")
		)
		(fp_text user "License: Apache-2.0"
			(at -0.4 -5.101 90)
			(layer "B.Fab")
			(effects
				(font
					(size 0.7 0.7)
					(thickness 0.15)
				)
				(justify left bottom mirror)
			)
		)
		(fp_text user "${REFERENCE}"
			(at -0.4 -2.7 90)
			(layer "B.Fab")
			(effects
				(font
					(size 0.7 0.7)
					(thickness 0.15)
				)
				(justify left bottom mirror)
			)
		)
		(fp_text user "Author: Antmicro"
			(at -0.4 -3.901 90)
			(layer "B.Fab")
			(effects
				(font
					(size 0.7 0.7)
					(thickness 0.15)
				)
				(justify left bottom mirror)
			)
		)
		(pad "1" smd circle
			(at 0 0 270)
			(size 0.75 0.75)
			(layers "B.Cu" "B.Mask")
			(net 108 "/SoM_IO/UART1.RX")
			(pinfunction "1")
			(pintype "passive")
		)
	)
	(footprint "antmicro-footprints:R_0402_1005Metric"
		(layer "B.Cu")
		(at 212.8 87.7)
		(descr "Resistor SMD 0402")
		(tags "resistor SMD 0402")
		(property "Reference" "R131"
			(at -3.9 -0.3 0)
			(layer "B.SilkS")
			(effects
				(font
					(size 0.7 0.7)
					(thickness 0.15)
				)
				(justify right top mirror)
			)
		)
		(property "Value" "R_1k_0402"
			(at -1.011843 -1.772046 0)
			(layer "B.Fab")
			(effects
				(font
					(size 0.7 0.7)
					(thickness 0.15)
				)
				(justify right top mirror)
			)
		)
		(property "Datasheet" "https://www.bourns.com/docs/product-datasheets/cr.pdf"
			(at 0 0 0)
			(layer "B.Fab")
			(hide yes)
			(effects
				(font
					(size 1.27 1.27)
					(thickness 0.15)
				)
				(justify mirror)
			)
		)
		(property "Description" "SMD Chip Resistor, 1 kohm, ± 1%, 63 mW, 0402 [1005 Metric], Thick Film, General Purpose"
			(at 0 0 0)
			(layer "B.Fab")
			(hide yes)
			(effects
				(font
					(size 1.27 1.27)
					(thickness 0.15)
				)
				(justify mirror)
			)
		)
		(property "Manufacturer" "Bourns"
			(at 0 0 180)
			(unlocked yes)
			(layer "B.Fab")
			(hide yes)
			(effects
				(font
					(size 1 1)
					(thickness 0.15)
				)
				(justify mirror)
			)
		)
		(property "MPN" "CR0402-FX-1001GLF"
			(at 0 0 180)
			(unlocked yes)
			(layer "B.Fab")
			(hide yes)
			(effects
				(font
					(size 1 1)
					(thickness 0.15)
				)
				(justify mirror)
			)
		)
		(property "Val" "1k"
			(at 0 0 180)
			(unlocked yes)
			(layer "B.Fab")
			(hide yes)
			(effects
				(font
					(size 1 1)
					(thickness 0.15)
				)
				(justify mirror)
			)
		)
		(property "License" "Apache-2.0"
			(at 0 0 180)
			(unlocked yes)
			(layer "B.Fab")
			(hide yes)
			(effects
				(font
					(size 1 1)
					(thickness 0.15)
				)
				(justify mirror)
			)
		)
		(property "Author" "Antmicro"
			(at 0 0 180)
			(unlocked yes)
			(layer "B.Fab")
			(hide yes)
			(effects
				(font
					(size 1 1)
					(thickness 0.15)
				)
				(justify mirror)
			)
		)
		(property "Tolerance" "1%"
			(at 0 0 180)
			(unlocked yes)
			(layer "B.Fab")
			(hide yes)
			(effects
				(font
					(size 1 1)
					(thickness 0.15)
				)
				(justify mirror)
			)
		)
		(sheetname "/USB DP Alt mode/")
		(sheetfile "usb_dp.kicad_sch")
		(attr smd exclude_from_pos_files exclude_from_bom dnp)
		(fp_poly
			(pts
				(xy -0.925 0.47) (xy 0.925 0.47) (xy 0.925 -0.47) (xy -0.925 -0.47)
			)
			(stroke
				(width 0.05)
				(type default)
			)
			(fill no)
			(layer "B.CrtYd")
		)
		(fp_poly
			(pts
				(xy -0.5 0.25) (xy 0.5 0.25) (xy 0.5 -0.25) (xy -0.5 -0.25)
			)
			(stroke
				(width 0.15)
				(type solid)
			)
			(fill no)
			(layer "B.Fab")
		)
		(fp_text user "${REFERENCE}"
			(at -0.95 -3.168 0)
			(layer "B.Fab")
			(effects
				(font
					(size 0.7 0.7)
					(thickness 0.15)
				)
				(justify right top mirror)
			)
		)
		(fp_text user "Author: Antmicro"
			(at -0.95 -4.169 0)
			(layer "B.Fab")
			(effects
				(font
					(size 0.7 0.7)
					(thickness 0.15)
				)
				(justify right top mirror)
			)
		)
		(fp_text user "License: Apache-2.0"
			(at -0.949999 -5.169 0)
			(layer "B.Fab")
			(effects
				(font
					(size 0.7 0.7)
					(thickness 0.15)
				)
				(justify right top mirror)
			)
		)
		(pad "1" smd roundrect
			(at -0.48 0)
			(size 0.59 0.64)
			(layers "B.Cu" "B.Mask" "B.Paste")
			(roundrect_rratio 0.25)
			(net 964 "/USB DP Alt mode/USBC1_SSEQ0")
			(pintype "passive")
		)
		(pad "2" smd roundrect
			(at 0.48 0)
			(size 0.59 0.64)
			(layers "B.Cu" "B.Mask" "B.Paste")
			(roundrect_rratio 0.25)
			(net 1 "GND")
			(pintype "passive")
		)
	)
	(footprint "antmicro-footprints:R_0402_1005Metric"
		(layer "B.Cu")
		(at 182 57.5 -90)
		(descr "Resistor SMD 0402")
		(tags "resistor SMD 0402")
		(property "Reference" "R17"
			(at -3.55 -0.355 90)
			(layer "B.SilkS")
			(effects
				(font
					(size 0.7 0.7)
					(thickness 0.15)
				)
				(justify left bottom mirror)
			)
		)
		(property "Value" "R_2k2_0402"
			(at -1.011843 -1.772047 90)
			(layer "B.Fab")
			(effects
				(font
					(size 0.7 0.7)
					(thickness 0.15)
				)
				(justify left bottom mirror)
			)
		)
		(property "Datasheet" "https://www.bourns.com/docs/product-datasheets/cr.pdf"
			(at 0 0 90)
			(layer "B.Fab")
			(hide yes)
			(effects
				(font
					(size 1.27 1.27)
					(thickness 0.15)
				)
				(justify mirror)
			)
		)
		(property "Description" "SMD Chip Resistor, 2.2 kohm, ± 1%, 62.5 mW, 0402 [1005 Metric], Thick Film, General Purpose"
			(at 0 0 90)
			(layer "B.Fab")
			(hide yes)
			(effects
				(font
					(size 1.27 1.27)
					(thickness 0.15)
				)
				(justify mirror)
			)
		)
		(property "MPN" "CR0402-FX-2201GLF"
			(at 0 0 90)
			(unlocked yes)
			(layer "B.Fab")
			(hide yes)
			(effects
				(font
					(size 1 1)
					(thickness 0.15)
				)
				(justify mirror)
			)
		)
		(property "Manufacturer" "Bourns"
			(at 0 0 90)
			(unlocked yes)
			(layer "B.Fab")
			(hide yes)
			(effects
				(font
					(size 1 1)
					(thickness 0.15)
				)
				(justify mirror)
			)
		)
		(property "License" "Apache-2.0"
			(at 0 0 90)
			(unlocked yes)
			(layer "B.Fab")
			(hide yes)
			(effects
				(font
					(size 1 1)
					(thickness 0.15)
				)
				(justify mirror)
			)
		)
		(property "Author" "Antmicro"
			(at 0 0 90)
			(unlocked yes)
			(layer "B.Fab")
			(hide yes)
			(effects
				(font
					(size 1 1)
					(thickness 0.15)
				)
				(justify mirror)
			)
		)
		(property "Val" "2k2"
			(at 0 0 90)
			(unlocked yes)
			(layer "B.Fab")
			(hide yes)
			(effects
				(font
					(size 1 1)
					(thickness 0.15)
				)
				(justify mirror)
			)
		)
		(property "Tolerance" "1%"
			(at 0 0 90)
			(unlocked yes)
			(layer "B.Fab")
			(hide yes)
			(effects
				(font
					(size 1 1)
					(thickness 0.15)
				)
				(justify mirror)
			)
		)
		(sheetname "/Power/")
		(sheetfile "power.kicad_sch")
		(attr smd)
		(fp_rect
			(start -0.925 0.47)
			(end 0.925 -0.47)
			(stroke
				(width 0.05)
				(type default)
			)
			(fill no)
			(layer "B.CrtYd")
		)
		(fp_rect
			(start -0.5 0.25)
			(end 0.5 -0.25)
			(stroke
				(width 0.15)
				(type solid)
			)
			(fill no)
			(layer "B.Fab")
		)
		(fp_text user "${REFERENCE}"
			(at -0.95 -3.168 90)
			(layer "B.Fab")
			(effects
				(font
					(size 0.7 0.7)
					(thickness 0.15)
				)
				(justify left bottom mirror)
			)
		)
		(fp_text user "Author: Antmicro"
			(at -0.95 -4.169 90)
			(layer "B.Fab")
			(effects
				(font
					(size 0.7 0.7)
					(thickness 0.15)
				)
				(justify left bottom mirror)
			)
		)
		(fp_text user "License: Apache-2.0"
			(at -0.95 -5.169 90)
			(layer "B.Fab")
			(effects
				(font
					(size 0.7 0.7)
					(thickness 0.15)
				)
				(justify left bottom mirror)
			)
		)
		(pad "1" smd roundrect
			(at -0.48 0 270)
			(size 0.59 0.64)
			(layers "B.Cu" "B.Mask" "B.Paste")
			(roundrect_rratio 0.25)
			(net 1108 "Net-(D6-A)")
			(pintype "passive")
		)
		(pad "2" smd roundrect
			(at 0.48 0 270)
			(size 0.59 0.64)
			(layers "B.Cu" "B.Mask" "B.Paste")
			(roundrect_rratio 0.25)
			(net 904 "+20V")
			(pintype "passive")
		)
	)
	(footprint "antmicro-footprints:PCM12SMTR"
		(layer "B.Cu")
		(at 89.505 55.89)
		(property "Reference" "SW2"
			(at -6.665 0.76 0)
			(layer "B.SilkS")
			(effects
				(font
					(size 0.7 0.7)
					(thickness 0.15)
				)
				(justify right top mirror)
			)
		)
		(property "Value" "SW_SPDT_PCM12SMTR"
			(at 0 -4.15 0)
			(layer "B.Fab")
			(effects
				(font
					(size 0.7 0.7)
					(thickness 0.15)
				)
				(justify right top mirror)
			)
		)
		(property "Datasheet" "https://www.mouser.com/datasheet/2/60/pcm-1841544.pdf"
			(at 0 0 0)
			(layer "B.Fab")
			(hide yes)
			(effects
				(font
					(size 1.27 1.27)
					(thickness 0.15)
				)
				(justify mirror)
			)
		)
		(property "Description" "Slide switch"
			(at 0 0 0)
			(layer "B.Fab")
			(hide yes)
			(effects
				(font
					(size 1.27 1.27)
					(thickness 0.15)
				)
				(justify mirror)
			)
		)
		(property "Manufacturer" "C&K"
			(at 0 0 180)
			(unlocked yes)
			(layer "B.Fab")
			(hide yes)
			(effects
				(font
					(size 1 1)
					(thickness 0.15)
				)
				(justify mirror)
			)
		)
		(property "MPN" "PCM12SMTR"
			(at 0 0 180)
			(unlocked yes)
			(layer "B.Fab")
			(hide yes)
			(effects
				(font
					(size 1 1)
					(thickness 0.15)
				)
				(justify mirror)
			)
		)
		(property "Author" "Antmicro"
			(at 0 0 180)
			(unlocked yes)
			(layer "B.Fab")
			(hide yes)
			(effects
				(font
					(size 1 1)
					(thickness 0.15)
				)
				(justify mirror)
			)
		)
		(property "License" "Apache-2.0"
			(at 0 0 180)
			(unlocked yes)
			(layer "B.Fab")
			(hide yes)
			(effects
				(font
					(size 1 1)
					(thickness 0.15)
				)
				(justify mirror)
			)
		)
		(sheetname "/SoM_Power/")
		(sheetfile "som_power.kicad_sch")
		(attr smd)
		(fp_line
			(start -3.351 -0.348)
			(end -3.351 0.251)
			(stroke
				(width 0.15)
				(type solid)
			)
			(layer "B.SilkS")
		)
		(fp_line
			(start -2.901 -1.348)
			(end 2.9 -1.348)
			(stroke
				(width 0.15)
				(type solid)
			)
			(layer "B.SilkS")
		)
		(fp_line
			(start -1.601 1.251)
			(end 0.1 1.251)
			(stroke
				(width 0.15)
				(type solid)
			)
			(layer "B.SilkS")
		)
		(fp_line
			(start 3.349 0.251)
			(end 3.349 -0.348)
			(stroke
				(width 0.15)
				(type solid)
			)
			(layer "B.SilkS")
		)
		(fp_circle
			(center -3.15 2.45)
			(end -3.1 2.39)
			(stroke
				(width 0.15)
				(type solid)
			)
			(fill yes)
			(layer "B.SilkS")
		)
		(fp_line
			(start -4.42 -1.65)
			(end -4.42 1.57)
			(stroke
				(width 0.05)
				(type solid)
			)
			(layer "B.CrtYd")
		)
		(fp_line
			(start -4.42 1.57)
			(end -2.86 1.57)
			(stroke
				(width 0.05)
				(type solid)
			)
			(layer "B.CrtYd")
		)
		(fp_line
			(start -2.86 1.57)
			(end -2.86 2.7)
			(stroke
				(width 0.05)
				(type solid)
			)
			(layer "B.CrtYd")
		)
		(fp_line
			(start -2.86 2.7)
			(end 2.83 2.7)
			(stroke
				(width 0.05)
				(type solid)
			)
			(layer "B.CrtYd")
		)
		(fp_line
			(start -1.77 -3.08)
			(end -1.77 -1.65)
			(stroke
				(width 0.05)
				(type solid)
			)
			(layer "B.CrtYd")
		)
		(fp_line
			(start -1.77 -1.65)
			(end -4.42 -1.65)
			(stroke
				(width 0.05)
				(type solid)
			)
			(layer "B.CrtYd")
		)
		(fp_line
			(start 1.74 -3.08)
			(end -1.77 -3.08)
			(stroke
				(width 0.05)
				(type solid)
			)
			(layer "B.CrtYd")
		)
		(fp_line
			(start 1.74 -1.65)
			(end 1.74 -3.08)
			(stroke
				(width 0.05)
				(type solid)
			)
			(layer "B.CrtYd")
		)
		(fp_line
			(start 2.83 1.57)
			(end 4.4 1.57)
			(stroke
				(width 0.05)
				(type solid)
			)
			(layer "B.CrtYd")
		)
		(fp_line
			(start 2.83 2.7)
			(end 2.83 1.57)
			(stroke
				(width 0.05)
				(type solid)
			)
			(layer "B.CrtYd")
		)
		(fp_line
			(start 4.4 -1.65)
			(end 1.74 -1.65)
			(stroke
				(width 0.05)
				(type solid)
			)
			(layer "B.CrtYd")
		)
		(fp_line
			(start 4.4 1.57)
			(end 4.4 -1.65)
			(stroke
				(width 0.05)
				(type solid)
			)
			(layer "B.CrtYd")
		)
		(fp_line
			(start -3.351 -1.348)
			(end -3.351 1.251)
			(stroke
				(width 0.15)
				(type solid)
			)
			(layer "B.Fab")
		)
		(fp_line
			(start -3.351 1.251)
			(end 3.349 1.251)
			(stroke
				(width 0.15)
				(type solid)
			)
			(layer "B.Fab")
		)
		(fp_line
			(start -1.502 -2.849)
			(end 1.499 -2.849)
			(stroke
				(width 0.15)
				(type solid)
			)
			(layer "B.Fab")
		)
		(fp_line
			(start -1.502 -1.348)
			(end -3.351 -1.348)
			(stroke
				(width 0.15)
				(type solid)
			)
			(layer "B.Fab")
		)
		(fp_line
			(start -1.502 -1.348)
			(end -1.502 -2.849)
			(stroke
				(width 0.15)
				(type solid)
			)
			(layer "B.Fab")
		)
		(fp_line
			(start 1.499 -2.849)
			(end 1.499 -1.348)
			(stroke
				(width 0.15)
				(type solid)
			)
			(layer "B.Fab")
		)
		(fp_line
			(start 1.499 -1.348)
			(end -1.502 -1.348)
			(stroke
				(width 0.15)
				(type solid)
			)
			(layer "B.Fab")
		)
		(fp_line
			(start 3.349 -1.348)
			(end 1.499 -1.348)
			(stroke
				(width 0.15)
				(type solid)
			)
			(layer "B.Fab")
		)
		(fp_line
			(start 3.349 1.251)
			(end 3.349 -1.348)
			(stroke
				(width 0.15)
				(type solid)
			)
			(layer "B.Fab")
		)
		(fp_text user "${REFERENCE}"
			(at -2.152 -7.94 0)
			(layer "B.Fab")
			(effects
				(font
					(size 0.7 0.7)
					(thickness 0.15)
				)
				(justify right top mirror)
			)
		)
		(fp_text user "Author: Antmicro"
			(at -2.152 -9.14 0)
			(layer "B.Fab")
			(effects
				(font
					(size 0.7 0.7)
					(thickness 0.15)
				)
				(justify right top mirror)
			)
		)
		(fp_text user "License: Apache-2.0"
			(at -2.152 -10.339 0)
			(layer "B.Fab")
			(effects
				(font
					(size 0.7 0.7)
					(thickness 0.15)
				)
				(justify right top mirror)
			)
		)
		(pad "" np_thru_hole circle
			(at -1.502 -0.049)
			(size 0.9 0.9)
			(drill 0.9)
			(layers "*.Cu" "*.Mask")
		)
		(pad "" np_thru_hole circle
			(at 1.499 -0.049)
			(size 0.9 0.9)
			(drill 0.9)
			(layers "*.Cu" "*.Mask")
		)
		(pad "1" smd roundrect
			(at -2.25 1.7)
			(size 0.7 1.5)
			(layers "B.Cu" "B.Mask" "B.Paste")
			(roundrect_rratio 0.25)
			(net 1038 "unconnected-(SW2-Pad1)")
			(pintype "passive+no_connect")
		)
		(pad "2" smd roundrect
			(at 0.749 1.7)
			(size 0.7 1.5)
			(layers "B.Cu" "B.Mask" "B.Paste")
			(roundrect_rratio 0.25)
			(net 1037 "Net-(U72-~{MR})")
			(pintype "passive")
		)
		(pad "3" smd roundrect
			(at 2.248 1.7)
			(size 0.7 1.5)
			(layers "B.Cu" "B.Mask" "B.Paste")
			(roundrect_rratio 0.25)
			(net 1036 "Net-(R307-Pad2)")
			(pintype "passive")
		)
		(pad "S1" smd roundrect
			(at -3.651 0.915)
			(size 1 0.8)
			(layers "B.Cu" "B.Mask" "B.Paste")
			(roundrect_rratio 0.25)
			(net 1 "GND")
			(pinfunction "SH")
			(pintype "passive")
		)
		(pad "S2" smd roundrect
			(at -3.651 -1.013)
			(size 1 0.8)
			(layers "B.Cu" "B.Mask" "B.Paste")
			(roundrect_rratio 0.25)
			(net 1 "GND")
			(pinfunction "SH")
			(pintype "passive")
		)
		(pad "S3" smd roundrect
			(at 3.65 -1.013)
			(size 1 0.8)
			(layers "B.Cu" "B.Mask" "B.Paste")
			(roundrect_rratio 0.25)
			(net 1 "GND")
			(pinfunction "SH")
			(pintype "passive")
		)
		(pad "S4" smd roundrect
			(at 3.65 0.915)
			(size 1 0.8)
			(layers "B.Cu" "B.Mask" "B.Paste")
			(roundrect_rratio 0.25)
			(net 1 "GND")
			(pinfunction "SH")
			(pintype "passive")
		)
	)
	(footprint "antmicro-footprints:SOT-523"
		(layer "B.Cu")
		(at 236.4 71 90)
		(property "Reference" "Q2"
			(at -0.8 1.4 90)
			(layer "B.SilkS")
			(effects
				(font
					(size 0.7 0.7)
					(thickness 0.15)
				)
				(justify right top mirror)
			)
		)
		(property "Value" "DMG1012T-7"
			(at 0.1 -1.824 90)
			(layer "B.Fab")
			(effects
				(font
					(size 0.7 0.7)
					(thickness 0.15)
				)
				(justify right top mirror)
			)
		)
		(property "Datasheet" "https://www.diodes.com/assets/Datasheets/ds31783.pdf"
			(at 0 0 90)
			(layer "B.Fab")
			(hide yes)
			(effects
				(font
					(size 1.27 1.27)
					(thickness 0.15)
				)
				(justify mirror)
			)
		)
		(property "Description" "Power MOSFET, N Channel, 20 V, 630 mA, 0.3 ohm, SOT-523, Surface Mount"
			(at 0 0 90)
			(layer "B.Fab")
			(hide yes)
			(effects
				(font
					(size 1.27 1.27)
					(thickness 0.15)
				)
				(justify mirror)
			)
		)
		(property "MPN" "DMG1012T-7"
			(at 0 0 270)
			(unlocked yes)
			(layer "B.Fab")
			(hide yes)
			(effects
				(font
					(size 1 1)
					(thickness 0.15)
				)
				(justify mirror)
			)
		)
		(property "Manufacturer" "Diodes Incorporated"
			(at 0 0 270)
			(unlocked yes)
			(layer "B.Fab")
			(hide yes)
			(effects
				(font
					(size 1 1)
					(thickness 0.15)
				)
				(justify mirror)
			)
		)
		(property "Author" "Antmicro"
			(at 0 0 270)
			(unlocked yes)
			(layer "B.Fab")
			(hide yes)
			(effects
				(font
					(size 1 1)
					(thickness 0.15)
				)
				(justify mirror)
			)
		)
		(property "License" "Apache-2.0"
			(at 0 0 270)
			(unlocked yes)
			(layer "B.Fab")
			(hide yes)
			(effects
				(font
					(size 1 1)
					(thickness 0.15)
				)
				(justify mirror)
			)
		)
		(sheetname "/SoM_Power/")
		(sheetfile "som_power.kicad_sch")
		(attr smd)
		(fp_line
			(start -0.927 0.050999)
			(end -0.927 0.350999)
			(stroke
				(width 0.15)
				(type solid)
			)
			(layer "B.SilkS")
		)
		(fp_line
			(start -0.927 0.350999)
			(end -0.725 0.551)
			(stroke
				(width 0.15)
				(type solid)
			)
			(layer "B.SilkS")
		)
		(fp_line
			(start -0.277 0.551)
			(end -0.277 0.750001)
			(stroke
				(width 0.15)
				(type solid)
			)
			(layer "B.SilkS")
		)
		(fp_line
			(start -0.725 0.551)
			(end -0.277 0.551)
			(stroke
				(width 0.15)
				(type solid)
			)
			(layer "B.SilkS")
		)
		(fp_circle
			(center -0.9652 -0.9652)
			(end -0.915201 -0.9652)
			(stroke
				(width 0.15)
				(type solid)
			)
			(fill yes)
			(layer "B.SilkS")
		)
		(fp_line
			(start -1.12 -1.15)
			(end 1.1 -1.15)
			(stroke
				(width 0.05)
				(type solid)
			)
			(layer "B.CrtYd")
		)
		(fp_line
			(start 1.1 1.159999)
			(end 1.1 -1.15)
			(stroke
				(width 0.05)
				(type solid)
			)
			(layer "B.CrtYd")
		)
		(fp_line
			(start -1.12 1.159999)
			(end -1.12 -1.15)
			(stroke
				(width 0.05)
				(type solid)
			)
			(layer "B.CrtYd")
		)
		(fp_line
			(start -1.12 1.159999)
			(end 1.1 1.159999)
			(stroke
				(width 0.05)
				(type solid)
			)
			(layer "B.CrtYd")
		)
		(fp_line
			(start 0.8 -0.424)
			(end -0.802 -0.424)
			(stroke
				(width 0.15)
				(type solid)
			)
			(layer "B.Fab")
		)
		(fp_line
			(start -0.802 0.276)
			(end -0.802 -0.424)
			(stroke
				(width 0.15)
				(type solid)
			)
			(layer "B.Fab")
		)
		(fp_line
			(start 0.8 0.425)
			(end 0.8 -0.424)
			(stroke
				(width 0.15)
				(type solid)
			)
			(layer "B.Fab")
		)
		(fp_line
			(start 0.8 0.425)
			(end -0.652 0.425)
			(stroke
				(width 0.15)
				(type solid)
			)
			(layer "B.Fab")
		)
		(fp_line
			(start -0.652 0.425)
			(end -0.802 0.276)
			(stroke
				(width 0.15)
				(type solid)
			)
			(layer "B.Fab")
		)
		(fp_circle
			(center -0.9652 -0.9652)
			(end -0.9144 -0.9652)
			(stroke
				(width 0.15)
				(type solid)
			)
			(fill no)
			(layer "B.Fab")
		)
		(fp_text user "License: Apache-2.0"
			(at -1.12 -5.024 90)
			(layer "B.Fab")
			(effects
				(font
					(size 0.7 0.7)
					(thickness 0.15)
				)
				(justify right top mirror)
			)
		)
		(fp_text user "${REFERENCE}"
			(at -1.12 -3.824 90)
			(layer "B.Fab")
			(effects
				(font
					(size 0.7 0.7)
					(thickness 0.15)
				)
				(justify right top mirror)
			)
		)
		(fp_text user "Author: Antmicro"
			(at -1.12 -6.224 90)
			(layer "B.Fab")
			(effects
				(font
					(size 0.7 0.7)
					(thickness 0.15)
				)
				(justify right top mirror)
			)
		)
		(pad "1" smd rect
			(at -0.5 -0.65 90)
			(size 0.4 0.51)
			(layers "B.Cu" "B.Mask" "B.Paste")
			(net 702 "/SoM_Power/~{SYS_RESET}")
			(pinfunction "G")
			(pintype "input")
		)
		(pad "2" smd rect
			(at 0.498 -0.65 90)
			(size 0.4 0.51)
			(layers "B.Cu" "B.Mask" "B.Paste")
			(net 1 "GND")
			(pinfunction "S")
			(pintype "passive")
		)
		(pad "3" smd rect
			(at 0 0.652001 90)
			(size 0.4 0.51)
			(layers "B.Cu" "B.Mask" "B.Paste")
			(net 1393 "Net-(D65-C)")
			(pinfunction "D")
			(pintype "passive")
		)
	)
	(footprint "antmicro-footprints:TP_SMD_0.75mm"
		(layer "B.Cu")
		(at 194.6 80.6815)
		(property "Reference" "TP13"
			(at 0.45 -3.2315 90)
			(layer "B.SilkS")
			(effects
				(font
					(size 0.7 0.7)
					(thickness 0.15)
				)
				(justify left bottom mirror)
			)
		)
		(property "Value" "TP_0.75mm_SMD"
			(at 0 -1.2 180)
			(layer "B.Fab")
			(effects
				(font
					(size 0.7 0.7)
					(thickness 0.15)
				)
				(justify left bottom mirror)
			)
		)
		(property "Description" "SMT test point"
			(at 0 0 180)
			(layer "B.Fab")
			(hide yes)
			(effects
				(font
					(size 1.27 1.27)
					(thickness 0.15)
				)
				(justify mirror)
			)
		)
		(property "MPN" ""
			(at 0 0 180)
			(unlocked yes)
			(layer "B.Fab")
			(hide yes)
			(effects
				(font
					(size 1 1)
					(thickness 0.15)
				)
				(justify mirror)
			)
		)
		(property "Manufacturer" ""
			(at 0 0 180)
			(unlocked yes)
			(layer "B.Fab")
			(hide yes)
			(effects
				(font
					(size 1 1)
					(thickness 0.15)
				)
				(justify mirror)
			)
		)
		(property "Author" "Antmicro"
			(at 0 0 180)
			(unlocked yes)
			(layer "B.Fab")
			(hide yes)
			(effects
				(font
					(size 1 1)
					(thickness 0.15)
				)
				(justify mirror)
			)
		)
		(property "License" "Apache-2.0"
			(at 0 0 180)
			(unlocked yes)
			(layer "B.Fab")
			(hide yes)
			(effects
				(font
					(size 1 1)
					(thickness 0.15)
				)
				(justify mirror)
			)
		)
		(sheetname "/USB Debug, PD/")
		(sheetfile "usb_debug_pd.kicad_sch")
		(attr exclude_from_pos_files exclude_from_bom)
		(fp_circle
			(center 0 0)
			(end 0.475 0)
			(stroke
				(width 0.05)
				(type default)
			)
			(fill no)
			(layer "B.CrtYd")
		)
		(fp_text user "Author: Antmicro"
			(at -0.4 -3.901 180)
			(layer "B.Fab")
			(effects
				(font
					(size 0.7 0.7)
					(thickness 0.15)
				)
				(justify left bottom mirror)
			)
		)
		(fp_text user "License: Apache-2.0"
			(at -0.4 -5.101 180)
			(layer "B.Fab")
			(effects
				(font
					(size 0.7 0.7)
					(thickness 0.15)
				)
				(justify left bottom mirror)
			)
		)
		(fp_text user "${REFERENCE}"
			(at -0.4 -2.7 180)
			(layer "B.Fab")
			(effects
				(font
					(size 0.7 0.7)
					(thickness 0.15)
				)
				(justify left bottom mirror)
			)
		)
		(pad "1" smd circle
			(at 0 0)
			(size 0.75 0.75)
			(layers "B.Cu" "B.Mask")
			(net 1042 "/USB Debug, PD/PDC_I2C2_IRQn")
			(pinfunction "1")
			(pintype "passive")
		)
	)
	(footprint "antmicro-footprints:QFN-16-1EP_4x4mm_P0.65mm"
		(layer "B.Cu")
		(at 220 78.34 -90)
		(property "Reference" "U34"
			(at 2.49 2.32 0)
			(layer "B.SilkS")
			(effects
				(font
					(size 0.7 0.7)
					(thickness 0.15)
				)
				(justify left bottom mirror)
			)
		)
		(property "Value" "FT230X_QFN"
			(at 0 -3.3 90)
			(layer "B.Fab")
			(effects
				(font
					(size 0.7 0.7)
					(thickness 0.15)
				)
				(justify left bottom mirror)
			)
		)
		(property "Datasheet" "https://ftdichip.com/wp-content/uploads/2021/10/DS_FT230X.pdf"
			(at 0 0 90)
			(layer "B.Fab")
			(hide yes)
			(effects
				(font
					(size 1.27 1.27)
					(thickness 0.15)
				)
				(justify mirror)
			)
		)
		(property "Description" "USB Interface, USB-UART Converter, USB 2.0, 2.97 V, 5.5 V, QFN, 16 Pins"
			(at 0 0 90)
			(layer "B.Fab")
			(hide yes)
			(effects
				(font
					(size 1.27 1.27)
					(thickness 0.15)
				)
				(justify mirror)
			)
		)
		(property "Manufacturer" "FTDI Chip"
			(at 0 0 90)
			(unlocked yes)
			(layer "B.Fab")
			(hide yes)
			(effects
				(font
					(size 1 1)
					(thickness 0.15)
				)
				(justify mirror)
			)
		)
		(property "MPN" "FT230XQ-R"
			(at 0 0 90)
			(unlocked yes)
			(layer "B.Fab")
			(hide yes)
			(effects
				(font
					(size 1 1)
					(thickness 0.15)
				)
				(justify mirror)
			)
		)
		(property "Author" "Antmicro"
			(at 0 0 90)
			(unlocked yes)
			(layer "B.Fab")
			(hide yes)
			(effects
				(font
					(size 1 1)
					(thickness 0.15)
				)
				(justify mirror)
			)
		)
		(property "License" "Apache-2.0"
			(at 0 0 90)
			(unlocked yes)
			(layer "B.Fab")
			(hide yes)
			(effects
				(font
					(size 1 1)
					(thickness 0.15)
				)
				(justify mirror)
			)
		)
		(sheetname "/USB Debug, PD/")
		(sheetfile "usb_debug_pd.kicad_sch")
		(attr smd)
		(fp_line
			(start 1.499 2.101)
			(end 2.1 2.101)
			(stroke
				(width 0.15)
				(type solid)
			)
			(layer "B.SilkS")
		)
		(fp_line
			(start 2.1 2.101)
			(end 2.1 1.401)
			(stroke
				(width 0.15)
				(type solid)
			)
			(layer "B.SilkS")
		)
		(fp_line
			(start -2.1 2.1)
			(end -2.101 1.4)
			(stroke
				(width 0.15)
				(type solid)
			)
			(layer "B.SilkS")
		)
		(fp_line
			(start -1.4 2.1)
			(end -2.1 2.1)
			(stroke
				(width 0.15)
				(type solid)
			)
			(layer "B.SilkS")
		)
		(fp_line
			(start -2.101 -1.398)
			(end -2.101 -2.1)
			(stroke
				(width 0.15)
				(type solid)
			)
			(layer "B.SilkS")
		)
		(fp_line
			(start -2.101 -2.1)
			(end -1.5 -2.1)
			(stroke
				(width 0.15)
				(type solid)
			)
			(layer "B.SilkS")
		)
		(fp_line
			(start 1.499 -2.1)
			(end 2.1 -2.1)
			(stroke
				(width 0.15)
				(type solid)
			)
			(layer "B.SilkS")
		)
		(fp_line
			(start 2.1 -2.1)
			(end 2.1 -1.398)
			(stroke
				(width 0.15)
				(type solid)
			)
			(layer "B.SilkS")
		)
		(fp_circle
			(center -2.35 1.4)
			(end -2.3 1.4)
			(stroke
				(width 0.15)
				(type solid)
			)
			(fill yes)
			(layer "B.SilkS")
		)
		(fp_rect
			(start -2.35 2.35)
			(end 2.35 -2.35)
			(stroke
				(width 0.05)
				(type solid)
			)
			(fill no)
			(layer "B.CrtYd")
		)
		(fp_line
			(start -1.5 2)
			(end -2 1.5)
			(stroke
				(width 0.15)
				(type solid)
			)
			(layer "B.Fab")
		)
		(fp_rect
			(start 2 -2)
			(end -2 2)
			(stroke
				(width 0.15)
				(type solid)
			)
			(fill no)
			(layer "B.Fab")
		)
		(fp_text user "Author: Antmicro"
			(at -2.35 -6.799 90)
			(layer "B.Fab")
			(effects
				(font
					(size 0.7 0.7)
					(thickness 0.15)
				)
				(justify left bottom mirror)
			)
		)
		(fp_text user "License: Apache-2.0"
			(at -2.35 -7.999 90)
			(layer "B.Fab")
			(effects
				(font
					(size 0.7 0.7)
					(thickness 0.15)
				)
				(justify left bottom mirror)
			)
		)
		(fp_text user "${REFERENCE}"
			(at -2.35 -5.599 90)
			(layer "B.Fab")
			(effects
				(font
					(size 0.7 0.7)
					(thickness 0.15)
				)
				(justify left bottom mirror)
			)
		)
		(pad "1" smd rect
			(at -1.9 0.975 270)
			(size 0.8 0.4)
			(layers "B.Cu" "B.Mask" "B.Paste")
			(net 334 "/USB Debug, PD/FTDI_3V3")
			(pinfunction "V_{CCIO}")
			(pintype "power_in")
		)
		(pad "2" smd rect
			(at -1.9 0.325 270)
			(size 0.8 0.4)
			(layers "B.Cu" "B.Mask" "B.Paste")
			(net 961 "Net-(U34-RXD)")
			(pinfunction "RXD")
			(pintype "input")
		)
		(pad "3" smd rect
			(at -1.9 -0.325 270)
			(size 0.8 0.4)
			(layers "B.Cu" "B.Mask" "B.Paste")
			(net 1 "GND")
			(pinfunction "GND")
			(pintype "passive")
		)
		(pad "4" smd rect
			(at -1.9 -0.975 270)
			(size 0.8 0.4)
			(layers "B.Cu" "B.Mask" "B.Paste")
			(net 1115 "unconnected-(U34-~{CTS}-Pad4)")
			(pinfunction "~{CTS}")
			(pintype "input+no_connect")
		)
		(pad "5" smd rect
			(at -0.975 -1.9 270)
			(size 0.4 0.8)
			(layers "B.Cu" "B.Mask" "B.Paste")
			(net 536 "/USB Debug, PD/FTDI_LED_TX")
			(pinfunction "CBUS2")
			(pintype "bidirectional")
		)
		(pad "6" smd rect
			(at -0.325 -1.9 270)
			(size 0.4 0.8)
			(layers "B.Cu" "B.Mask" "B.Paste")
			(net 973 "/USB Debug, PD/USB_FTDI_P")
			(pinfunction "D+")
			(pintype "input")
		)
		(pad "7" smd rect
			(at 0.325 -1.9 270)
			(size 0.4 0.8)
			(layers "B.Cu" "B.Mask" "B.Paste")
			(net 974 "/USB Debug, PD/USB_FTDI_N")
			(pinfunction "D-")
			(pintype "input")
		)
		(pad "8" smd rect
			(at 0.975 -1.9 270)
			(size 0.4 0.8)
			(layers "B.Cu" "B.Mask" "B.Paste")
			(net 334 "/USB Debug, PD/FTDI_3V3")
			(pinfunction "3V3_{OUT}")
			(pintype "passive")
		)
		(pad "9" smd rect
			(at 1.9 -0.975 270)
			(size 0.8 0.4)
			(layers "B.Cu" "B.Mask" "B.Paste")
			(net 339 "Net-(U34-~{RESET})")
			(pinfunction "~{RESET}")
			(pintype "input")
		)
		(pad "10" smd rect
			(at 1.9 -0.325 270)
			(size 0.8 0.4)
			(layers "B.Cu" "B.Mask" "B.Paste")
			(net 334 "/USB Debug, PD/FTDI_3V3")
			(pinfunction "V_{CC}")
			(pintype "power_in")
		)
		(pad "11" smd rect
			(at 1.9 0.325 270)
			(size 0.8 0.4)
			(layers "B.Cu" "B.Mask" "B.Paste")
			(net 537 "/USB Debug, PD/FTDI_LED_RX")
			(pinfunction "CBUS1")
			(pintype "bidirectional")
		)
		(pad "12" smd rect
			(at 1.9 0.975 270)
			(size 0.8 0.4)
			(layers "B.Cu" "B.Mask" "B.Paste")
			(net 956 "/USB Debug, PD/FTDI_CBUS0{slash}SDA")
			(pinfunction "CBUS0")
			(pintype "bidirectional")
		)
		(pad "13" smd rect
			(at 0.975 1.9 270)
			(size 0.4 0.8)
			(layers "B.Cu" "B.Mask" "B.Paste")
			(net 1 "GND")
			(pinfunction "GND")
			(pintype "power_in")
		)
		(pad "14" smd rect
			(at 0.325 1.9 270)
			(size 0.4 0.8)
			(layers "B.Cu" "B.Mask" "B.Paste")
			(net 955 "/USB Debug, PD/FTDI_CBUS3{slash}SCL")
			(pinfunction "CBUS3")
			(pintype "bidirectional")
		)
		(pad "15" smd rect
			(at -0.325 1.9 270)
			(size 0.4 0.8)
			(layers "B.Cu" "B.Mask" "B.Paste")
			(net 958 "Net-(U34-TXD)")
			(pinfunction "TXD")
			(pintype "output")
		)
		(pad "16" smd rect
			(at -0.975 1.9 270)
			(size 0.4 0.8)
			(layers "B.Cu" "B.Mask" "B.Paste")
			(net 1114 "unconnected-(U34-~{RTS}-Pad16)")
			(pinfunction "~{RTS}")
			(pintype "output+no_connect")
		)
		(pad "17" smd rect
			(at 0 0 270)
			(size 2.3 2.3)
			(layers "B.Cu" "B.Mask" "B.Paste")
			(net 1 "GND")
			(pinfunction "GND")
			(pintype "passive")
		)
	)
	(footprint "antmicro-footprints:R_0402_1005Metric"
		(layer "B.Cu")
		(at 157.15 68.55 180)
		(descr "Resistor SMD 0402")
		(tags "resistor SMD 0402")
		(property "Reference" "R295"
			(at -1.07 -4.15 0)
			(layer "B.SilkS")
			(effects
				(font
					(size 0.7 0.7)
					(thickness 0.15)
				)
				(justify left bottom mirror)
			)
		)
		(property "Value" "R_0R_0402"
			(at -1.011843 -1.772047 0)
			(layer "B.Fab")
			(effects
				(font
					(size 0.7 0.7)
					(thickness 0.15)
				)
				(justify left bottom mirror)
			)
		)
		(property "Datasheet" "https://industrial.panasonic.com/cdbs/www-data/pdf/RDA0000/AOA0000C301.pdf"
			(at 0 0 0)
			(layer "B.Fab")
			(hide yes)
			(effects
				(font
					(size 1.27 1.27)
					(thickness 0.15)
				)
				(justify mirror)
			)
		)
		(property "Description" "SMD Chip Resistor, Jumper, 0 ohm, 100 mW, 0402 [1005 Metric], Thick Film, General Purpose"
			(at 0 0 0)
			(layer "B.Fab")
			(hide yes)
			(effects
				(font
					(size 1.27 1.27)
					(thickness 0.15)
				)
				(justify mirror)
			)
		)
		(property "MPN" "ERJ2GE0R00X"
			(at 0 0 0)
			(unlocked yes)
			(layer "B.Fab")
			(hide yes)
			(effects
				(font
					(size 1 1)
					(thickness 0.15)
				)
				(justify mirror)
			)
		)
		(property "Manufacturer" "Panasonic"
			(at 0 0 0)
			(unlocked yes)
			(layer "B.Fab")
			(hide yes)
			(effects
				(font
					(size 1 1)
					(thickness 0.15)
				)
				(justify mirror)
			)
		)
		(property "License" "Apache-2.0"
			(at 0 0 0)
			(unlocked yes)
			(layer "B.Fab")
			(hide yes)
			(effects
				(font
					(size 1 1)
					(thickness 0.15)
				)
				(justify mirror)
			)
		)
		(property "Author" "Antmicro"
			(at 0 0 0)
			(unlocked yes)
			(layer "B.Fab")
			(hide yes)
			(effects
				(font
					(size 1 1)
					(thickness 0.15)
				)
				(justify mirror)
			)
		)
		(property "Val" "0R"
			(at 0 0 0)
			(unlocked yes)
			(layer "B.Fab")
			(hide yes)
			(effects
				(font
					(size 1 1)
					(thickness 0.15)
				)
				(justify mirror)
			)
		)
		(property "Tolerance" "~"
			(at 0 0 0)
			(unlocked yes)
			(layer "B.Fab")
			(hide yes)
			(effects
				(font
					(size 1 1)
					(thickness 0.15)
				)
				(justify mirror)
			)
		)
		(property "Current" "1A"
			(at 0 0 0)
			(unlocked yes)
			(layer "B.Fab")
			(hide yes)
			(effects
				(font
					(size 1 1)
					(thickness 0.15)
				)
				(justify mirror)
			)
		)
		(sheetname "/SoM_IO2/")
		(sheetfile "som_io2.kicad_sch")
		(attr smd exclude_from_pos_files exclude_from_bom dnp)
		(fp_rect
			(start -0.925 0.47)
			(end 0.925 -0.47)
			(stroke
				(width 0.05)
				(type default)
			)
			(fill no)
			(layer "B.CrtYd")
		)
		(fp_rect
			(start -0.5 0.25)
			(end 0.5 -0.25)
			(stroke
				(width 0.15)
				(type solid)
			)
			(fill no)
			(layer "B.Fab")
		)
		(fp_text user "License: Apache-2.0"
			(at -0.95 -5.169 0)
			(layer "B.Fab")
			(effects
				(font
					(size 0.7 0.7)
					(thickness 0.15)
				)
				(justify left bottom mirror)
			)
		)
		(fp_text user "${REFERENCE}"
			(at -0.95 -3.168 0)
			(layer "B.Fab")
			(effects
				(font
					(size 0.7 0.7)
					(thickness 0.15)
				)
				(justify left bottom mirror)
			)
		)
		(fp_text user "Author: Antmicro"
			(at -0.95 -4.169 0)
			(layer "B.Fab")
			(effects
				(font
					(size 0.7 0.7)
					(thickness 0.15)
				)
				(justify left bottom mirror)
			)
		)
		(pad "1" smd roundrect
			(at -0.48 0 180)
			(size 0.59 0.64)
			(layers "B.Cu" "B.Mask" "B.Paste")
			(roundrect_rratio 0.25)
			(net 1031 "Net-(U59-B4)")
			(pintype "passive")
		)
		(pad "2" smd roundrect
			(at 0.48 0 180)
			(size 0.59 0.64)
			(layers "B.Cu" "B.Mask" "B.Paste")
			(roundrect_rratio 0.25)
			(net 688 "/SoM_IO2/JTAG_TDO")
			(pintype "passive")
		)
	)
	(footprint "antmicro-footprints:C_0402_1005Metric"
		(layer "B.Cu")
		(at 221.35 82.3 -90)
		(descr "Capacitor SMD 0402")
		(tags "capacitor SMD 0402")
		(property "Reference" "C140"
			(at 0.9 -0.55 90)
			(layer "B.SilkS")
			(effects
				(font
					(size 0.7 0.7)
					(thickness 0.15)
				)
				(justify left bottom mirror)
			)
		)
		(property "Value" "C_100n_0402"
			(at -1.022927 -2.155213 90)
			(layer "B.Fab")
			(effects
				(font
					(size 0.7 0.7)
					(thickness 0.15)
				)
				(justify left bottom mirror)
			)
		)
		(property "Datasheet" "https://www.murata.com/products/productdetail?partno=GRM155R61H104KE14%23"
			(at 0 0 90)
			(layer "B.Fab")
			(hide yes)
			(effects
				(font
					(size 1.27 1.27)
					(thickness 0.15)
				)
				(justify mirror)
			)
		)
		(property "Description" "SMD Multilayer Ceramic Capacitor, 0.1 µF, 50 V, 0402 [1005 Metric], ± 10%, X5R, GRM Series"
			(at 0 0 90)
			(layer "B.Fab")
			(hide yes)
			(effects
				(font
					(size 1.27 1.27)
					(thickness 0.15)
				)
				(justify mirror)
			)
		)
		(property "Manufacturer" "Murata"
			(at 0 0 90)
			(unlocked yes)
			(layer "B.Fab")
			(hide yes)
			(effects
				(font
					(size 1 1)
					(thickness 0.15)
				)
				(justify mirror)
			)
		)
		(property "MPN" "GRM155R61H104KE14D"
			(at 0 0 90)
			(unlocked yes)
			(layer "B.Fab")
			(hide yes)
			(effects
				(font
					(size 1 1)
					(thickness 0.15)
				)
				(justify mirror)
			)
		)
		(property "Val" "100n"
			(at 0 0 90)
			(unlocked yes)
			(layer "B.Fab")
			(hide yes)
			(effects
				(font
					(size 1 1)
					(thickness 0.15)
				)
				(justify mirror)
			)
		)
		(property "License" "Apache-2.0"
			(at 0 0 90)
			(unlocked yes)
			(layer "B.Fab")
			(hide yes)
			(effects
				(font
					(size 1 1)
					(thickness 0.15)
				)
				(justify mirror)
			)
		)
		(property "Author" "Antmicro"
			(at 0 0 90)
			(unlocked yes)
			(layer "B.Fab")
			(hide yes)
			(effects
				(font
					(size 1 1)
					(thickness 0.15)
				)
				(justify mirror)
			)
		)
		(property "Voltage" "50V"
			(at 0 0 90)
			(unlocked yes)
			(layer "B.Fab")
			(hide yes)
			(effects
				(font
					(size 1 1)
					(thickness 0.15)
				)
				(justify mirror)
			)
		)
		(property "Dielectric" "X5R"
			(at 0 0 90)
			(unlocked yes)
			(layer "B.Fab")
			(hide yes)
			(effects
				(font
					(size 1 1)
					(thickness 0.15)
				)
				(justify mirror)
			)
		)
		(sheetname "/USB Debug, PD/")
		(sheetfile "usb_debug_pd.kicad_sch")
		(attr smd)
		(fp_rect
			(start -0.925 0.47)
			(end 0.925 -0.47)
			(stroke
				(width 0.05)
				(type default)
			)
			(fill no)
			(layer "B.CrtYd")
		)
		(fp_line
			(start -0.494 0.25)
			(end 0.504 0.25)
			(stroke
				(width 0.15)
				(type solid)
			)
			(layer "B.Fab")
		)
		(fp_line
			(start 0.504 0.25)
			(end 0.504 -0.248)
			(stroke
				(width 0.15)
				(type solid)
			)
			(layer "B.Fab")
		)
		(fp_line
			(start -0.494 -0.248)
			(end -0.494 0.25)
			(stroke
				(width 0.15)
				(type solid)
			)
			(layer "B.Fab")
		)
		(fp_line
			(start 0.504 -0.248)
			(end -0.494 -0.248)
			(stroke
				(width 0.15)
				(type solid)
			)
			(layer "B.Fab")
		)
		(fp_text user "${REFERENCE}"
			(at -0.939 -4.599 90)
			(layer "B.Fab")
			(effects
				(font
					(size 0.7 0.7)
					(thickness 0.15)
				)
				(justify left bottom mirror)
			)
		)
		(fp_text user "License: Apache-2.0"
			(at -0.939 -5.799 90)
			(layer "B.Fab")
			(effects
				(font
					(size 0.7 0.7)
					(thickness 0.15)
				)
				(justify left bottom mirror)
			)
		)
		(fp_text user "Author: Antmicro"
			(at -0.939 -3.399 90)
			(layer "B.Fab")
			(effects
				(font
					(size 0.7 0.7)
					(thickness 0.15)
				)
				(justify left bottom mirror)
			)
		)
		(pad "1" smd roundrect
			(at -0.48 0 270)
			(size 0.59 0.64)
			(layers "B.Cu" "B.Mask" "B.Paste")
			(roundrect_rratio 0.25)
			(net 339 "Net-(U34-~{RESET})")
			(pintype "passive")
		)
		(pad "2" smd roundrect
			(at 0.48 0 270)
			(size 0.59 0.64)
			(layers "B.Cu" "B.Mask" "B.Paste")
			(roundrect_rratio 0.25)
			(net 1 "GND")
			(pintype "passive")
		)
	)
	(footprint "antmicro-footprints:TP_SMD_0.75mm"
		(layer "B.Cu")
		(at 198.8 116.4 90)
		(property "Reference" "TP66"
			(at 0.58 -0.33 90)
			(layer "B.SilkS")
			(effects
				(font
					(size 0.7 0.7)
					(thickness 0.15)
				)
				(justify right top mirror)
			)
		)
		(property "Value" "TP_0.75mm_SMD"
			(at 0 -1.2 90)
			(layer "B.Fab")
			(effects
				(font
					(size 0.7 0.7)
					(thickness 0.15)
				)
				(justify right top mirror)
			)
		)
		(property "Description" "SMT test point"
			(at 0 0 90)
			(layer "B.Fab")
			(hide yes)
			(effects
				(font
					(size 1.27 1.27)
					(thickness 0.15)
				)
				(justify mirror)
			)
		)
		(property "MPN" ""
			(at 0 0 270)
			(unlocked yes)
			(layer "B.Fab")
			(hide yes)
			(effects
				(font
					(size 1 1)
					(thickness 0.15)
				)
				(justify mirror)
			)
		)
		(property "Manufacturer" ""
			(at 0 0 270)
			(unlocked yes)
			(layer "B.Fab")
			(hide yes)
			(effects
				(font
					(size 1 1)
					(thickness 0.15)
				)
				(justify mirror)
			)
		)
		(property "Author" "Antmicro"
			(at 0 0 270)
			(unlocked yes)
			(layer "B.Fab")
			(hide yes)
			(effects
				(font
					(size 1 1)
					(thickness 0.15)
				)
				(justify mirror)
			)
		)
		(property "License" "Apache-2.0"
			(at 0 0 270)
			(unlocked yes)
			(layer "B.Fab")
			(hide yes)
			(effects
				(font
					(size 1 1)
					(thickness 0.15)
				)
				(justify mirror)
			)
		)
		(sheetname "/USB Hub/")
		(sheetfile "usb_hub.kicad_sch")
		(attr exclude_from_pos_files exclude_from_bom)
		(fp_circle
			(center 0 0)
			(end 0.475 0)
			(stroke
				(width 0.05)
				(type default)
			)
			(fill no)
			(layer "B.CrtYd")
		)
		(fp_text user "${REFERENCE}"
			(at -0.4 -2.7 90)
			(layer "B.Fab")
			(effects
				(font
					(size 0.7 0.7)
					(thickness 0.15)
				)
				(justify right top mirror)
			)
		)
		(fp_text user "License: Apache-2.0"
			(at -0.4 -5.101 90)
			(layer "B.Fab")
			(effects
				(font
					(size 0.7 0.7)
					(thickness 0.15)
				)
				(justify right top mirror)
			)
		)
		(fp_text user "Author: Antmicro"
			(at -0.4 -3.901 90)
			(layer "B.Fab")
			(effects
				(font
					(size 0.7 0.7)
					(thickness 0.15)
				)
				(justify right top mirror)
			)
		)
		(pad "1" smd circle
			(at 0 0 90)
			(size 0.75 0.75)
			(layers "B.Cu" "B.Mask")
			(net 1103 "/USB Hub/DP1_DISCH")
			(pinfunction "1")
			(pintype "passive")
		)
	)
	(footprint "antmicro-footprints:R_0402_1005Metric"
		(layer "B.Cu")
		(at 212.048 76.25 -90)
		(descr "Resistor SMD 0402")
		(tags "resistor SMD 0402")
		(property "Reference" "R115"
			(at -1.25 0.648 90)
			(layer "B.SilkS")
			(effects
				(font
					(size 0.7 0.7)
					(thickness 0.15)
				)
				(justify left bottom mirror)
			)
		)
		(property "Value" "R_100k_0402"
			(at -1.011843 -1.772047 90)
			(layer "B.Fab")
			(effects
				(font
					(size 0.7 0.7)
					(thickness 0.15)
				)
				(justify left bottom mirror)
			)
		)
		(property "Datasheet" "https://www.bourns.com/docs/product-datasheets/cr.pdf"
			(at 0 0 90)
			(layer "B.Fab")
			(hide yes)
			(effects
				(font
					(size 1.27 1.27)
					(thickness 0.15)
				)
				(justify mirror)
			)
		)
		(property "Description" "SMD Chip Resistor, 100 kohm, ± 1%, 62.5 mW, 0402 [1005 Metric], Thick Film, General Purpose"
			(at 0 0 90)
			(layer "B.Fab")
			(hide yes)
			(effects
				(font
					(size 1.27 1.27)
					(thickness 0.15)
				)
				(justify mirror)
			)
		)
		(property "MPN" "CR0402-FX-1003GLF"
			(at 0 0 90)
			(unlocked yes)
			(layer "B.Fab")
			(hide yes)
			(effects
				(font
					(size 1 1)
					(thickness 0.15)
				)
				(justify mirror)
			)
		)
		(property "Manufacturer" "Bourns"
			(at 0 0 90)
			(unlocked yes)
			(layer "B.Fab")
			(hide yes)
			(effects
				(font
					(size 1 1)
					(thickness 0.15)
				)
				(justify mirror)
			)
		)
		(property "License" "Apache-2.0"
			(at 0 0 90)
			(unlocked yes)
			(layer "B.Fab")
			(hide yes)
			(effects
				(font
					(size 1 1)
					(thickness 0.15)
				)
				(justify mirror)
			)
		)
		(property "Author" "Antmicro"
			(at 0 0 90)
			(unlocked yes)
			(layer "B.Fab")
			(hide yes)
			(effects
				(font
					(size 1 1)
					(thickness 0.15)
				)
				(justify mirror)
			)
		)
		(property "Val" "100k"
			(at 0 0 90)
			(unlocked yes)
			(layer "B.Fab")
			(hide yes)
			(effects
				(font
					(size 1 1)
					(thickness 0.15)
				)
				(justify mirror)
			)
		)
		(property "Tolerance" "1%"
			(at 0 0 90)
			(unlocked yes)
			(layer "B.Fab")
			(hide yes)
			(effects
				(font
					(size 1 1)
					(thickness 0.15)
				)
				(justify mirror)
			)
		)
		(sheetname "/USB Debug, PD/")
		(sheetfile "usb_debug_pd.kicad_sch")
		(attr smd)
		(fp_rect
			(start -0.925 0.47)
			(end 0.925 -0.47)
			(stroke
				(width 0.05)
				(type default)
			)
			(fill no)
			(layer "B.CrtYd")
		)
		(fp_rect
			(start -0.5 0.25)
			(end 0.5 -0.25)
			(stroke
				(width 0.15)
				(type solid)
			)
			(fill no)
			(layer "B.Fab")
		)
		(fp_text user "License: Apache-2.0"
			(at -0.95 -5.169 90)
			(layer "B.Fab")
			(effects
				(font
					(size 0.7 0.7)
					(thickness 0.15)
				)
				(justify left bottom mirror)
			)
		)
		(fp_text user "${REFERENCE}"
			(at -0.95 -3.168 90)
			(layer "B.Fab")
			(effects
				(font
					(size 0.7 0.7)
					(thickness 0.15)
				)
				(justify left bottom mirror)
			)
		)
		(fp_text user "Author: Antmicro"
			(at -0.95 -4.169 90)
			(layer "B.Fab")
			(effects
				(font
					(size 0.7 0.7)
					(thickness 0.15)
				)
				(justify left bottom mirror)
			)
		)
		(pad "1" smd roundrect
			(at -0.48 0 270)
			(size 0.59 0.64)
			(layers "B.Cu" "B.Mask" "B.Paste")
			(roundrect_rratio 0.25)
			(net 881 "/USB Debug, PD/FTDI_CBUS_EN")
			(pintype "passive")
		)
		(pad "2" smd roundrect
			(at 0.48 0 270)
			(size 0.59 0.64)
			(layers "B.Cu" "B.Mask" "B.Paste")
			(roundrect_rratio 0.25)
			(net 334 "/USB Debug, PD/FTDI_3V3")
			(pintype "passive")
		)
	)
	(footprint "antmicro-footprints:TP_SMD_0.75mm"
		(layer "B.Cu")
		(at 146.75 63.1 -90)
		(property "Reference" "TP94"
			(at 0.5 -0.45 90)
			(layer "B.SilkS")
			(effects
				(font
					(size 0.7 0.7)
					(thickness 0.15)
				)
				(justify left bottom mirror)
			)
		)
		(property "Value" "TP_0.75mm_SMD"
			(at 0 -1.2 90)
			(layer "B.Fab")
			(effects
				(font
					(size 0.7 0.7)
					(thickness 0.15)
				)
				(justify left bottom mirror)
			)
		)
		(property "Description" "SMT test point"
			(at 0 0 90)
			(layer "B.Fab")
			(hide yes)
			(effects
				(font
					(size 1.27 1.27)
					(thickness 0.15)
				)
				(justify mirror)
			)
		)
		(property "MPN" ""
			(at 0 0 90)
			(unlocked yes)
			(layer "B.Fab")
			(hide yes)
			(effects
				(font
					(size 1 1)
					(thickness 0.15)
				)
				(justify mirror)
			)
		)
		(property "Manufacturer" ""
			(at 0 0 90)
			(unlocked yes)
			(layer "B.Fab")
			(hide yes)
			(effects
				(font
					(size 1 1)
					(thickness 0.15)
				)
				(justify mirror)
			)
		)
		(property "Author" "Antmicro"
			(at 0 0 90)
			(unlocked yes)
			(layer "B.Fab")
			(hide yes)
			(effects
				(font
					(size 1 1)
					(thickness 0.15)
				)
				(justify mirror)
			)
		)
		(property "License" "Apache-2.0"
			(at 0 0 90)
			(unlocked yes)
			(layer "B.Fab")
			(hide yes)
			(effects
				(font
					(size 1 1)
					(thickness 0.15)
				)
				(justify mirror)
			)
		)
		(sheetname "/Peripherals/")
		(sheetfile "peripherals.kicad_sch")
		(attr exclude_from_pos_files exclude_from_bom)
		(fp_circle
			(center 0 0)
			(end 0.475 0)
			(stroke
				(width 0.05)
				(type default)
			)
			(fill no)
			(layer "B.CrtYd")
		)
		(fp_text user "License: Apache-2.0"
			(at -0.4 -5.101 90)
			(layer "B.Fab")
			(effects
				(font
					(size 0.7 0.7)
					(thickness 0.15)
				)
				(justify left bottom mirror)
			)
		)
		(fp_text user "${REFERENCE}"
			(at -0.4 -2.7 90)
			(layer "B.Fab")
			(effects
				(font
					(size 0.7 0.7)
					(thickness 0.15)
				)
				(justify left bottom mirror)
			)
		)
		(fp_text user "Author: Antmicro"
			(at -0.4 -3.901 90)
			(layer "B.Fab")
			(effects
				(font
					(size 0.7 0.7)
					(thickness 0.15)
				)
				(justify left bottom mirror)
			)
		)
		(pad "1" smd circle
			(at 0 0 270)
			(size 0.75 0.75)
			(layers "B.Cu" "B.Mask")
			(net 839 "/Peripherals/I2C_CONN2_3V3")
			(pinfunction "1")
			(pintype "passive")
		)
	)
	(footprint "antmicro-footprints:Mech_Lightpipe_Bivar_SLP3-150-150-F"
		(locked yes)
		(layer "B.Cu")
		(at 232.829 65.329999 -90)
		(property "Reference" "H14"
			(at 0 1.6 90)
			(unlocked yes)
			(layer "B.SilkS")
			(effects
				(font
					(size 0.7 0.7)
					(thickness 0.15)
				)
				(justify left bottom mirror)
			)
		)
		(property "Value" "Lightpipe_Bivar_SLP3-150-150-F"
			(at 0 -6.6 90)
			(unlocked yes)
			(layer "B.Fab")
			(effects
				(font
					(size 0.7 0.7)
					(thickness 0.15)
				)
				(justify left bottom mirror)
			)
		)
		(property "Datasheet" "https://eu.mouser.com/datasheet/2/50/Bivar_SLP3_150_XXX_X_N-3318840.pdf"
			(at 0 0 90)
			(layer "B.Fab")
			(hide yes)
			(effects
				(font
					(size 1.27 1.27)
					(thickness 0.15)
				)
				(justify mirror)
			)
		)
		(property "Description" "LED Light Pipe, Rigid Board, Horizontal"
			(at 0 0 90)
			(layer "B.Fab")
			(hide yes)
			(effects
				(font
					(size 1.27 1.27)
					(thickness 0.15)
				)
				(justify mirror)
			)
		)
		(property "Manufacturer" "BIVAR"
			(at 0 0 90)
			(unlocked yes)
			(layer "B.Fab")
			(hide yes)
			(effects
				(font
					(size 1 1)
					(thickness 0.15)
				)
				(justify mirror)
			)
		)
		(property "MPN" "SLP3-150-150-F"
			(at 0 0 90)
			(unlocked yes)
			(layer "B.Fab")
			(hide yes)
			(effects
				(font
					(size 1 1)
					(thickness 0.15)
				)
				(justify mirror)
			)
		)
		(property "Author" "Antmicro"
			(at 0 0 90)
			(unlocked yes)
			(layer "B.Fab")
			(hide yes)
			(effects
				(font
					(size 1 1)
					(thickness 0.15)
				)
				(justify mirror)
			)
		)
		(property "License" "Apache-2.0"
			(at 0 0 90)
			(unlocked yes)
			(layer "B.Fab")
			(hide yes)
			(effects
				(font
					(size 1 1)
					(thickness 0.15)
				)
				(justify mirror)
			)
		)
		(sheetname "/SoM_Power/")
		(sheetfile "som_power.kicad_sch")
		(attr through_hole)
		(fp_poly
			(pts
				(xy -1.04 1.225) (xy 3.559 1.225) (xy 3.559 -5.326) (xy -1.04 -5.326)
			)
			(stroke
				(width 0.15)
				(type solid)
			)
			(fill no)
			(layer "B.SilkS")
		)
		(fp_poly
			(pts
				(xy -1.301 1.504001) (xy 3.819 1.504) (xy 3.819 -1.196) (xy -1.301 -1.196)
			)
			(stroke
				(width 0.05)
				(type solid)
			)
			(fill no)
			(layer "B.CrtYd")
		)
		(fp_poly
			(pts
				(xy -1.3 -4.196) (xy 3.819 -4.196) (xy 3.819 -5.596) (xy -1.3 -5.596)
			)
			(stroke
				(width 0.05)
				(type solid)
			)
			(fill no)
			(layer "B.CrtYd")
		)
		(fp_line
			(start 1.25 -1.8)
			(end 1.25 -2.499999)
			(stroke
				(width 0.15)
				(type solid)
			)
			(layer "B.Fab")
		)
		(fp_line
			(start 1.25 -2.499999)
			(end 1.95 -2.5)
			(stroke
				(width 0.15)
				(type solid)
			)
			(layer "B.Fab")
		)
		(fp_line
			(start 1.25 -2.499999)
			(end 1.25 -3.201)
			(stroke
				(width 0.15)
				(type solid)
			)
			(layer "B.Fab")
		)
		(fp_line
			(start 0.55 -2.5)
			(end 1.25 -2.499999)
			(stroke
				(width 0.15)
				(type solid)
			)
			(layer "B.Fab")
		)
		(fp_poly
			(pts
				(xy -0.791 -1.375999) (xy 3.309 -1.376) (xy 3.309 -3.625) (xy -0.791 -3.625001)
			)
			(stroke
				(width 0.15)
				(type solid)
			)
			(fill no)
			(layer "B.Fab")
		)
		(fp_text user "License: Apache-2.0"
			(at -7.21 -24.37 90)
			(layer "B.Fab")
			(effects
				(font
					(size 0.7 0.7)
					(thickness 0.15)
				)
				(justify left bottom mirror)
			)
		)
		(fp_text user "${REFERENCE}"
			(at -7.21 -23.17 90)
			(unlocked yes)
			(layer "B.Fab")
			(effects
				(font
					(size 0.7 0.7)
					(thickness 0.15)
				)
				(justify left bottom mirror)
			)
		)
		(fp_text user "Author: Antmicro"
			(at -7.209999 -25.57 90)
			(layer "B.Fab")
			(effects
				(font
					(size 0.7 0.7)
					(thickness 0.15)
				)
				(justify left bottom mirror)
			)
		)
		(pad "" np_thru_hole circle
			(at 0 0 270)
			(size 1.2 1.2)
			(drill 1.3)
			(layers "*.Cu" "*.Mask")
		)
		(pad "" np_thru_hole circle
			(at 2.5 0 270)
			(size 1.2 1.2)
			(drill 1.3)
			(layers "*.Cu" "*.Mask")
		)
	)
	(footprint "antmicro-footprints:C_0402_1005Metric"
		(layer "B.Cu")
		(at 207.35 131.83 -90)
		(descr "Capacitor SMD 0402")
		(tags "capacitor SMD 0402")
		(property "Reference" "C92"
			(at -1.03 0.55 90)
			(layer "B.SilkS")
			(effects
				(font
					(size 0.7 0.7)
					(thickness 0.15)
				)
				(justify left bottom mirror)
			)
		)
		(property "Value" "C_100n_0402"
			(at -1.022927 -2.155213 90)
			(layer "B.Fab")
			(effects
				(font
					(size 0.7 0.7)
					(thickness 0.15)
				)
				(justify left bottom mirror)
			)
		)
		(property "Datasheet" "https://www.murata.com/products/productdetail?partno=GRM155R61H104KE14%23"
			(at 0 0 90)
			(layer "B.Fab")
			(hide yes)
			(effects
				(font
					(size 1.27 1.27)
					(thickness 0.15)
				)
				(justify mirror)
			)
		)
		(property "Description" "SMD Multilayer Ceramic Capacitor, 0.1 µF, 50 V, 0402 [1005 Metric], ± 10%, X5R, GRM Series"
			(at 0 0 90)
			(layer "B.Fab")
			(hide yes)
			(effects
				(font
					(size 1.27 1.27)
					(thickness 0.15)
				)
				(justify mirror)
			)
		)
		(property "MPN" "GRM155R61H104KE14D"
			(at 0 0 90)
			(unlocked yes)
			(layer "B.Fab")
			(hide yes)
			(effects
				(font
					(size 1 1)
					(thickness 0.15)
				)
				(justify mirror)
			)
		)
		(property "Val" "100n"
			(at 0 0 90)
			(unlocked yes)
			(layer "B.Fab")
			(hide yes)
			(effects
				(font
					(size 1 1)
					(thickness 0.15)
				)
				(justify mirror)
			)
		)
		(property "Voltage" "50V"
			(at 0 0 90)
			(unlocked yes)
			(layer "B.Fab")
			(hide yes)
			(effects
				(font
					(size 1 1)
					(thickness 0.15)
				)
				(justify mirror)
			)
		)
		(property "Dielectric" "X5R"
			(at 0 0 90)
			(unlocked yes)
			(layer "B.Fab")
			(hide yes)
			(effects
				(font
					(size 1 1)
					(thickness 0.15)
				)
				(justify mirror)
			)
		)
		(property "Manufacturer" "Murata"
			(at 0 0 90)
			(unlocked yes)
			(layer "B.Fab")
			(hide yes)
			(effects
				(font
					(size 1 1)
					(thickness 0.15)
				)
				(justify mirror)
			)
		)
		(property "License" "Apache-2.0"
			(at 0 0 90)
			(unlocked yes)
			(layer "B.Fab")
			(hide yes)
			(effects
				(font
					(size 1 1)
					(thickness 0.15)
				)
				(justify mirror)
			)
		)
		(property "Author" "Antmicro"
			(at 0 0 90)
			(unlocked yes)
			(layer "B.Fab")
			(hide yes)
			(effects
				(font
					(size 1 1)
					(thickness 0.15)
				)
				(justify mirror)
			)
		)
		(sheetname "/USB Hub/")
		(sheetfile "usb_hub.kicad_sch")
		(attr smd)
		(fp_rect
			(start -0.925 0.47)
			(end 0.925 -0.47)
			(stroke
				(width 0.05)
				(type default)
			)
			(fill no)
			(layer "B.CrtYd")
		)
		(fp_line
			(start -0.494 0.25)
			(end 0.504 0.25)
			(stroke
				(width 0.15)
				(type solid)
			)
			(layer "B.Fab")
		)
		(fp_line
			(start 0.504 0.25)
			(end 0.504 -0.248)
			(stroke
				(width 0.15)
				(type solid)
			)
			(layer "B.Fab")
		)
		(fp_line
			(start -0.494 -0.248)
			(end -0.494 0.25)
			(stroke
				(width 0.15)
				(type solid)
			)
			(layer "B.Fab")
		)
		(fp_line
			(start 0.504 -0.248)
			(end -0.494 -0.248)
			(stroke
				(width 0.15)
				(type solid)
			)
			(layer "B.Fab")
		)
		(fp_text user "${REFERENCE}"
			(at -0.939 -4.599 90)
			(layer "B.Fab")
			(effects
				(font
					(size 0.7 0.7)
					(thickness 0.15)
				)
				(justify left bottom mirror)
			)
		)
		(fp_text user "License: Apache-2.0"
			(at -0.939 -5.799 90)
			(layer "B.Fab")
			(effects
				(font
					(size 0.7 0.7)
					(thickness 0.15)
				)
				(justify left bottom mirror)
			)
		)
		(fp_text user "Author: Antmicro"
			(at -0.939 -3.399 90)
			(layer "B.Fab")
			(effects
				(font
					(size 0.7 0.7)
					(thickness 0.15)
				)
				(justify left bottom mirror)
			)
		)
		(pad "1" smd roundrect
			(at -0.48 0 270)
			(size 0.59 0.64)
			(layers "B.Cu" "B.Mask" "B.Paste")
			(roundrect_rratio 0.25)
			(net 1 "GND")
			(pintype "passive")
		)
		(pad "2" smd roundrect
			(at 0.48 0 270)
			(size 0.59 0.64)
			(layers "B.Cu" "B.Mask" "B.Paste")
			(roundrect_rratio 0.25)
			(net 282 "+1V15")
			(pintype "passive")
		)
	)
	(footprint "antmicro-footprints:R_0402_1005Metric"
		(layer "B.Cu")
		(at 235.9 133 180)
		(descr "Resistor SMD 0402")
		(tags "resistor SMD 0402")
		(property "Reference" "R259"
			(at -3.784 -0.362 0)
			(layer "B.SilkS")
			(effects
				(font
					(size 0.7 0.7)
					(thickness 0.15)
				)
				(justify left bottom mirror)
			)
		)
		(property "Value" "R_2k2_0402"
			(at -1.011843 -1.772046 0)
			(layer "B.Fab")
			(effects
				(font
					(size 0.7 0.7)
					(thickness 0.15)
				)
				(justify left bottom mirror)
			)
		)
		(property "Datasheet" "https://www.bourns.com/docs/product-datasheets/cr.pdf"
			(at 0 0 0)
			(layer "B.Fab")
			(hide yes)
			(effects
				(font
					(size 1.27 1.27)
					(thickness 0.15)
				)
				(justify mirror)
			)
		)
		(property "Description" "SMD Chip Resistor, 2.2 kohm, ± 1%, 62.5 mW, 0402 [1005 Metric], Thick Film, General Purpose"
			(at 0 0 0)
			(layer "B.Fab")
			(hide yes)
			(effects
				(font
					(size 1.27 1.27)
					(thickness 0.15)
				)
				(justify mirror)
			)
		)
		(property "Manufacturer" "Bourns"
			(at 0 0 0)
			(unlocked yes)
			(layer "B.Fab")
			(hide yes)
			(effects
				(font
					(size 1 1)
					(thickness 0.15)
				)
				(justify mirror)
			)
		)
		(property "MPN" "CR0402-FX-2201GLF"
			(at 0 0 0)
			(unlocked yes)
			(layer "B.Fab")
			(hide yes)
			(effects
				(font
					(size 1 1)
					(thickness 0.15)
				)
				(justify mirror)
			)
		)
		(property "Val" "2k2"
			(at 0 0 0)
			(unlocked yes)
			(layer "B.Fab")
			(hide yes)
			(effects
				(font
					(size 1 1)
					(thickness 0.15)
				)
				(justify mirror)
			)
		)
		(property "License" "Apache-2.0"
			(at 0 0 0)
			(unlocked yes)
			(layer "B.Fab")
			(hide yes)
			(effects
				(font
					(size 1 1)
					(thickness 0.15)
				)
				(justify mirror)
			)
		)
		(property "Author" "Antmicro"
			(at 0 0 0)
			(unlocked yes)
			(layer "B.Fab")
			(hide yes)
			(effects
				(font
					(size 1 1)
					(thickness 0.15)
				)
				(justify mirror)
			)
		)
		(property "Tolerance" "1%"
			(at 0 0 0)
			(unlocked yes)
			(layer "B.Fab")
			(hide yes)
			(effects
				(font
					(size 1 1)
					(thickness 0.15)
				)
				(justify mirror)
			)
		)
		(sheetname "/USB Hub/")
		(sheetfile "usb_hub.kicad_sch")
		(attr smd)
		(fp_poly
			(pts
				(xy -0.925 0.47) (xy -0.925 -0.47) (xy 0.925 -0.47) (xy 0.925 0.47)
			)
			(stroke
				(width 0.05)
				(type default)
			)
			(fill no)
			(layer "B.CrtYd")
		)
		(fp_poly
			(pts
				(xy -0.5 0.25) (xy -0.5 -0.25) (xy 0.5 -0.25) (xy 0.5 0.25)
			)
			(stroke
				(width 0.15)
				(type solid)
			)
			(fill no)
			(layer "B.Fab")
		)
		(fp_text user "${REFERENCE}"
			(at -0.95 -3.168 0)
			(layer "B.Fab")
			(effects
				(font
					(size 0.7 0.7)
					(thickness 0.15)
				)
				(justify left bottom mirror)
			)
		)
		(fp_text user "Author: Antmicro"
			(at -0.95 -4.169 0)
			(layer "B.Fab")
			(effects
				(font
					(size 0.7 0.7)
					(thickness 0.15)
				)
				(justify left bottom mirror)
			)
		)
		(fp_text user "License: Apache-2.0"
			(at -0.949999 -5.169 0)
			(layer "B.Fab")
			(effects
				(font
					(size 0.7 0.7)
					(thickness 0.15)
				)
				(justify left bottom mirror)
			)
		)
		(pad "1" smd roundrect
			(at -0.48 0 180)
			(size 0.59 0.64)
			(layers "B.Cu" "B.Mask" "B.Paste")
			(roundrect_rratio 0.25)
			(net 1 "GND")
			(pintype "passive")
		)
		(pad "2" smd roundrect
			(at 0.48 0 180)
			(size 0.59 0.64)
			(layers "B.Cu" "B.Mask" "B.Paste")
			(roundrect_rratio 0.25)
			(net 1015 "/USB Hub/USBC4_ISET")
			(pintype "passive")
		)
	)
	(footprint "antmicro-footprints:TP_SMD_0.75mm"
		(layer "B.Cu")
		(at 197.5 124.3)
		(property "Reference" "TP1"
			(at -0.5 0.9 180)
			(layer "B.SilkS")
			(effects
				(font
					(size 0.7 0.7)
					(thickness 0.15)
				)
				(justify left bottom mirror)
			)
		)
		(property "Value" "TP_0.75mm_SMD"
			(at 0 -1.2 180)
			(layer "B.Fab")
			(effects
				(font
					(size 0.7 0.7)
					(thickness 0.15)
				)
				(justify left bottom mirror)
			)
		)
		(property "Description" "SMT test point"
			(at 0 0 180)
			(layer "B.Fab")
			(hide yes)
			(effects
				(font
					(size 1.27 1.27)
					(thickness 0.15)
				)
				(justify mirror)
			)
		)
		(property "MPN" ""
			(at 0 0 180)
			(unlocked yes)
			(layer "B.Fab")
			(hide yes)
			(effects
				(font
					(size 1 1)
					(thickness 0.15)
				)
				(justify mirror)
			)
		)
		(property "Manufacturer" ""
			(at 0 0 180)
			(unlocked yes)
			(layer "B.Fab")
			(hide yes)
			(effects
				(font
					(size 1 1)
					(thickness 0.15)
				)
				(justify mirror)
			)
		)
		(property "Author" "Antmicro"
			(at 0 0 180)
			(unlocked yes)
			(layer "B.Fab")
			(hide yes)
			(effects
				(font
					(size 1 1)
					(thickness 0.15)
				)
				(justify mirror)
			)
		)
		(property "License" "Apache-2.0"
			(at 0 0 180)
			(unlocked yes)
			(layer "B.Fab")
			(hide yes)
			(effects
				(font
					(size 1 1)
					(thickness 0.15)
				)
				(justify mirror)
			)
		)
		(sheetname "/USB Hub/")
		(sheetfile "usb_hub.kicad_sch")
		(attr exclude_from_pos_files exclude_from_bom)
		(fp_circle
			(center 0 0)
			(end 0.475 0)
			(stroke
				(width 0.05)
				(type default)
			)
			(fill no)
			(layer "B.CrtYd")
		)
		(fp_text user "License: Apache-2.0"
			(at -0.4 -5.101 180)
			(layer "B.Fab")
			(effects
				(font
					(size 0.7 0.7)
					(thickness 0.15)
				)
				(justify left bottom mirror)
			)
		)
		(fp_text user "Author: Antmicro"
			(at -0.4 -3.901 180)
			(layer "B.Fab")
			(effects
				(font
					(size 0.7 0.7)
					(thickness 0.15)
				)
				(justify left bottom mirror)
			)
		)
		(fp_text user "${REFERENCE}"
			(at -0.4 -2.7 180)
			(layer "B.Fab")
			(effects
				(font
					(size 0.7 0.7)
					(thickness 0.15)
				)
				(justify left bottom mirror)
			)
		)
		(pad "1" smd circle
			(at 0 0)
			(size 0.75 0.75)
			(layers "B.Cu" "B.Mask")
			(net 914 "/USB Hub/PRT_CTL1")
			(pinfunction "1")
			(pintype "passive")
		)
	)
	(footprint "antmicro-footprints:R_0402_1005Metric"
		(layer "B.Cu")
		(at 201.3 130.5 90)
		(descr "Resistor SMD 0402")
		(tags "resistor SMD 0402")
		(property "Reference" "R58"
			(at -3.1 -0.3 90)
			(layer "B.SilkS")
			(effects
				(font
					(size 0.7 0.7)
					(thickness 0.15)
				)
				(justify right top mirror)
			)
		)
		(property "Value" "R_0R_0402"
			(at -1.011843 -1.772047 90)
			(layer "B.Fab")
			(effects
				(font
					(size 0.7 0.7)
					(thickness 0.15)
				)
				(justify right top mirror)
			)
		)
		(property "Datasheet" "https://industrial.panasonic.com/cdbs/www-data/pdf/RDA0000/AOA0000C301.pdf"
			(at 0 0 90)
			(layer "B.Fab")
			(hide yes)
			(effects
				(font
					(size 1.27 1.27)
					(thickness 0.15)
				)
				(justify mirror)
			)
		)
		(property "Description" "SMD Chip Resistor, Jumper, 0 ohm, 100 mW, 0402 [1005 Metric], Thick Film, General Purpose"
			(at 0 0 90)
			(layer "B.Fab")
			(hide yes)
			(effects
				(font
					(size 1.27 1.27)
					(thickness 0.15)
				)
				(justify mirror)
			)
		)
		(property "Manufacturer" "Panasonic"
			(at 0 0 270)
			(unlocked yes)
			(layer "B.Fab")
			(hide yes)
			(effects
				(font
					(size 1 1)
					(thickness 0.15)
				)
				(justify mirror)
			)
		)
		(property "MPN" "ERJ2GE0R00X"
			(at 0 0 270)
			(unlocked yes)
			(layer "B.Fab")
			(hide yes)
			(effects
				(font
					(size 1 1)
					(thickness 0.15)
				)
				(justify mirror)
			)
		)
		(property "Val" "0R"
			(at 0 0 270)
			(unlocked yes)
			(layer "B.Fab")
			(hide yes)
			(effects
				(font
					(size 1 1)
					(thickness 0.15)
				)
				(justify mirror)
			)
		)
		(property "License" "Apache-2.0"
			(at 0 0 270)
			(unlocked yes)
			(layer "B.Fab")
			(hide yes)
			(effects
				(font
					(size 1 1)
					(thickness 0.15)
				)
				(justify mirror)
			)
		)
		(property "Author" "Antmicro"
			(at 0 0 270)
			(unlocked yes)
			(layer "B.Fab")
			(hide yes)
			(effects
				(font
					(size 1 1)
					(thickness 0.15)
				)
				(justify mirror)
			)
		)
		(property "Tolerance" "~"
			(at 0 0 270)
			(unlocked yes)
			(layer "B.Fab")
			(hide yes)
			(effects
				(font
					(size 1 1)
					(thickness 0.15)
				)
				(justify mirror)
			)
		)
		(property "Current" "1A"
			(at 0 0 270)
			(unlocked yes)
			(layer "B.Fab")
			(hide yes)
			(effects
				(font
					(size 1 1)
					(thickness 0.15)
				)
				(justify mirror)
			)
		)
		(sheetname "/USB Hub/")
		(sheetfile "usb_hub.kicad_sch")
		(attr smd)
		(fp_rect
			(start -0.925 0.47)
			(end 0.925 -0.47)
			(stroke
				(width 0.05)
				(type default)
			)
			(fill no)
			(layer "B.CrtYd")
		)
		(fp_rect
			(start -0.5 0.25)
			(end 0.5 -0.25)
			(stroke
				(width 0.15)
				(type solid)
			)
			(fill no)
			(layer "B.Fab")
		)
		(fp_text user "${REFERENCE}"
			(at -0.95 -3.168 90)
			(layer "B.Fab")
			(effects
				(font
					(size 0.7 0.7)
					(thickness 0.15)
				)
				(justify right top mirror)
			)
		)
		(fp_text user "Author: Antmicro"
			(at -0.95 -4.169 90)
			(layer "B.Fab")
			(effects
				(font
					(size 0.7 0.7)
					(thickness 0.15)
				)
				(justify right top mirror)
			)
		)
		(fp_text user "License: Apache-2.0"
			(at -0.95 -5.169 90)
			(layer "B.Fab")
			(effects
				(font
					(size 0.7 0.7)
					(thickness 0.15)
				)
				(justify right top mirror)
			)
		)
		(pad "1" smd roundrect
			(at -0.48 0 90)
			(size 0.59 0.64)
			(layers "B.Cu" "B.Mask" "B.Paste")
			(roundrect_rratio 0.25)
			(net 1142 "Net-(U21-USB3DN_RXDP3)")
			(pintype "passive")
		)
		(pad "2" smd roundrect
			(at 0.48 0 90)
			(size 0.59 0.64)
			(layers "B.Cu" "B.Mask" "B.Paste")
			(roundrect_rratio 0.25)
			(net 1 "GND")
			(pintype "passive")
		)
	)
	(footprint "antmicro-footprints:C_0805_2012Metric"
		(layer "B.Cu")
		(at 99.1 126.5 -90)
		(descr "Capacitor SMD 0805")
		(tags "capacitor SMD 0805")
		(property "Reference" "C229"
			(at -1.5 -2.1 90)
			(layer "B.SilkS")
			(effects
				(font
					(size 0.7 0.7)
					(thickness 0.15)
				)
				(justify left bottom mirror)
			)
		)
		(property "Value" "C_22u_25V_0805"
			(at -2.055717 -1.963153 90)
			(layer "B.Fab")
			(effects
				(font
					(size 0.7 0.7)
					(thickness 0.15)
				)
				(justify left bottom mirror)
			)
		)
		(property "Datasheet" "https://product.samsungsem.com/mlcc/CL21A226MAYNNN.do"
			(at 0 0 90)
			(layer "B.Fab")
			(hide yes)
			(effects
				(font
					(size 1.27 1.27)
					(thickness 0.15)
				)
				(justify mirror)
			)
		)
		(property "Description" "SMT Multilayer Ceramic Capacitor, 22uF, +/-20%, 25V, X5R, 0805 [2012 Metric]"
			(at 0 0 90)
			(layer "B.Fab")
			(hide yes)
			(effects
				(font
					(size 1.27 1.27)
					(thickness 0.15)
				)
				(justify mirror)
			)
		)
		(property "MPN" "CL21A226MAYNNNE"
			(at 0 0 270)
			(unlocked yes)
			(layer "B.Fab")
			(hide yes)
			(effects
				(font
					(size 1 1)
					(thickness 0.15)
				)
				(justify mirror)
			)
		)
		(property "Val" "22u"
			(at 0 0 270)
			(unlocked yes)
			(layer "B.Fab")
			(hide yes)
			(effects
				(font
					(size 1 1)
					(thickness 0.15)
				)
				(justify mirror)
			)
		)
		(property "Voltage" "25V"
			(at 0 0 270)
			(unlocked yes)
			(layer "B.Fab")
			(hide yes)
			(effects
				(font
					(size 1 1)
					(thickness 0.15)
				)
				(justify mirror)
			)
		)
		(property "Dielectric" "X5R"
			(at 0 0 270)
			(unlocked yes)
			(layer "B.Fab")
			(hide yes)
			(effects
				(font
					(size 1 1)
					(thickness 0.15)
				)
				(justify mirror)
			)
		)
		(property "Manufacturer" "Samsung Electro-Mechanics"
			(at 0 0 270)
			(unlocked yes)
			(layer "B.Fab")
			(hide yes)
			(effects
				(font
					(size 1 1)
					(thickness 0.15)
				)
				(justify mirror)
			)
		)
		(property "License" "Apache-2.0"
			(at 0 0 270)
			(unlocked yes)
			(layer "B.Fab")
			(hide yes)
			(effects
				(font
					(size 1 1)
					(thickness 0.15)
				)
				(justify mirror)
			)
		)
		(property "Author" "Antmicro"
			(at 0 0 270)
			(unlocked yes)
			(layer "B.Fab")
			(hide yes)
			(effects
				(font
					(size 1 1)
					(thickness 0.15)
				)
				(justify mirror)
			)
		)
		(property "Public" "False"
			(at 0 0 270)
			(unlocked yes)
			(layer "B.Fab")
			(hide yes)
			(effects
				(font
					(size 1 1)
					(thickness 0.15)
				)
				(justify mirror)
			)
		)
		(sheetname "/Expansion connector/")
		(sheetfile "expansion_connector.kicad_sch")
		(attr smd)
		(fp_line
			(start -0.3 0.7)
			(end 0.3 0.7)
			(stroke
				(width 0.15)
				(type solid)
			)
			(layer "B.SilkS")
		)
		(fp_line
			(start -0.3 -0.7)
			(end 0.3 -0.7)
			(stroke
				(width 0.15)
				(type solid)
			)
			(layer "B.SilkS")
		)
		(fp_poly
			(pts
				(xy 1.95 0.9) (xy -1.95 0.9) (xy -1.95 -0.9) (xy 1.95 -0.9)
			)
			(stroke
				(width 0.05)
				(type default)
			)
			(fill no)
			(layer "B.CrtYd")
		)
		(fp_poly
			(pts
				(xy -0.95 0.675001) (xy 0.95 0.675001) (xy 0.95 -0.675001) (xy -0.95 -0.675001)
			)
			(stroke
				(width 0.15)
				(type solid)
			)
			(fill no)
			(layer "B.Fab")
		)
		(fp_text user "Author: Antmicro"
			(at -1.9 -5.947 90)
			(layer "B.Fab")
			(effects
				(font
					(size 0.7 0.7)
					(thickness 0.15)
				)
				(justify left bottom mirror)
			)
		)
		(fp_text user "${REFERENCE}"
			(at -1.899999 -3.947 90)
			(layer "B.Fab")
			(effects
				(font
					(size 0.7 0.7)
					(thickness 0.15)
				)
				(justify left bottom mirror)
			)
		)
		(fp_text user "License: Apache-2.0"
			(at -1.9 -4.947 90)
			(layer "B.Fab")
			(effects
				(font
					(size 0.7 0.7)
					(thickness 0.15)
				)
				(justify left bottom mirror)
			)
		)
		(pad "1" smd roundrect
			(at -1.099999 0 270)
			(size 1.2 1.3)
			(layers "B.Cu" "B.Mask" "B.Paste")
			(roundrect_rratio 0.25)
			(net 1 "GND")
			(pintype "passive")
		)
		(pad "2" smd roundrect
			(at 1.099999 0 270)
			(size 1.2 1.3)
			(layers "B.Cu" "B.Mask" "B.Paste")
			(roundrect_rratio 0.25)
			(net 297 "/Expansion connector/+3V3_FMC")
			(pintype "passive")
		)
	)
	(footprint "antmicro-footprints:TP_SMD_0.75mm"
		(layer "B.Cu")
		(at 137.95 84.1 90)
		(property "Reference" "TP59"
			(at -3.13 -0.31 90)
			(layer "B.SilkS")
			(effects
				(font
					(size 0.7 0.7)
					(thickness 0.15)
				)
				(justify right top mirror)
			)
		)
		(property "Value" "TP_0.75mm_SMD"
			(at 0 -1.2 90)
			(layer "B.Fab")
			(effects
				(font
					(size 0.7 0.7)
					(thickness 0.15)
				)
				(justify right top mirror)
			)
		)
		(property "Description" "SMT test point"
			(at 0 0 90)
			(layer "B.Fab")
			(hide yes)
			(effects
				(font
					(size 1.27 1.27)
					(thickness 0.15)
				)
				(justify mirror)
			)
		)
		(property "MPN" ""
			(at 0 0 270)
			(unlocked yes)
			(layer "B.Fab")
			(hide yes)
			(effects
				(font
					(size 1 1)
					(thickness 0.15)
				)
				(justify mirror)
			)
		)
		(property "Manufacturer" ""
			(at 0 0 270)
			(unlocked yes)
			(layer "B.Fab")
			(hide yes)
			(effects
				(font
					(size 1 1)
					(thickness 0.15)
				)
				(justify mirror)
			)
		)
		(property "Author" "Antmicro"
			(at 0 0 270)
			(unlocked yes)
			(layer "B.Fab")
			(hide yes)
			(effects
				(font
					(size 1 1)
					(thickness 0.15)
				)
				(justify mirror)
			)
		)
		(property "License" "Apache-2.0"
			(at 0 0 270)
			(unlocked yes)
			(layer "B.Fab")
			(hide yes)
			(effects
				(font
					(size 1 1)
					(thickness 0.15)
				)
				(justify mirror)
			)
		)
		(sheetname "/SoM_Power/")
		(sheetfile "som_power.kicad_sch")
		(attr exclude_from_pos_files exclude_from_bom)
		(fp_circle
			(center 0 0)
			(end 0.475 0)
			(stroke
				(width 0.05)
				(type default)
			)
			(fill no)
			(layer "B.CrtYd")
		)
		(fp_text user "License: Apache-2.0"
			(at -0.4 -5.101 90)
			(layer "B.Fab")
			(effects
				(font
					(size 0.7 0.7)
					(thickness 0.15)
				)
				(justify right top mirror)
			)
		)
		(fp_text user "${REFERENCE}"
			(at -0.4 -2.7 90)
			(layer "B.Fab")
			(effects
				(font
					(size 0.7 0.7)
					(thickness 0.15)
				)
				(justify right top mirror)
			)
		)
		(fp_text user "Author: Antmicro"
			(at -0.4 -3.901 90)
			(layer "B.Fab")
			(effects
				(font
					(size 0.7 0.7)
					(thickness 0.15)
				)
				(justify right top mirror)
			)
		)
		(pad "1" smd circle
			(at 0 0 90)
			(size 0.75 0.75)
			(layers "B.Cu" "B.Mask")
			(net 704 "Net-(J1A-GPIO30)")
			(pinfunction "1")
			(pintype "passive")
		)
	)
	(footprint "antmicro-footprints:TSOT23-6"
		(layer "B.Cu")
		(at 210.5 62.5 180)
		(property "Reference" "U47"
			(at -2.1 -1.6 90)
			(layer "B.SilkS")
			(effects
				(font
					(size 0.7 0.7)
					(thickness 0.15)
				)
				(justify right top mirror)
			)
		)
		(property "Value" "AP22615A_TSOT26"
			(at 0 -2.600001 0)
			(layer "B.Fab")
			(effects
				(font
					(size 0.7 0.7)
					(thickness 0.15)
				)
				(justify left bottom mirror)
			)
		)
		(property "Datasheet" "https://www.mouser.com/datasheet/2/115/DIOD_S_A0008958405_1-2543193.pdf"
			(at 0 0 0)
			(layer "B.Fab")
			(hide yes)
			(effects
				(font
					(size 1.27 1.27)
					(thickness 0.15)
				)
				(justify mirror)
			)
		)
		(property "Description" "Power Load Distribution Switch, High Side, Active High, 1 Output, 5.5 V, 3.6 A, 0.04 ohm, TSOT-26-6"
			(at 0 0 0)
			(layer "B.Fab")
			(hide yes)
			(effects
				(font
					(size 1.27 1.27)
					(thickness 0.15)
				)
				(justify mirror)
			)
		)
		(property "MPN" "AP22615AWU-7"
			(at 0 0 0)
			(unlocked yes)
			(layer "B.Fab")
			(hide yes)
			(effects
				(font
					(size 1 1)
					(thickness 0.15)
				)
				(justify mirror)
			)
		)
		(property "Manufacturer" "Diodes Incorporated"
			(at 0 0 0)
			(unlocked yes)
			(layer "B.Fab")
			(hide yes)
			(effects
				(font
					(size 1 1)
					(thickness 0.15)
				)
				(justify mirror)
			)
		)
		(property "Author" "Antmicro"
			(at 0 0 0)
			(unlocked yes)
			(layer "B.Fab")
			(hide yes)
			(effects
				(font
					(size 1 1)
					(thickness 0.15)
				)
				(justify mirror)
			)
		)
		(property "License" "Apache-2.0"
			(at 0 0 0)
			(unlocked yes)
			(layer "B.Fab")
			(hide yes)
			(effects
				(font
					(size 1 1)
					(thickness 0.15)
				)
				(justify mirror)
			)
		)
		(sheetname "/CSI/")
		(sheetfile "csi.kicad_sch")
		(attr smd)
		(fp_line
			(start 1 1.497)
			(end 1 1.375)
			(stroke
				(width 0.15)
				(type solid)
			)
			(layer "B.SilkS")
		)
		(fp_line
			(start 1 1.497)
			(end -1 1.5)
			(stroke
				(width 0.15)
				(type solid)
			)
			(layer "B.SilkS")
		)
		(fp_line
			(start 1 -1.55)
			(end 1 -1.4)
			(stroke
				(width 0.15)
				(type solid)
			)
			(layer "B.SilkS")
		)
		(fp_line
			(start 1 -1.55)
			(end -1 -1.55)
			(stroke
				(width 0.15)
				(type solid)
			)
			(layer "B.SilkS")
		)
		(fp_line
			(start -1 1.5)
			(end -1 1.375)
			(stroke
				(width 0.15)
				(type solid)
			)
			(layer "B.SilkS")
		)
		(fp_line
			(start -1 -1.55)
			(end -1 -1.4)
			(stroke
				(width 0.15)
				(type solid)
			)
			(layer "B.SilkS")
		)
		(fp_circle
			(center -1.44 1.5)
			(end -1.39 1.5)
			(stroke
				(width 0.15)
				(type solid)
			)
			(fill yes)
			(layer "B.SilkS")
		)
		(fp_poly
			(pts
				(xy 1.930001 1.7) (xy 1.930001 -1.7) (xy -1.930001 -1.7) (xy -1.930001 1.7)
			)
			(stroke
				(width 0.05)
				(type solid)
			)
			(fill no)
			(layer "B.CrtYd")
		)
		(fp_line
			(start -0.45 1.520999)
			(end -0.876001 1.096)
			(stroke
				(width 0.15)
				(type solid)
			)
			(layer "B.Fab")
		)
		(fp_poly
			(pts
				(xy 0.875 -1.528) (xy 0.875 1.525) (xy -0.875 1.525) (xy -0.875 -1.528)
			)
			(stroke
				(width 0.15)
				(type solid)
			)
			(fill no)
			(layer "B.Fab")
		)
		(fp_text user "License: Apache-2.0"
			(at -1.93 -6.199 0)
			(layer "B.Fab")
			(effects
				(font
					(size 0.7 0.7)
					(thickness 0.15)
				)
				(justify left bottom mirror)
			)
		)
		(fp_text user "${REFERENCE}"
			(at -1.93 -3.8 0)
			(layer "B.Fab")
			(effects
				(font
					(size 0.7 0.7)
					(thickness 0.15)
				)
				(justify left bottom mirror)
			)
		)
		(fp_text user "Author: Antmicro"
			(at -1.93 -5 0)
			(layer "B.Fab")
			(effects
				(font
					(size 0.7 0.7)
					(thickness 0.15)
				)
				(justify left bottom mirror)
			)
		)
		(pad "1" smd rect
			(at -1.301 0.947 270)
			(size 0.7 1.2)
			(layers "B.Cu" "B.Mask" "B.Paste")
			(net 8 "/CSI/CSIB_3V3")
			(pinfunction "OUT")
			(pintype "power_out")
		)
		(pad "2" smd rect
			(at -1.300999 -0.004 270)
			(size 0.7 1.2)
			(layers "B.Cu" "B.Mask" "B.Paste")
			(net 1 "GND")
			(pinfunction "GND")
			(pintype "power_in")
		)
		(pad "3" smd rect
			(at -1.301 -0.954 270)
			(size 0.7 1.2)
			(layers "B.Cu" "B.Mask" "B.Paste")
			(net 117 "/CSI/CAM_CTRL.CSIB_FLG")
			(pinfunction "FLG")
			(pintype "output")
		)
		(pad "4" smd rect
			(at 1.299 -0.954 270)
			(size 0.7 1.2)
			(layers "B.Cu" "B.Mask" "B.Paste")
			(net 123 "/CSI/CAM_CTRL.CSIB_PEN")
			(pinfunction "EN")
			(pintype "input")
		)
		(pad "5" smd rect
			(at 1.299 -0.004 270)
			(size 0.7 1.2)
			(layers "B.Cu" "B.Mask" "B.Paste")
			(net 998 "/CSI/CSIB_3V3_ISET")
			(pinfunction "ISET")
			(pintype "passive")
		)
		(pad "6" smd rect
			(at 1.299 0.947 270)
			(size 0.7 1.2)
			(layers "B.Cu" "B.Mask" "B.Paste")
			(net 2 "+3V3")
			(pinfunction "IN")
			(pintype "power_in")
		)
	)
	(footprint "antmicro-footprints:R_0402_1005Metric"
		(layer "B.Cu")
		(at 223 107.4)
		(descr "Resistor SMD 0402")
		(tags "resistor SMD 0402")
		(property "Reference" "R338"
			(at -1.5 -1.4 0)
			(layer "B.SilkS")
			(effects
				(font
					(size 0.7 0.7)
					(thickness 0.15)
				)
				(justify right top mirror)
			)
		)
		(property "Value" "R_10k_0402"
			(at -1.011843 -1.772047 0)
			(layer "B.Fab")
			(effects
				(font
					(size 0.7 0.7)
					(thickness 0.15)
				)
				(justify right top mirror)
			)
		)
		(property "Datasheet" "https://www.bourns.com/docs/product-datasheets/cr.pdf"
			(at 0 0 0)
			(layer "B.Fab")
			(hide yes)
			(effects
				(font
					(size 1.27 1.27)
					(thickness 0.15)
				)
				(justify mirror)
			)
		)
		(property "Description" "SMD Chip Resistor, 10 kohm, ± 1%, 62.5 mW, 0402 [1005 Metric], Thick Film, General Purpose"
			(at 0 0 0)
			(layer "B.Fab")
			(hide yes)
			(effects
				(font
					(size 1.27 1.27)
					(thickness 0.15)
				)
				(justify mirror)
			)
		)
		(property "Manufacturer" "Bourns"
			(at 0 0 180)
			(unlocked yes)
			(layer "B.Fab")
			(hide yes)
			(effects
				(font
					(size 1 1)
					(thickness 0.15)
				)
				(justify mirror)
			)
		)
		(property "MPN" "CR0402-FX-1002GLF"
			(at 0 0 180)
			(unlocked yes)
			(layer "B.Fab")
			(hide yes)
			(effects
				(font
					(size 1 1)
					(thickness 0.15)
				)
				(justify mirror)
			)
		)
		(property "Val" "10k"
			(at 0 0 180)
			(unlocked yes)
			(layer "B.Fab")
			(hide yes)
			(effects
				(font
					(size 1 1)
					(thickness 0.15)
				)
				(justify mirror)
			)
		)
		(property "License" "Apache-2.0"
			(at 0 0 180)
			(unlocked yes)
			(layer "B.Fab")
			(hide yes)
			(effects
				(font
					(size 1 1)
					(thickness 0.15)
				)
				(justify mirror)
			)
		)
		(property "Author" "Antmicro"
			(at 0 0 180)
			(unlocked yes)
			(layer "B.Fab")
			(hide yes)
			(effects
				(font
					(size 1 1)
					(thickness 0.15)
				)
				(justify mirror)
			)
		)
		(property "Tolerance" "1%"
			(at 0 0 180)
			(unlocked yes)
			(layer "B.Fab")
			(hide yes)
			(effects
				(font
					(size 1 1)
					(thickness 0.15)
				)
				(justify mirror)
			)
		)
		(sheetname "/Recovery USB/")
		(sheetfile "recovery_usb.kicad_sch")
		(attr smd)
		(fp_rect
			(start -0.925 0.47)
			(end 0.925 -0.47)
			(stroke
				(width 0.05)
				(type default)
			)
			(fill no)
			(layer "B.CrtYd")
		)
		(fp_rect
			(start -0.5 0.25)
			(end 0.5 -0.25)
			(stroke
				(width 0.15)
				(type solid)
			)
			(fill no)
			(layer "B.Fab")
		)
		(fp_text user "${REFERENCE}"
			(at -0.95 -3.168 0)
			(layer "B.Fab")
			(effects
				(font
					(size 0.7 0.7)
					(thickness 0.15)
				)
				(justify right top mirror)
			)
		)
		(fp_text user "License: Apache-2.0"
			(at -0.95 -5.169 0)
			(layer "B.Fab")
			(effects
				(font
					(size 0.7 0.7)
					(thickness 0.15)
				)
				(justify right top mirror)
			)
		)
		(fp_text user "Author: Antmicro"
			(at -0.95 -4.169 0)
			(layer "B.Fab")
			(effects
				(font
					(size 0.7 0.7)
					(thickness 0.15)
				)
				(justify right top mirror)
			)
		)
		(pad "1" smd roundrect
			(at -0.48 0)
			(size 0.59 0.64)
			(layers "B.Cu" "B.Mask" "B.Paste")
			(roundrect_rratio 0.25)
			(net 2 "+3V3")
			(pintype "passive")
		)
		(pad "2" smd roundrect
			(at 0.48 0)
			(size 0.59 0.64)
			(layers "B.Cu" "B.Mask" "B.Paste")
			(roundrect_rratio 0.25)
			(net 1018 "/Recovery USB/USBC2_VBUS_DET")
			(pintype "passive")
		)
	)
	(footprint "antmicro-footprints:R_0402_1005Metric"
		(layer "B.Cu")
		(at 208.726 148)
		(descr "Resistor SMD 0402")
		(tags "resistor SMD 0402")
		(property "Reference" "R189"
			(at 0.9 -0.3 0)
			(layer "B.SilkS")
			(effects
				(font
					(size 0.7 0.7)
					(thickness 0.15)
				)
				(justify right top mirror)
			)
		)
		(property "Value" "R_1k_0402"
			(at -1.011843 -1.772047 0)
			(layer "B.Fab")
			(effects
				(font
					(size 0.7 0.7)
					(thickness 0.15)
				)
				(justify right top mirror)
			)
		)
		(property "Datasheet" "https://www.bourns.com/docs/product-datasheets/cr.pdf"
			(at 0 0 0)
			(layer "B.Fab")
			(hide yes)
			(effects
				(font
					(size 1.27 1.27)
					(thickness 0.15)
				)
				(justify mirror)
			)
		)
		(property "Description" "SMD Chip Resistor, 1 kohm, ± 1%, 63 mW, 0402 [1005 Metric], Thick Film, General Purpose"
			(at 0 0 0)
			(layer "B.Fab")
			(hide yes)
			(effects
				(font
					(size 1.27 1.27)
					(thickness 0.15)
				)
				(justify mirror)
			)
		)
		(property "MPN" "CR0402-FX-1001GLF"
			(at 0 0 180)
			(unlocked yes)
			(layer "B.Fab")
			(hide yes)
			(effects
				(font
					(size 1 1)
					(thickness 0.15)
				)
				(justify mirror)
			)
		)
		(property "Manufacturer" "Bourns"
			(at 0 0 180)
			(unlocked yes)
			(layer "B.Fab")
			(hide yes)
			(effects
				(font
					(size 1 1)
					(thickness 0.15)
				)
				(justify mirror)
			)
		)
		(property "License" "Apache-2.0"
			(at 0 0 180)
			(unlocked yes)
			(layer "B.Fab")
			(hide yes)
			(effects
				(font
					(size 1 1)
					(thickness 0.15)
				)
				(justify mirror)
			)
		)
		(property "Author" "Antmicro"
			(at 0 0 180)
			(unlocked yes)
			(layer "B.Fab")
			(hide yes)
			(effects
				(font
					(size 1 1)
					(thickness 0.15)
				)
				(justify mirror)
			)
		)
		(property "Val" "1k"
			(at 0 0 180)
			(unlocked yes)
			(layer "B.Fab")
			(hide yes)
			(effects
				(font
					(size 1 1)
					(thickness 0.15)
				)
				(justify mirror)
			)
		)
		(property "Tolerance" "1%"
			(at 0 0 180)
			(unlocked yes)
			(layer "B.Fab")
			(hide yes)
			(effects
				(font
					(size 1 1)
					(thickness 0.15)
				)
				(justify mirror)
			)
		)
		(sheetname "/SFP/")
		(sheetfile "sfp.kicad_sch")
		(attr smd)
		(fp_rect
			(start -0.925 0.47)
			(end 0.925 -0.47)
			(stroke
				(width 0.05)
				(type default)
			)
			(fill no)
			(layer "B.CrtYd")
		)
		(fp_rect
			(start -0.5 0.25)
			(end 0.5 -0.25)
			(stroke
				(width 0.15)
				(type solid)
			)
			(fill no)
			(layer "B.Fab")
		)
		(fp_text user "${REFERENCE}"
			(at -0.95 -3.168 0)
			(layer "B.Fab")
			(effects
				(font
					(size 0.7 0.7)
					(thickness 0.15)
				)
				(justify right top mirror)
			)
		)
		(fp_text user "Author: Antmicro"
			(at -0.95 -4.169 0)
			(layer "B.Fab")
			(effects
				(font
					(size 0.7 0.7)
					(thickness 0.15)
				)
				(justify right top mirror)
			)
		)
		(fp_text user "License: Apache-2.0"
			(at -0.95 -5.169 0)
			(layer "B.Fab")
			(effects
				(font
					(size 0.7 0.7)
					(thickness 0.15)
				)
				(justify right top mirror)
			)
		)
		(pad "1" smd roundrect
			(at -0.48 0)
			(size 0.59 0.64)
			(layers "B.Cu" "B.Mask" "B.Paste")
			(roundrect_rratio 0.25)
			(net 1371 "Net-(J12-TX_{FAULT})")
			(pintype "passive")
		)
		(pad "2" smd roundrect
			(at 0.48 0)
			(size 0.59 0.64)
			(layers "B.Cu" "B.Mask" "B.Paste")
			(roundrect_rratio 0.25)
			(net 2 "+3V3")
			(pintype "passive")
		)
	)
	(footprint "antmicro-footprints:TP_SMD_0.75mm"
		(layer "B.Cu")
		(at 142.65 70 -90)
		(property "Reference" "TP80"
			(at 0.3 -3.25 0)
			(layer "B.SilkS")
			(effects
				(font
					(size 0.7 0.7)
					(thickness 0.15)
				)
				(justify left bottom mirror)
			)
		)
		(property "Value" "TP_0.75mm_SMD"
			(at 0 -1.2 90)
			(layer "B.Fab")
			(effects
				(font
					(size 0.7 0.7)
					(thickness 0.15)
				)
				(justify left bottom mirror)
			)
		)
		(property "Description" "SMT test point"
			(at 0 0 90)
			(layer "B.Fab")
			(hide yes)
			(effects
				(font
					(size 1.27 1.27)
					(thickness 0.15)
				)
				(justify mirror)
			)
		)
		(property "MPN" ""
			(at 0 0 90)
			(unlocked yes)
			(layer "B.Fab")
			(hide yes)
			(effects
				(font
					(size 1 1)
					(thickness 0.15)
				)
				(justify mirror)
			)
		)
		(property "Manufacturer" ""
			(at 0 0 90)
			(unlocked yes)
			(layer "B.Fab")
			(hide yes)
			(effects
				(font
					(size 1 1)
					(thickness 0.15)
				)
				(justify mirror)
			)
		)
		(property "Author" "Antmicro"
			(at 0 0 90)
			(unlocked yes)
			(layer "B.Fab")
			(hide yes)
			(effects
				(font
					(size 1 1)
					(thickness 0.15)
				)
				(justify mirror)
			)
		)
		(property "License" "Apache-2.0"
			(at 0 0 90)
			(unlocked yes)
			(layer "B.Fab")
			(hide yes)
			(effects
				(font
					(size 1 1)
					(thickness 0.15)
				)
				(justify mirror)
			)
		)
		(sheetname "/SoM_Power/")
		(sheetfile "som_power.kicad_sch")
		(attr exclude_from_pos_files exclude_from_bom)
		(fp_circle
			(center 0 0)
			(end 0.475 0)
			(stroke
				(width 0.05)
				(type default)
			)
			(fill no)
			(layer "B.CrtYd")
		)
		(fp_text user "Author: Antmicro"
			(at -0.4 -3.901 90)
			(layer "B.Fab")
			(effects
				(font
					(size 0.7 0.7)
					(thickness 0.15)
				)
				(justify left bottom mirror)
			)
		)
		(fp_text user "License: Apache-2.0"
			(at -0.4 -5.101 90)
			(layer "B.Fab")
			(effects
				(font
					(size 0.7 0.7)
					(thickness 0.15)
				)
				(justify left bottom mirror)
			)
		)
		(fp_text user "${REFERENCE}"
			(at -0.4 -2.7 90)
			(layer "B.Fab")
			(effects
				(font
					(size 0.7 0.7)
					(thickness 0.15)
				)
				(justify left bottom mirror)
			)
		)
		(pad "1" smd circle
			(at 0 0 270)
			(size 0.75 0.75)
			(layers "B.Cu" "B.Mask")
			(net 85 "/SoM_Power/~{SOM_POWER_BTN}")
			(pinfunction "1")
			(pintype "passive")
		)
	)
	(footprint "antmicro-footprints:Mech_Lightpipe_Bivar_SLP3-150-150-F"
		(locked yes)
		(layer "B.Cu")
		(at 232.829 59.489999 -90)
		(property "Reference" "H15"
			(at 0 1.6 90)
			(unlocked yes)
			(layer "B.SilkS")
			(effects
				(font
					(size 0.7 0.7)
					(thickness 0.15)
				)
				(justify left bottom mirror)
			)
		)
		(property "Value" "Lightpipe_Bivar_SLP3-150-150-F"
			(at 0 -6.6 90)
			(unlocked yes)
			(layer "B.Fab")
			(effects
				(font
					(size 0.7 0.7)
					(thickness 0.15)
				)
				(justify left bottom mirror)
			)
		)
		(property "Datasheet" "https://eu.mouser.com/datasheet/2/50/Bivar_SLP3_150_XXX_X_N-3318840.pdf"
			(at 0 0 90)
			(layer "B.Fab")
			(hide yes)
			(effects
				(font
					(size 1.27 1.27)
					(thickness 0.15)
				)
				(justify mirror)
			)
		)
		(property "Description" "LED Light Pipe, Rigid Board, Horizontal"
			(at 0 0 90)
			(layer "B.Fab")
			(hide yes)
			(effects
				(font
					(size 1.27 1.27)
					(thickness 0.15)
				)
				(justify mirror)
			)
		)
		(property "Manufacturer" "BIVAR"
			(at 0 0 90)
			(unlocked yes)
			(layer "B.Fab")
			(hide yes)
			(effects
				(font
					(size 1 1)
					(thickness 0.15)
				)
				(justify mirror)
			)
		)
		(property "MPN" "SLP3-150-150-F"
			(at 0 0 90)
			(unlocked yes)
			(layer "B.Fab")
			(hide yes)
			(effects
				(font
					(size 1 1)
					(thickness 0.15)
				)
				(justify mirror)
			)
		)
		(property "Author" "Antmicro"
			(at 0 0 90)
			(unlocked yes)
			(layer "B.Fab")
			(hide yes)
			(effects
				(font
					(size 1 1)
					(thickness 0.15)
				)
				(justify mirror)
			)
		)
		(property "License" "Apache-2.0"
			(at 0 0 90)
			(unlocked yes)
			(layer "B.Fab")
			(hide yes)
			(effects
				(font
					(size 1 1)
					(thickness 0.15)
				)
				(justify mirror)
			)
		)
		(sheetname "/Power/")
		(sheetfile "power.kicad_sch")
		(attr through_hole)
		(fp_poly
			(pts
				(xy -1.04 1.225) (xy 3.559 1.225) (xy 3.559 -5.326) (xy -1.04 -5.326)
			)
			(stroke
				(width 0.15)
				(type solid)
			)
			(fill no)
			(layer "B.SilkS")
		)
		(fp_poly
			(pts
				(xy -1.301 1.504001) (xy 3.819 1.504) (xy 3.819 -1.196) (xy -1.301 -1.196)
			)
			(stroke
				(width 0.05)
				(type solid)
			)
			(fill no)
			(layer "B.CrtYd")
		)
		(fp_poly
			(pts
				(xy -1.3 -4.196) (xy 3.819 -4.196) (xy 3.819 -5.596) (xy -1.3 -5.596)
			)
			(stroke
				(width 0.05)
				(type solid)
			)
			(fill no)
			(layer "B.CrtYd")
		)
		(fp_line
			(start 1.25 -1.8)
			(end 1.25 -2.499999)
			(stroke
				(width 0.15)
				(type solid)
			)
			(layer "B.Fab")
		)
		(fp_line
			(start 1.25 -2.499999)
			(end 1.95 -2.5)
			(stroke
				(width 0.15)
				(type solid)
			)
			(layer "B.Fab")
		)
		(fp_line
			(start 1.25 -2.499999)
			(end 1.25 -3.201)
			(stroke
				(width 0.15)
				(type solid)
			)
			(layer "B.Fab")
		)
		(fp_line
			(start 0.55 -2.5)
			(end 1.25 -2.499999)
			(stroke
				(width 0.15)
				(type solid)
			)
			(layer "B.Fab")
		)
		(fp_poly
			(pts
				(xy -0.791 -1.375999) (xy 3.309 -1.376) (xy 3.309 -3.625) (xy -0.791 -3.625001)
			)
			(stroke
				(width 0.15)
				(type solid)
			)
			(fill no)
			(layer "B.Fab")
		)
		(fp_text user "License: Apache-2.0"
			(at -7.21 -24.37 90)
			(layer "B.Fab")
			(effects
				(font
					(size 0.7 0.7)
					(thickness 0.15)
				)
				(justify left bottom mirror)
			)
		)
		(fp_text user "Author: Antmicro"
			(at -7.209999 -25.57 90)
			(layer "B.Fab")
			(effects
				(font
					(size 0.7 0.7)
					(thickness 0.15)
				)
				(justify left bottom mirror)
			)
		)
		(fp_text user "${REFERENCE}"
			(at -7.21 -23.17 90)
			(unlocked yes)
			(layer "B.Fab")
			(effects
				(font
					(size 0.7 0.7)
					(thickness 0.15)
				)
				(justify left bottom mirror)
			)
		)
		(pad "" np_thru_hole circle
			(at 0 0 270)
			(size 1.2 1.2)
			(drill 1.3)
			(layers "*.Cu" "*.Mask")
		)
		(pad "" np_thru_hole circle
			(at 2.5 0 270)
			(size 1.2 1.2)
			(drill 1.3)
			(layers "*.Cu" "*.Mask")
		)
	)
	(footprint "antmicro-footprints:C_0402_1005Metric"
		(layer "B.Cu")
		(at 235.57 77.51)
		(descr "Capacitor SMD 0402")
		(tags "capacitor SMD 0402")
		(property "Reference" "C152"
			(at -3.7 -0.32 0)
			(layer "B.SilkS")
			(effects
				(font
					(size 0.7 0.7)
					(thickness 0.15)
				)
				(justify right top mirror)
			)
		)
		(property "Value" "C_100n_0402"
			(at -1.022927 -2.155213 0)
			(layer "B.Fab")
			(effects
				(font
					(size 0.7 0.7)
					(thickness 0.15)
				)
				(justify right top mirror)
			)
		)
		(property "Datasheet" "https://www.murata.com/products/productdetail?partno=GRM155R61H104KE14%23"
			(at 0 0 0)
			(layer "B.Fab")
			(hide yes)
			(effects
				(font
					(size 1.27 1.27)
					(thickness 0.15)
				)
				(justify mirror)
			)
		)
		(property "Description" "SMD Multilayer Ceramic Capacitor, 0.1 µF, 50 V, 0402 [1005 Metric], ± 10%, X5R, GRM Series"
			(at 0 0 0)
			(layer "B.Fab")
			(hide yes)
			(effects
				(font
					(size 1.27 1.27)
					(thickness 0.15)
				)
				(justify mirror)
			)
		)
		(property "MPN" "GRM155R61H104KE14D"
			(at 0 0 180)
			(unlocked yes)
			(layer "B.Fab")
			(hide yes)
			(effects
				(font
					(size 1 1)
					(thickness 0.15)
				)
				(justify mirror)
			)
		)
		(property "Manufacturer" "Murata"
			(at 0 0 180)
			(unlocked yes)
			(layer "B.Fab")
			(hide yes)
			(effects
				(font
					(size 1 1)
					(thickness 0.15)
				)
				(justify mirror)
			)
		)
		(property "Val" "100n"
			(at 0 0 180)
			(unlocked yes)
			(layer "B.Fab")
			(hide yes)
			(effects
				(font
					(size 1 1)
					(thickness 0.15)
				)
				(justify mirror)
			)
		)
		(property "License" "Apache-2.0"
			(at 0 0 180)
			(unlocked yes)
			(layer "B.Fab")
			(hide yes)
			(effects
				(font
					(size 1 1)
					(thickness 0.15)
				)
				(justify mirror)
			)
		)
		(property "Author" "Antmicro"
			(at 0 0 180)
			(unlocked yes)
			(layer "B.Fab")
			(hide yes)
			(effects
				(font
					(size 1 1)
					(thickness 0.15)
				)
				(justify mirror)
			)
		)
		(property "Voltage" "50V"
			(at 0 0 180)
			(unlocked yes)
			(layer "B.Fab")
			(hide yes)
			(effects
				(font
					(size 1 1)
					(thickness 0.15)
				)
				(justify mirror)
			)
		)
		(property "Dielectric" "X5R"
			(at 0 0 180)
			(unlocked yes)
			(layer "B.Fab")
			(hide yes)
			(effects
				(font
					(size 1 1)
					(thickness 0.15)
				)
				(justify mirror)
			)
		)
		(sheetname "/USB Debug, PD/")
		(sheetfile "usb_debug_pd.kicad_sch")
		(attr smd)
		(fp_rect
			(start -0.925 0.47)
			(end 0.925 -0.47)
			(stroke
				(width 0.05)
				(type default)
			)
			(fill no)
			(layer "B.CrtYd")
		)
		(fp_line
			(start -0.494 -0.248)
			(end -0.494 0.25)
			(stroke
				(width 0.15)
				(type solid)
			)
			(layer "B.Fab")
		)
		(fp_line
			(start -0.494 0.25)
			(end 0.504 0.25)
			(stroke
				(width 0.15)
				(type solid)
			)
			(layer "B.Fab")
		)
		(fp_line
			(start 0.504 -0.248)
			(end -0.494 -0.248)
			(stroke
				(width 0.15)
				(type solid)
			)
			(layer "B.Fab")
		)
		(fp_line
			(start 0.504 0.25)
			(end 0.504 -0.248)
			(stroke
				(width 0.15)
				(type solid)
			)
			(layer "B.Fab")
		)
		(fp_text user "Author: Antmicro"
			(at -0.939 -3.399 0)
			(layer "B.Fab")
			(effects
				(font
					(size 0.7 0.7)
					(thickness 0.15)
				)
				(justify right top mirror)
			)
		)
		(fp_text user "${REFERENCE}"
			(at -0.939 -4.599 0)
			(layer "B.Fab")
			(effects
				(font
					(size 0.7 0.7)
					(thickness 0.15)
				)
				(justify right top mirror)
			)
		)
		(fp_text user "License: Apache-2.0"
			(at -0.939 -5.799 0)
			(layer "B.Fab")
			(effects
				(font
					(size 0.7 0.7)
					(thickness 0.15)
				)
				(justify right top mirror)
			)
		)
		(pad "1" smd roundrect
			(at -0.48 0)
			(size 0.59 0.64)
			(layers "B.Cu" "B.Mask" "B.Paste")
			(roundrect_rratio 0.25)
			(net 176 "/USB Debug, PD/USBC0_VBUS")
			(pintype "passive")
		)
		(pad "2" smd roundrect
			(at 0.48 0)
			(size 0.59 0.64)
			(layers "B.Cu" "B.Mask" "B.Paste")
			(roundrect_rratio 0.25)
			(net 1 "GND")
			(pintype "passive")
		)
	)
	(footprint "antmicro-footprints:C_0402_1005Metric"
		(layer "B.Cu")
		(at 207.226 139.6)
		(descr "Capacitor SMD 0402")
		(tags "capacitor SMD 0402")
		(property "Reference" "C177"
			(at 1.1 -0.4 0)
			(layer "B.SilkS")
			(effects
				(font
					(size 0.7 0.7)
					(thickness 0.15)
				)
				(justify right top mirror)
			)
		)
		(property "Value" "C_100n_0402"
			(at -1.022927 -2.155213 0)
			(layer "B.Fab")
			(effects
				(font
					(size 0.7 0.7)
					(thickness 0.15)
				)
				(justify right top mirror)
			)
		)
		(property "Datasheet" "https://www.murata.com/products/productdetail?partno=GRM155R61H104KE14%23"
			(at 0 0 0)
			(layer "B.Fab")
			(hide yes)
			(effects
				(font
					(size 1.27 1.27)
					(thickness 0.15)
				)
				(justify mirror)
			)
		)
		(property "Description" "SMD Multilayer Ceramic Capacitor, 0.1 µF, 50 V, 0402 [1005 Metric], ± 10%, X5R, GRM Series"
			(at 0 0 0)
			(layer "B.Fab")
			(hide yes)
			(effects
				(font
					(size 1.27 1.27)
					(thickness 0.15)
				)
				(justify mirror)
			)
		)
		(property "MPN" "GRM155R61H104KE14D"
			(at 0 0 180)
			(unlocked yes)
			(layer "B.Fab")
			(hide yes)
			(effects
				(font
					(size 1 1)
					(thickness 0.15)
				)
				(justify mirror)
			)
		)
		(property "Manufacturer" "Murata"
			(at 0 0 180)
			(unlocked yes)
			(layer "B.Fab")
			(hide yes)
			(effects
				(font
					(size 1 1)
					(thickness 0.15)
				)
				(justify mirror)
			)
		)
		(property "License" "Apache-2.0"
			(at 0 0 180)
			(unlocked yes)
			(layer "B.Fab")
			(hide yes)
			(effects
				(font
					(size 1 1)
					(thickness 0.15)
				)
				(justify mirror)
			)
		)
		(property "Author" "Antmicro"
			(at 0 0 180)
			(unlocked yes)
			(layer "B.Fab")
			(hide yes)
			(effects
				(font
					(size 1 1)
					(thickness 0.15)
				)
				(justify mirror)
			)
		)
		(property "Val" "100n"
			(at 0 0 180)
			(unlocked yes)
			(layer "B.Fab")
			(hide yes)
			(effects
				(font
					(size 1 1)
					(thickness 0.15)
				)
				(justify mirror)
			)
		)
		(property "Voltage" "50V"
			(at 0 0 180)
			(unlocked yes)
			(layer "B.Fab")
			(hide yes)
			(effects
				(font
					(size 1 1)
					(thickness 0.15)
				)
				(justify mirror)
			)
		)
		(property "Dielectric" "X5R"
			(at 0 0 180)
			(unlocked yes)
			(layer "B.Fab")
			(hide yes)
			(effects
				(font
					(size 1 1)
					(thickness 0.15)
				)
				(justify mirror)
			)
		)
		(sheetname "/SFP/")
		(sheetfile "sfp.kicad_sch")
		(attr smd)
		(fp_rect
			(start -0.925 0.47)
			(end 0.925 -0.47)
			(stroke
				(width 0.05)
				(type default)
			)
			(fill no)
			(layer "B.CrtYd")
		)
		(fp_line
			(start -0.494 -0.248)
			(end -0.494 0.25)
			(stroke
				(width 0.15)
				(type solid)
			)
			(layer "B.Fab")
		)
		(fp_line
			(start -0.494 0.25)
			(end 0.504 0.25)
			(stroke
				(width 0.15)
				(type solid)
			)
			(layer "B.Fab")
		)
		(fp_line
			(start 0.504 -0.248)
			(end -0.494 -0.248)
			(stroke
				(width 0.15)
				(type solid)
			)
			(layer "B.Fab")
		)
		(fp_line
			(start 0.504 0.25)
			(end 0.504 -0.248)
			(stroke
				(width 0.15)
				(type solid)
			)
			(layer "B.Fab")
		)
		(fp_text user "Author: Antmicro"
			(at -0.939 -3.399 0)
			(layer "B.Fab")
			(effects
				(font
					(size 0.7 0.7)
					(thickness 0.15)
				)
				(justify right top mirror)
			)
		)
		(fp_text user "License: Apache-2.0"
			(at -0.939 -5.799 0)
			(layer "B.Fab")
			(effects
				(font
					(size 0.7 0.7)
					(thickness 0.15)
				)
				(justify right top mirror)
			)
		)
		(fp_text user "${REFERENCE}"
			(at -0.939 -4.599 0)
			(layer "B.Fab")
			(effects
				(font
					(size 0.7 0.7)
					(thickness 0.15)
				)
				(justify right top mirror)
			)
		)
		(pad "1" smd roundrect
			(at -0.48 0)
			(size 0.59 0.64)
			(layers "B.Cu" "B.Mask" "B.Paste")
			(roundrect_rratio 0.25)
			(net 1 "GND")
			(pintype "passive")
		)
		(pad "2" smd roundrect
			(at 0.48 0)
			(size 0.59 0.64)
			(layers "B.Cu" "B.Mask" "B.Paste")
			(roundrect_rratio 0.25)
			(net 379 "/SFP/SH")
			(pintype "passive")
		)
	)
	(footprint "antmicro-footprints:TP_SMD_0.75mm"
		(layer "B.Cu")
		(at 137 75.2 -45)
		(property "Reference" "TP106"
			(at 1.909188 0.494975 0)
			(layer "B.SilkS")
			(effects
				(font
					(size 0.7 0.7)
					(thickness 0.15)
				)
				(justify left bottom mirror)
			)
		)
		(property "Value" "TP_0.75mm_SMD"
			(at 0 -1.2 135)
			(layer "B.Fab")
			(effects
				(font
					(size 0.7 0.7)
					(thickness 0.15)
				)
				(justify left bottom mirror)
			)
		)
		(property "Description" "SMT test point"
			(at 0 0 135)
			(layer "B.Fab")
			(hide yes)
			(effects
				(font
					(size 1.27 1.27)
					(thickness 0.15)
				)
				(justify mirror)
			)
		)
		(property "MPN" ""
			(at 0 0 135)
			(unlocked yes)
			(layer "B.Fab")
			(hide yes)
			(effects
				(font
					(size 1 1)
					(thickness 0.15)
				)
				(justify mirror)
			)
		)
		(property "Manufacturer" ""
			(at 0 0 135)
			(unlocked yes)
			(layer "B.Fab")
			(hide yes)
			(effects
				(font
					(size 1 1)
					(thickness 0.15)
				)
				(justify mirror)
			)
		)
		(property "Author" "Antmicro"
			(at 0 0 135)
			(unlocked yes)
			(layer "B.Fab")
			(hide yes)
			(effects
				(font
					(size 1 1)
					(thickness 0.15)
				)
				(justify mirror)
			)
		)
		(property "License" "Apache-2.0"
			(at 0 0 135)
			(unlocked yes)
			(layer "B.Fab")
			(hide yes)
			(effects
				(font
					(size 1 1)
					(thickness 0.15)
				)
				(justify mirror)
			)
		)
		(sheetname "/SoM_IO/")
		(sheetfile "som_io.kicad_sch")
		(attr exclude_from_pos_files exclude_from_bom)
		(fp_circle
			(center 0 0)
			(end 0.475 0)
			(stroke
				(width 0.05)
				(type default)
			)
			(fill no)
			(layer "B.CrtYd")
		)
		(fp_text user "Author: Antmicro"
			(at -0.4 -3.901 135)
			(layer "B.Fab")
			(effects
				(font
					(size 0.7 0.7)
					(thickness 0.15)
				)
				(justify left bottom mirror)
			)
		)
		(fp_text user "License: Apache-2.0"
			(at -0.4 -5.101 135)
			(layer "B.Fab")
			(effects
				(font
					(size 0.7 0.7)
					(thickness 0.15)
				)
				(justify left bottom mirror)
			)
		)
		(fp_text user "${REFERENCE}"
			(at -0.4 -2.7 135)
			(layer "B.Fab")
			(effects
				(font
					(size 0.7 0.7)
					(thickness 0.15)
				)
				(justify left bottom mirror)
			)
		)
		(pad "1" smd circle
			(at 0 0 315)
			(size 0.75 0.75)
			(layers "B.Cu" "B.Mask")
			(net 243 "/SoM_IO/UART1.CTS")
			(pinfunction "1")
			(pintype "passive")
		)
	)
	(footprint "antmicro-footprints:R_0402_1005Metric"
		(layer "B.Cu")
		(at 157.14 65.5 180)
		(descr "Resistor SMD 0402")
		(tags "resistor SMD 0402")
		(property "Reference" "R294"
			(at -1.06 -4.3 0)
			(layer "B.SilkS")
			(effects
				(font
					(size 0.7 0.7)
					(thickness 0.15)
				)
				(justify left bottom mirror)
			)
		)
		(property "Value" "R_0R_0402"
			(at -1.011843 -1.772047 0)
			(layer "B.Fab")
			(effects
				(font
					(size 0.7 0.7)
					(thickness 0.15)
				)
				(justify left bottom mirror)
			)
		)
		(property "Datasheet" "https://industrial.panasonic.com/cdbs/www-data/pdf/RDA0000/AOA0000C301.pdf"
			(at 0 0 0)
			(layer "B.Fab")
			(hide yes)
			(effects
				(font
					(size 1.27 1.27)
					(thickness 0.15)
				)
				(justify mirror)
			)
		)
		(property "Description" "SMD Chip Resistor, Jumper, 0 ohm, 100 mW, 0402 [1005 Metric], Thick Film, General Purpose"
			(at 0 0 0)
			(layer "B.Fab")
			(hide yes)
			(effects
				(font
					(size 1.27 1.27)
					(thickness 0.15)
				)
				(justify mirror)
			)
		)
		(property "MPN" "ERJ2GE0R00X"
			(at 0 0 0)
			(unlocked yes)
			(layer "B.Fab")
			(hide yes)
			(effects
				(font
					(size 1 1)
					(thickness 0.15)
				)
				(justify mirror)
			)
		)
		(property "Manufacturer" "Panasonic"
			(at 0 0 0)
			(unlocked yes)
			(layer "B.Fab")
			(hide yes)
			(effects
				(font
					(size 1 1)
					(thickness 0.15)
				)
				(justify mirror)
			)
		)
		(property "License" "Apache-2.0"
			(at 0 0 0)
			(unlocked yes)
			(layer "B.Fab")
			(hide yes)
			(effects
				(font
					(size 1 1)
					(thickness 0.15)
				)
				(justify mirror)
			)
		)
		(property "Author" "Antmicro"
			(at 0 0 0)
			(unlocked yes)
			(layer "B.Fab")
			(hide yes)
			(effects
				(font
					(size 1 1)
					(thickness 0.15)
				)
				(justify mirror)
			)
		)
		(property "Val" "0R"
			(at 0 0 0)
			(unlocked yes)
			(layer "B.Fab")
			(hide yes)
			(effects
				(font
					(size 1 1)
					(thickness 0.15)
				)
				(justify mirror)
			)
		)
		(property "Tolerance" "~"
			(at 0 0 0)
			(unlocked yes)
			(layer "B.Fab")
			(hide yes)
			(effects
				(font
					(size 1 1)
					(thickness 0.15)
				)
				(justify mirror)
			)
		)
		(property "Current" "1A"
			(at 0 0 0)
			(unlocked yes)
			(layer "B.Fab")
			(hide yes)
			(effects
				(font
					(size 1 1)
					(thickness 0.15)
				)
				(justify mirror)
			)
		)
		(sheetname "/SoM_IO2/")
		(sheetfile "som_io2.kicad_sch")
		(attr smd exclude_from_pos_files exclude_from_bom dnp)
		(fp_rect
			(start -0.925 0.47)
			(end 0.925 -0.47)
			(stroke
				(width 0.05)
				(type default)
			)
			(fill no)
			(layer "B.CrtYd")
		)
		(fp_rect
			(start -0.5 0.25)
			(end 0.5 -0.25)
			(stroke
				(width 0.15)
				(type solid)
			)
			(fill no)
			(layer "B.Fab")
		)
		(fp_text user "License: Apache-2.0"
			(at -0.95 -5.169 0)
			(layer "B.Fab")
			(effects
				(font
					(size 0.7 0.7)
					(thickness 0.15)
				)
				(justify left bottom mirror)
			)
		)
		(fp_text user "${REFERENCE}"
			(at -0.95 -3.168 0)
			(layer "B.Fab")
			(effects
				(font
					(size 0.7 0.7)
					(thickness 0.15)
				)
				(justify left bottom mirror)
			)
		)
		(fp_text user "Author: Antmicro"
			(at -0.95 -4.169 0)
			(layer "B.Fab")
			(effects
				(font
					(size 0.7 0.7)
					(thickness 0.15)
				)
				(justify left bottom mirror)
			)
		)
		(pad "1" smd roundrect
			(at -0.48 0 180)
			(size 0.59 0.64)
			(layers "B.Cu" "B.Mask" "B.Paste")
			(roundrect_rratio 0.25)
			(net 1030 "Net-(U59-B1Y)")
			(pintype "passive")
		)
		(pad "2" smd roundrect
			(at 0.48 0 180)
			(size 0.59 0.64)
			(layers "B.Cu" "B.Mask" "B.Paste")
			(roundrect_rratio 0.25)
			(net 706 "/SoM_IO2/JTAG_TMS")
			(pintype "passive")
		)
	)
	(footprint "antmicro-footprints:R_0402_1005Metric"
		(layer "B.Cu")
		(at 71.1 67.3)
		(descr "Resistor SMD 0402")
		(tags "resistor SMD 0402")
		(property "Reference" "R395"
			(at 0.9 -0.3 0)
			(layer "B.SilkS")
			(effects
				(font
					(size 0.7 0.7)
					(thickness 0.15)
				)
				(justify right top mirror)
			)
		)
		(property "Value" "R_0R_0402"
			(at -1.011843 -1.772047 0)
			(layer "B.Fab")
			(effects
				(font
					(size 0.7 0.7)
					(thickness 0.15)
				)
				(justify right top mirror)
			)
		)
		(property "Datasheet" "https://industrial.panasonic.com/cdbs/www-data/pdf/RDA0000/AOA0000C301.pdf"
			(at 0 0 0)
			(layer "B.Fab")
			(hide yes)
			(effects
				(font
					(size 1.27 1.27)
					(thickness 0.15)
				)
				(justify mirror)
			)
		)
		(property "Description" "SMD Chip Resistor, Jumper, 0 ohm, 100 mW, 0402 [1005 Metric], Thick Film, General Purpose"
			(at 0 0 0)
			(layer "B.Fab")
			(hide yes)
			(effects
				(font
					(size 1.27 1.27)
					(thickness 0.15)
				)
				(justify mirror)
			)
		)
		(property "MPN" "ERJ2GE0R00X"
			(at 0 0 180)
			(unlocked yes)
			(layer "B.Fab")
			(hide yes)
			(effects
				(font
					(size 1 1)
					(thickness 0.15)
				)
				(justify mirror)
			)
		)
		(property "Manufacturer" "Panasonic"
			(at 0 0 180)
			(unlocked yes)
			(layer "B.Fab")
			(hide yes)
			(effects
				(font
					(size 1 1)
					(thickness 0.15)
				)
				(justify mirror)
			)
		)
		(property "License" "Apache-2.0"
			(at 0 0 180)
			(unlocked yes)
			(layer "B.Fab")
			(hide yes)
			(effects
				(font
					(size 1 1)
					(thickness 0.15)
				)
				(justify mirror)
			)
		)
		(property "Author" "Antmicro"
			(at 0 0 180)
			(unlocked yes)
			(layer "B.Fab")
			(hide yes)
			(effects
				(font
					(size 1 1)
					(thickness 0.15)
				)
				(justify mirror)
			)
		)
		(property "Val" "0R"
			(at 0 0 180)
			(unlocked yes)
			(layer "B.Fab")
			(hide yes)
			(effects
				(font
					(size 1 1)
					(thickness 0.15)
				)
				(justify mirror)
			)
		)
		(property "Tolerance" "~"
			(at 0 0 180)
			(unlocked yes)
			(layer "B.Fab")
			(hide yes)
			(effects
				(font
					(size 1 1)
					(thickness 0.15)
				)
				(justify mirror)
			)
		)
		(property "Current" "1A"
			(at 0 0 180)
			(unlocked yes)
			(layer "B.Fab")
			(hide yes)
			(effects
				(font
					(size 1 1)
					(thickness 0.15)
				)
				(justify mirror)
			)
		)
		(sheetname "/CSI/")
		(sheetfile "csi.kicad_sch")
		(attr smd)
		(fp_rect
			(start -0.925 0.47)
			(end 0.925 -0.47)
			(stroke
				(width 0.05)
				(type default)
			)
			(fill no)
			(layer "B.CrtYd")
		)
		(fp_rect
			(start -0.5 0.25)
			(end 0.5 -0.25)
			(stroke
				(width 0.15)
				(type solid)
			)
			(fill no)
			(layer "B.Fab")
		)
		(fp_text user "${REFERENCE}"
			(at -0.95 -3.168 0)
			(layer "B.Fab")
			(effects
				(font
					(size 0.7 0.7)
					(thickness 0.15)
				)
				(justify right top mirror)
			)
		)
		(fp_text user "License: Apache-2.0"
			(at -0.95 -5.169 0)
			(layer "B.Fab")
			(effects
				(font
					(size 0.7 0.7)
					(thickness 0.15)
				)
				(justify right top mirror)
			)
		)
		(fp_text user "Author: Antmicro"
			(at -0.95 -4.169 0)
			(layer "B.Fab")
			(effects
				(font
					(size 0.7 0.7)
					(thickness 0.15)
				)
				(justify right top mirror)
			)
		)
		(pad "1" smd roundrect
			(at -0.48 0)
			(size 0.59 0.64)
			(layers "B.Cu" "B.Mask" "B.Paste")
			(roundrect_rratio 0.25)
			(net 993 "/CSI/SDA_CAM2")
			(pintype "passive")
		)
		(pad "2" smd roundrect
			(at 0.48 0)
			(size 0.59 0.64)
			(layers "B.Cu" "B.Mask" "B.Paste")
			(roundrect_rratio 0.25)
			(net 1373 "Net-(J10-Pad39)")
			(pintype "passive")
		)
	)
	(footprint "antmicro-footprints:C_0603_1608Metric_EIA"
		(layer "B.Cu")
		(at 124.6 113.5)
		(descr "Capacitor SMD 0603, IPC-7351 Density Level A")
		(tags "Capacitor 0603")
		(property "Reference" "C191"
			(at 1.2 -1.9 0)
			(layer "B.SilkS")
			(effects
				(font
					(size 0.7 0.7)
					(thickness 0.15)
				)
				(justify right top mirror)
			)
		)
		(property "Value" "C_22u_16V_0603"
			(at -1.42757 -1.770288 0)
			(layer "B.Fab")
			(effects
				(font
					(size 0.7 0.7)
					(thickness 0.15)
				)
				(justify right top mirror)
			)
		)
		(property "Datasheet" "https://product.samsungsem.com/mlcc/CL10A226MO7JZN.do"
			(at 0 0 0)
			(layer "B.Fab")
			(hide yes)
			(effects
				(font
					(size 1.27 1.27)
					(thickness 0.15)
				)
				(justify mirror)
			)
		)
		(property "Description" "SMD Multilayer Ceramic Capacitor"
			(at 0 0 0)
			(layer "B.Fab")
			(hide yes)
			(effects
				(font
					(size 1.27 1.27)
					(thickness 0.15)
				)
				(justify mirror)
			)
		)
		(property "Manufacturer" "Samsung Electro-Mechanics"
			(at 0 0 0)
			(unlocked yes)
			(layer "B.Fab")
			(hide yes)
			(effects
				(font
					(size 1 1)
					(thickness 0.15)
				)
				(justify mirror)
			)
		)
		(property "MPN" "CL10A226MO7JZNC"
			(at 0 0 0)
			(unlocked yes)
			(layer "B.Fab")
			(hide yes)
			(effects
				(font
					(size 1 1)
					(thickness 0.15)
				)
				(justify mirror)
			)
		)
		(property "Val" "22u"
			(at 0 0 0)
			(unlocked yes)
			(layer "B.Fab")
			(hide yes)
			(effects
				(font
					(size 1 1)
					(thickness 0.15)
				)
				(justify mirror)
			)
		)
		(property "License" "Apache-2.0"
			(at 0 0 0)
			(unlocked yes)
			(layer "B.Fab")
			(hide yes)
			(effects
				(font
					(size 1 1)
					(thickness 0.15)
				)
				(justify mirror)
			)
		)
		(property "Author" "Antmicro"
			(at 0 0 0)
			(unlocked yes)
			(layer "B.Fab")
			(hide yes)
			(effects
				(font
					(size 1 1)
					(thickness 0.15)
				)
				(justify mirror)
			)
		)
		(property "Voltage" "16V"
			(at 0 0 0)
			(unlocked yes)
			(layer "B.Fab")
			(hide yes)
			(effects
				(font
					(size 1 1)
					(thickness 0.15)
				)
				(justify mirror)
			)
		)
		(property "Dielectric" "template_dielectric"
			(at 0 0 0)
			(unlocked yes)
			(layer "B.Fab")
			(hide yes)
			(effects
				(font
					(size 1 1)
					(thickness 0.15)
				)
				(justify mirror)
			)
		)
		(sheetname "/M.2/")
		(sheetfile "m2.kicad_sch")
		(attr smd)
		(fp_line
			(start -0.15 -0.55)
			(end 0.15 -0.55)
			(stroke
				(width 0.15)
				(type solid)
			)
			(layer "B.SilkS")
		)
		(fp_line
			(start -0.15 0.55)
			(end 0.15 0.55)
			(stroke
				(width 0.15)
				(type solid)
			)
			(layer "B.SilkS")
		)
		(fp_poly
			(pts
				(xy -1.25 0.65) (xy -1.25 -0.65) (xy 1.25 -0.65) (xy 1.25 0.65)
			)
			(stroke
				(width 0.05)
				(type solid)
			)
			(fill no)
			(layer "B.CrtYd")
		)
		(fp_poly
			(pts
				(xy -0.799999 0.45) (xy -0.799999 -0.45) (xy 0.799999 -0.45) (xy 0.799999 0.45)
			)
			(stroke
				(width 0.15)
				(type solid)
			)
			(fill no)
			(layer "B.Fab")
		)
		(fp_text user "Author: Antmicro"
			(at -1.682 -4.894 0)
			(layer "B.Fab")
			(effects
				(font
					(size 0.7 0.7)
					(thickness 0.15)
				)
				(justify right top mirror)
			)
		)
		(fp_text user "${REFERENCE}"
			(at -1.682001 -3.895 0)
			(layer "B.Fab")
			(effects
				(font
					(size 0.7 0.7)
					(thickness 0.15)
				)
				(justify right top mirror)
			)
		)
		(fp_text user "License: Apache-2.0"
			(at -1.682 -5.895 0)
			(layer "B.Fab")
			(effects
				(font
					(size 0.7 0.7)
					(thickness 0.15)
				)
				(justify right top mirror)
			)
		)
		(pad "1" smd roundrect
			(at -0.7 0)
			(size 0.8 1.1)
			(layers "B.Cu" "B.Mask" "B.Paste")
			(roundrect_rratio 0.2)
			(net 14 "/M.2/3V3_M2")
			(pintype "passive")
		)
		(pad "2" smd roundrect
			(at 0.7 0)
			(size 0.8 1.1)
			(layers "B.Cu" "B.Mask" "B.Paste")
			(roundrect_rratio 0.2)
			(net 1 "GND")
			(pintype "passive")
		)
	)
	(footprint "antmicro-footprints:C_0402_1005Metric"
		(layer "B.Cu")
		(at 97.75 54.5 180)
		(descr "Capacitor SMD 0402")
		(tags "capacitor SMD 0402")
		(property "Reference" "C226"
			(at -4 -0.5 0)
			(layer "B.SilkS")
			(effects
				(font
					(size 0.7 0.7)
					(thickness 0.15)
				)
				(justify left bottom mirror)
			)
		)
		(property "Value" "C_1u_25V_0402"
			(at -1.022927 -2.155213 0)
			(layer "B.Fab")
			(effects
				(font
					(size 0.7 0.7)
					(thickness 0.15)
				)
				(justify left bottom mirror)
			)
		)
		(property "Datasheet" "https://www.murata.com/products/productdetail?partno=GRM155R61E105KE11%23"
			(at 0 0 0)
			(layer "B.Fab")
			(hide yes)
			(effects
				(font
					(size 1.27 1.27)
					(thickness 0.15)
				)
				(justify mirror)
			)
		)
		(property "Description" "SMD Multilayer Ceramic Capacitor, 1 µF, 25 V, 0402 [1005 Metric], ± 10%, X5R, GRM Series"
			(at 0 0 0)
			(layer "B.Fab")
			(hide yes)
			(effects
				(font
					(size 1.27 1.27)
					(thickness 0.15)
				)
				(justify mirror)
			)
		)
		(property "MPN" "GRM155R61E105KE11J"
			(at 0 0 0)
			(unlocked yes)
			(layer "B.Fab")
			(hide yes)
			(effects
				(font
					(size 1 1)
					(thickness 0.15)
				)
				(justify mirror)
			)
		)
		(property "Manufacturer" "Murata"
			(at 0 0 0)
			(unlocked yes)
			(layer "B.Fab")
			(hide yes)
			(effects
				(font
					(size 1 1)
					(thickness 0.15)
				)
				(justify mirror)
			)
		)
		(property "License" "Apache-2.0"
			(at 0 0 0)
			(unlocked yes)
			(layer "B.Fab")
			(hide yes)
			(effects
				(font
					(size 1 1)
					(thickness 0.15)
				)
				(justify mirror)
			)
		)
		(property "Author" "Antmicro"
			(at 0 0 0)
			(unlocked yes)
			(layer "B.Fab")
			(hide yes)
			(effects
				(font
					(size 1 1)
					(thickness 0.15)
				)
				(justify mirror)
			)
		)
		(property "Val" "1u"
			(at 0 0 0)
			(unlocked yes)
			(layer "B.Fab")
			(hide yes)
			(effects
				(font
					(size 1 1)
					(thickness 0.15)
				)
				(justify mirror)
			)
		)
		(property "Voltage" "25V"
			(at 0 0 0)
			(unlocked yes)
			(layer "B.Fab")
			(hide yes)
			(effects
				(font
					(size 1 1)
					(thickness 0.15)
				)
				(justify mirror)
			)
		)
		(property "Dielectric" "X5R"
			(at 0 0 0)
			(unlocked yes)
			(layer "B.Fab")
			(hide yes)
			(effects
				(font
					(size 1 1)
					(thickness 0.15)
				)
				(justify mirror)
			)
		)
		(sheetname "/SoM_Power/")
		(sheetfile "som_power.kicad_sch")
		(attr smd)
		(fp_poly
			(pts
				(xy -0.925 0.47) (xy -0.925 -0.47) (xy 0.925 -0.47) (xy 0.925 0.47)
			)
			(stroke
				(width 0.05)
				(type default)
			)
			(fill no)
			(layer "B.CrtYd")
		)
		(fp_line
			(start 0.504 0.25)
			(end 0.504 -0.248)
			(stroke
				(width 0.15)
				(type solid)
			)
			(layer "B.Fab")
		)
		(fp_line
			(start 0.504 -0.248)
			(end -0.494 -0.248)
			(stroke
				(width 0.15)
				(type solid)
			)
			(layer "B.Fab")
		)
		(fp_line
			(start -0.494 0.25)
			(end 0.504 0.25)
			(stroke
				(width 0.15)
				(type solid)
			)
			(layer "B.Fab")
		)
		(fp_line
			(start -0.494 -0.248)
			(end -0.494 0.25)
			(stroke
				(width 0.15)
				(type solid)
			)
			(layer "B.Fab")
		)
		(fp_text user "Author: Antmicro"
			(at -0.939 -3.399 0)
			(layer "B.Fab")
			(effects
				(font
					(size 0.7 0.7)
					(thickness 0.15)
				)
				(justify left bottom mirror)
			)
		)
		(fp_text user "License: Apache-2.0"
			(at -0.939 -5.799 0)
			(layer "B.Fab")
			(effects
				(font
					(size 0.7 0.7)
					(thickness 0.15)
				)
				(justify left bottom mirror)
			)
		)
		(fp_text user "${REFERENCE}"
			(at -0.939 -4.599 0)
			(layer "B.Fab")
			(effects
				(font
					(size 0.7 0.7)
					(thickness 0.15)
				)
				(justify left bottom mirror)
			)
		)
		(pad "1" smd roundrect
			(at -0.48 0 180)
			(size 0.59 0.64)
			(layers "B.Cu" "B.Mask" "B.Paste")
			(roundrect_rratio 0.25)
			(net 1 "GND")
			(pintype "passive")
		)
		(pad "2" smd roundrect
			(at 0.48 0 180)
			(size 0.59 0.64)
			(layers "B.Cu" "B.Mask" "B.Paste")
			(roundrect_rratio 0.25)
			(net 521 "Net-(U72-CT)")
			(pintype "passive")
		)
	)
	(footprint "antmicro-footprints:LED_0603_1608Metric_G"
		(layer "B.Cu")
		(at 235.55 61.975)
		(descr "LED SMD 0603 Green")
		(tags "LED SMD 0603 Green")
		(property "Reference" "D53"
			(at -6.25 0.025 0)
			(layer "B.SilkS")
			(effects
				(font
					(size 0.7 0.7)
					(thickness 0.15)
				)
				(justify right top mirror)
			)
		)
		(property "Value" "LED_G_0603_LTST-C190GKT"
			(at -0.001 -1.599 0)
			(layer "B.Fab")
			(effects
				(font
					(size 0.7 0.7)
					(thickness 0.15)
				)
				(justify right top mirror)
			)
		)
		(property "Datasheet" "https://media.digikey.com/pdf/Data%20Sheets/Lite-On%20PDFs/LTST-C190GKT.pdf"
			(at 0 0 0)
			(layer "B.Fab")
			(hide yes)
			(effects
				(font
					(size 1.27 1.27)
					(thickness 0.15)
				)
				(justify mirror)
			)
		)
		(property "Description" "LED, Green, SMD, 0603, 20 mA, 2.1 V, 569 nm"
			(at 0 0 0)
			(layer "B.Fab")
			(hide yes)
			(effects
				(font
					(size 1.27 1.27)
					(thickness 0.15)
				)
				(justify mirror)
			)
		)
		(property "MPN" "LTST-C190GKT"
			(at 0 0 180)
			(unlocked yes)
			(layer "B.Fab")
			(hide yes)
			(effects
				(font
					(size 1 1)
					(thickness 0.15)
				)
				(justify mirror)
			)
		)
		(property "Manufacturer" "Lite-On"
			(at 0 0 180)
			(unlocked yes)
			(layer "B.Fab")
			(hide yes)
			(effects
				(font
					(size 1 1)
					(thickness 0.15)
				)
				(justify mirror)
			)
		)
		(property "Author" "Antmicro"
			(at 0 0 180)
			(unlocked yes)
			(layer "B.Fab")
			(hide yes)
			(effects
				(font
					(size 1 1)
					(thickness 0.15)
				)
				(justify mirror)
			)
		)
		(property "License" "Apache-2.0"
			(at 0 0 180)
			(unlocked yes)
			(layer "B.Fab")
			(hide yes)
			(effects
				(font
					(size 1 1)
					(thickness 0.15)
				)
				(justify mirror)
			)
		)
		(property "Color" "Green"
			(at 0 0 180)
			(unlocked yes)
			(layer "B.Fab")
			(hide yes)
			(effects
				(font
					(size 1 1)
					(thickness 0.15)
				)
				(justify mirror)
			)
		)
		(sheetname "/Power/")
		(sheetfile "power.kicad_sch")
		(attr smd)
		(fp_line
			(start -1.18 0.319)
			(end -1.18 -0.321)
			(stroke
				(width 0.15)
				(type solid)
			)
			(layer "B.SilkS")
		)
		(fp_line
			(start -0.094672 -0.201008)
			(end -0.094672 0.198992)
			(stroke
				(width 0.1)
				(type solid)
			)
			(layer "B.SilkS")
		)
		(fp_line
			(start -0.094672 -0.001008)
			(end -0.24 -0.001008)
			(stroke
				(width 0.1)
				(type solid)
			)
			(layer "B.SilkS")
		)
		(fp_line
			(start -0.094672 -0.001008)
			(end 0.105329 0.198992)
			(stroke
				(width 0.1)
				(type solid)
			)
			(layer "B.SilkS")
		)
		(fp_line
			(start 0.105328 -0.201008)
			(end -0.094672 -0.001008)
			(stroke
				(width 0.1)
				(type solid)
			)
			(layer "B.SilkS")
		)
		(fp_line
			(start 0.105328 -0.201008)
			(end 0.105329 0.198992)
			(stroke
				(width 0.1)
				(type solid)
			)
			(layer "B.SilkS")
		)
		(fp_line
			(start 0.105328 -0.001008)
			(end 0.240001 -0.001)
			(stroke
				(width 0.1)
				(type solid)
			)
			(layer "B.SilkS")
		)
		(fp_line
			(start 0.22 -0.35)
			(end -0.22 -0.35)
			(stroke
				(width 0.15)
				(type solid)
			)
			(layer "B.SilkS")
		)
		(fp_line
			(start 0.22 0.35)
			(end -0.22 0.35)
			(stroke
				(width 0.15)
				(type solid)
			)
			(layer "B.SilkS")
		)
		(fp_poly
			(pts
				(xy 1.25 -0.65) (xy -1.25 -0.65) (xy -1.25 0.65) (xy 1.25 0.65)
			)
			(stroke
				(width 0.05)
				(type solid)
			)
			(fill no)
			(layer "B.CrtYd")
		)
		(fp_line
			(start -0.199 -0.2)
			(end -0.199 -0.1)
			(stroke
				(width 0.15)
				(type solid)
			)
			(layer "B.Fab")
		)
		(fp_line
			(start -0.199 0)
			(end -0.597 0)
			(stroke
				(width 0.15)
				(type solid)
			)
			(layer "B.Fab")
		)
		(fp_line
			(start -0.199 0.202)
			(end -0.199 -0.1)
			(stroke
				(width 0.15)
				(type solid)
			)
			(layer "B.Fab")
		)
		(fp_line
			(start -0.101 0)
			(end 0.201 -0.2)
			(stroke
				(width 0.15)
				(type solid)
			)
			(layer "B.Fab")
		)
		(fp_line
			(start 0.200999 0)
			(end 0.201 0.202)
			(stroke
				(width 0.15)
				(type solid)
			)
			(layer "B.Fab")
		)
		(fp_line
			(start 0.201 -0.2)
			(end 0.200999 0)
			(stroke
				(width 0.15)
				(type solid)
			)
			(layer "B.Fab")
		)
		(fp_line
			(start 0.201 0.202)
			(end -0.101 0)
			(stroke
				(width 0.15)
				(type solid)
			)
			(layer "B.Fab")
		)
		(fp_line
			(start 0.599 0)
			(end 0.200999 0)
			(stroke
				(width 0.15)
				(type solid)
			)
			(layer "B.Fab")
		)
		(fp_poly
			(pts
				(xy 0.848 -0.4) (xy -0.85 -0.4) (xy -0.85 0.402) (xy 0.848 0.401999)
			)
			(stroke
				(width 0.15)
				(type solid)
			)
			(fill no)
			(layer "B.Fab")
		)
		(fp_text user "${REFERENCE}"
			(at -1.4224 -5.999 0)
			(layer "B.Fab")
			(effects
				(font
					(size 0.7 0.7)
					(thickness 0.15)
				)
				(justify right top mirror)
			)
		)
		(fp_text user "License: Apache-2.0"
			(at -1.4224 -3.599 0)
			(layer "B.Fab")
			(effects
				(font
					(size 0.7 0.7)
					(thickness 0.15)
				)
				(justify right top mirror)
			)
		)
		(fp_text user "Author: Antmicro"
			(at -1.4224 -4.799 0)
			(layer "B.Fab")
			(effects
				(font
					(size 0.7 0.7)
					(thickness 0.15)
				)
				(justify right top mirror)
			)
		)
		(pad "1" smd roundrect
			(at -0.7 0 180)
			(size 0.8 1)
			(layers "B.Cu" "B.Mask" "B.Paste")
			(roundrect_rratio 0.2)
			(net 1 "GND")
			(pinfunction "C")
			(pintype "passive")
		)
		(pad "2" smd roundrect
			(at 0.7 0 180)
			(size 0.8 1)
			(layers "B.Cu" "B.Mask" "B.Paste")
			(roundrect_rratio 0.2)
			(net 1395 "Net-(D53-A)")
			(pinfunction "A")
			(pintype "passive")
		)
	)
	(footprint "antmicro-footprints:R_0402_1005Metric"
		(layer "B.Cu")
		(at 161.92 62.8 90)
		(descr "Resistor SMD 0402")
		(tags "resistor SMD 0402")
		(property "Reference" "R126"
			(at -7.037 -8.42 90)
			(layer "B.SilkS")
			(effects
				(font
					(size 0.7 0.7)
					(thickness 0.15)
				)
				(justify right top mirror)
			)
		)
		(property "Value" "R_10k_0402"
			(at -1.011843 -1.772047 90)
			(layer "B.Fab")
			(effects
				(font
					(size 0.7 0.7)
					(thickness 0.15)
				)
				(justify right top mirror)
			)
		)
		(property "Datasheet" "https://www.bourns.com/docs/product-datasheets/cr.pdf"
			(at 0 0 90)
			(layer "B.Fab")
			(hide yes)
			(effects
				(font
					(size 1.27 1.27)
					(thickness 0.15)
				)
				(justify mirror)
			)
		)
		(property "Description" "SMD Chip Resistor, 10 kohm, ± 1%, 62.5 mW, 0402 [1005 Metric], Thick Film, General Purpose"
			(at 0 0 90)
			(layer "B.Fab")
			(hide yes)
			(effects
				(font
					(size 1.27 1.27)
					(thickness 0.15)
				)
				(justify mirror)
			)
		)
		(property "MPN" "CR0402-FX-1002GLF"
			(at 0 0 270)
			(unlocked yes)
			(layer "B.Fab")
			(hide yes)
			(effects
				(font
					(size 1 1)
					(thickness 0.15)
				)
				(justify mirror)
			)
		)
		(property "Manufacturer" "Bourns"
			(at 0 0 270)
			(unlocked yes)
			(layer "B.Fab")
			(hide yes)
			(effects
				(font
					(size 1 1)
					(thickness 0.15)
				)
				(justify mirror)
			)
		)
		(property "License" "Apache-2.0"
			(at 0 0 270)
			(unlocked yes)
			(layer "B.Fab")
			(hide yes)
			(effects
				(font
					(size 1 1)
					(thickness 0.15)
				)
				(justify mirror)
			)
		)
		(property "Author" "Antmicro"
			(at 0 0 270)
			(unlocked yes)
			(layer "B.Fab")
			(hide yes)
			(effects
				(font
					(size 1 1)
					(thickness 0.15)
				)
				(justify mirror)
			)
		)
		(property "Val" "10k"
			(at 0 0 270)
			(unlocked yes)
			(layer "B.Fab")
			(hide yes)
			(effects
				(font
					(size 1 1)
					(thickness 0.15)
				)
				(justify mirror)
			)
		)
		(property "Tolerance" "1%"
			(at 0 0 270)
			(unlocked yes)
			(layer "B.Fab")
			(hide yes)
			(effects
				(font
					(size 1 1)
					(thickness 0.15)
				)
				(justify mirror)
			)
		)
		(sheetname "/SoM_IO2/")
		(sheetfile "som_io2.kicad_sch")
		(attr smd exclude_from_pos_files exclude_from_bom dnp)
		(fp_rect
			(start -0.925 0.47)
			(end 0.925 -0.47)
			(stroke
				(width 0.05)
				(type default)
			)
			(fill no)
			(layer "B.CrtYd")
		)
		(fp_rect
			(start -0.5 0.25)
			(end 0.5 -0.25)
			(stroke
				(width 0.15)
				(type solid)
			)
			(fill no)
			(layer "B.Fab")
		)
		(fp_text user "License: Apache-2.0"
			(at -0.95 -5.169 90)
			(layer "B.Fab")
			(effects
				(font
					(size 0.7 0.7)
					(thickness 0.15)
				)
				(justify right top mirror)
			)
		)
		(fp_text user "Author: Antmicro"
			(at -0.95 -4.169 90)
			(layer "B.Fab")
			(effects
				(font
					(size 0.7 0.7)
					(thickness 0.15)
				)
				(justify right top mirror)
			)
		)
		(fp_text user "${REFERENCE}"
			(at -0.95 -3.168 90)
			(layer "B.Fab")
			(effects
				(font
					(size 0.7 0.7)
					(thickness 0.15)
				)
				(justify right top mirror)
			)
		)
		(pad "1" smd roundrect
			(at -0.48 0 90)
			(size 0.59 0.64)
			(layers "B.Cu" "B.Mask" "B.Paste")
			(roundrect_rratio 0.25)
			(net 1299 "Net-(Q28-G)")
			(pintype "passive")
		)
		(pad "2" smd roundrect
			(at 0.48 0 90)
			(size 0.59 0.64)
			(layers "B.Cu" "B.Mask" "B.Paste")
			(roundrect_rratio 0.25)
			(net 11 "+1V8")
			(pintype "passive")
		)
	)
	(footprint "antmicro-footprints:TSOT23-6"
		(layer "B.Cu")
		(at 135.6 62.08 -90)
		(property "Reference" "U53"
			(at -0.21 -2.72 90)
			(layer "B.SilkS")
			(effects
				(font
					(size 0.7 0.7)
					(thickness 0.15)
				)
				(justify left bottom mirror)
			)
		)
		(property "Value" "AP22615A_TSOT26"
			(at 0 -2.6 90)
			(layer "B.Fab")
			(effects
				(font
					(size 0.7 0.7)
					(thickness 0.15)
				)
				(justify left bottom mirror)
			)
		)
		(property "Datasheet" "https://www.mouser.com/datasheet/2/115/DIOD_S_A0008958405_1-2543193.pdf"
			(at 0 0 90)
			(layer "B.Fab")
			(hide yes)
			(effects
				(font
					(size 1.27 1.27)
					(thickness 0.15)
				)
				(justify mirror)
			)
		)
		(property "Description" "Power Load Distribution Switch, High Side, Active High, 1 Output, 5.5 V, 3.6 A, 0.04 ohm, TSOT-26-6"
			(at 0 0 90)
			(layer "B.Fab")
			(hide yes)
			(effects
				(font
					(size 1.27 1.27)
					(thickness 0.15)
				)
				(justify mirror)
			)
		)
		(property "MPN" "AP22615AWU-7"
			(at 0 0 270)
			(unlocked yes)
			(layer "B.Fab")
			(hide yes)
			(effects
				(font
					(size 1 1)
					(thickness 0.15)
				)
				(justify mirror)
			)
		)
		(property "Manufacturer" "Diodes Incorporated"
			(at 0 0 270)
			(unlocked yes)
			(layer "B.Fab")
			(hide yes)
			(effects
				(font
					(size 1 1)
					(thickness 0.15)
				)
				(justify mirror)
			)
		)
		(property "Author" "Antmicro"
			(at 0 0 270)
			(unlocked yes)
			(layer "B.Fab")
			(hide yes)
			(effects
				(font
					(size 1 1)
					(thickness 0.15)
				)
				(justify mirror)
			)
		)
		(property "License" "Apache-2.0"
			(at 0 0 270)
			(unlocked yes)
			(layer "B.Fab")
			(hide yes)
			(effects
				(font
					(size 1 1)
					(thickness 0.15)
				)
				(justify mirror)
			)
		)
		(sheetname "/Peripherals/")
		(sheetfile "peripherals.kicad_sch")
		(attr smd)
		(fp_line
			(start -1 1.5)
			(end -1 1.375)
			(stroke
				(width 0.15)
				(type solid)
			)
			(layer "B.SilkS")
		)
		(fp_line
			(start 1 1.497)
			(end -1 1.5)
			(stroke
				(width 0.15)
				(type solid)
			)
			(layer "B.SilkS")
		)
		(fp_line
			(start 1 1.497)
			(end 1 1.375)
			(stroke
				(width 0.15)
				(type solid)
			)
			(layer "B.SilkS")
		)
		(fp_line
			(start -1 -1.55)
			(end -1 -1.4)
			(stroke
				(width 0.15)
				(type solid)
			)
			(layer "B.SilkS")
		)
		(fp_line
			(start 1 -1.55)
			(end 1 -1.4)
			(stroke
				(width 0.15)
				(type solid)
			)
			(layer "B.SilkS")
		)
		(fp_line
			(start 1 -1.55)
			(end -1 -1.55)
			(stroke
				(width 0.15)
				(type solid)
			)
			(layer "B.SilkS")
		)
		(fp_circle
			(center -1.44 1.5)
			(end -1.39 1.5)
			(stroke
				(width 0.15)
				(type solid)
			)
			(fill yes)
			(layer "B.SilkS")
		)
		(fp_rect
			(start 1.93 1.7)
			(end -1.93 -1.7)
			(stroke
				(width 0.05)
				(type solid)
			)
			(fill no)
			(layer "B.CrtYd")
		)
		(fp_line
			(start -0.45 1.521)
			(end -0.876 1.096)
			(stroke
				(width 0.15)
				(type solid)
			)
			(layer "B.Fab")
		)
		(fp_rect
			(start 0.875 -1.528)
			(end -0.875 1.525)
			(stroke
				(width 0.15)
				(type solid)
			)
			(fill no)
			(layer "B.Fab")
		)
		(fp_text user "Author: Antmicro"
			(at -1.93 -5 90)
			(layer "B.Fab")
			(effects
				(font
					(size 0.7 0.7)
					(thickness 0.15)
				)
				(justify left bottom mirror)
			)
		)
		(fp_text user "License: Apache-2.0"
			(at -1.93 -6.199 90)
			(layer "B.Fab")
			(effects
				(font
					(size 0.7 0.7)
					(thickness 0.15)
				)
				(justify left bottom mirror)
			)
		)
		(fp_text user "${REFERENCE}"
			(at -1.93 -3.8 90)
			(layer "B.Fab")
			(effects
				(font
					(size 0.7 0.7)
					(thickness 0.15)
				)
				(justify left bottom mirror)
			)
		)
		(pad "1" smd rect
			(at -1.301 0.947)
			(size 0.7 1.2)
			(layers "B.Cu" "B.Mask" "B.Paste")
			(net 838 "/Peripherals/I2C_CONN1_3V3")
			(pinfunction "OUT")
			(pintype "power_out")
		)
		(pad "2" smd rect
			(at -1.301 -0.004)
			(size 0.7 1.2)
			(layers "B.Cu" "B.Mask" "B.Paste")
			(net 1 "GND")
			(pinfunction "GND")
			(pintype "power_in")
		)
		(pad "3" smd rect
			(at -1.301 -0.954)
			(size 0.7 1.2)
			(layers "B.Cu" "B.Mask" "B.Paste")
			(net 1121 "unconnected-(U53-FLG-Pad3)")
			(pinfunction "FLG")
			(pintype "output+no_connect")
		)
		(pad "4" smd rect
			(at 1.299 -0.954)
			(size 0.7 1.2)
			(layers "B.Cu" "B.Mask" "B.Paste")
			(net 90 "/Peripherals/I2C_CONN_PEN")
			(pinfunction "EN")
			(pintype "input")
		)
		(pad "5" smd rect
			(at 1.299 -0.004)
			(size 0.7 1.2)
			(layers "B.Cu" "B.Mask" "B.Paste")
			(net 1009 "Net-(U53-ISET)")
			(pinfunction "ISET")
			(pintype "passive")
		)
		(pad "6" smd rect
			(at 1.299 0.947)
			(size 0.7 1.2)
			(layers "B.Cu" "B.Mask" "B.Paste")
			(net 2 "+3V3")
			(pinfunction "IN")
			(pintype "power_in")
		)
	)
	(footprint "antmicro-footprints:C_0402_1005Metric"
		(layer "B.Cu")
		(at 110.25 107.5)
		(descr "Capacitor SMD 0402")
		(tags "capacitor SMD 0402")
		(property "Reference" "C181"
			(at -0.95 0.5 180)
			(layer "B.SilkS")
			(effects
				(font
					(size 0.7 0.7)
					(thickness 0.15)
				)
				(justify left bottom mirror)
			)
		)
		(property "Value" "C_220n_0402"
			(at -1.022927 -2.155213 180)
			(layer "B.Fab")
			(effects
				(font
					(size 0.7 0.7)
					(thickness 0.15)
				)
				(justify left bottom mirror)
			)
		)
		(property "Datasheet" "https://www.yageo.com/en/Chart/Download/pdf/CC0402KRX5R6BB224"
			(at 0 0 180)
			(layer "B.Fab")
			(hide yes)
			(effects
				(font
					(size 1.27 1.27)
					(thickness 0.15)
				)
				(justify mirror)
			)
		)
		(property "Description" "SMD Multilayer Ceramic Capacitor, 0.22 µF, 10 V, 0402 [1005 Metric], ± 10%, X5R, CC Series"
			(at 0 0 180)
			(layer "B.Fab")
			(hide yes)
			(effects
				(font
					(size 1.27 1.27)
					(thickness 0.15)
				)
				(justify mirror)
			)
		)
		(property "MPN" "CC0402KRX5R6BB224"
			(at 0 0 0)
			(unlocked yes)
			(layer "B.Fab")
			(hide yes)
			(effects
				(font
					(size 1 1)
					(thickness 0.15)
				)
				(justify mirror)
			)
		)
		(property "Val" "220n"
			(at 0 0 0)
			(unlocked yes)
			(layer "B.Fab")
			(hide yes)
			(effects
				(font
					(size 1 1)
					(thickness 0.15)
				)
				(justify mirror)
			)
		)
		(property "Voltage" "25V"
			(at 0 0 0)
			(unlocked yes)
			(layer "B.Fab")
			(hide yes)
			(effects
				(font
					(size 1 1)
					(thickness 0.15)
				)
				(justify mirror)
			)
		)
		(property "Dielectric" "X7R"
			(at 0 0 0)
			(unlocked yes)
			(layer "B.Fab")
			(hide yes)
			(effects
				(font
					(size 1 1)
					(thickness 0.15)
				)
				(justify mirror)
			)
		)
		(property "Manufacturer" "YAGEO"
			(at 0 0 0)
			(unlocked yes)
			(layer "B.Fab")
			(hide yes)
			(effects
				(font
					(size 1 1)
					(thickness 0.15)
				)
				(justify mirror)
			)
		)
		(property "License" "Apache-2.0"
			(at 0 0 0)
			(unlocked yes)
			(layer "B.Fab")
			(hide yes)
			(effects
				(font
					(size 1 1)
					(thickness 0.15)
				)
				(justify mirror)
			)
		)
		(property "Author" "Antmicro"
			(at 0 0 0)
			(unlocked yes)
			(layer "B.Fab")
			(hide yes)
			(effects
				(font
					(size 1 1)
					(thickness 0.15)
				)
				(justify mirror)
			)
		)
		(property "Public" "False"
			(at 0 0 0)
			(unlocked yes)
			(layer "B.Fab")
			(hide yes)
			(effects
				(font
					(size 1 1)
					(thickness 0.15)
				)
				(justify mirror)
			)
		)
		(sheetname "/M.2/")
		(sheetfile "m2.kicad_sch")
		(attr smd)
		(fp_rect
			(start -0.925 0.47)
			(end 0.925 -0.47)
			(stroke
				(width 0.05)
				(type default)
			)
			(fill no)
			(layer "B.CrtYd")
		)
		(fp_line
			(start -0.494 -0.248)
			(end -0.494 0.25)
			(stroke
				(width 0.15)
				(type solid)
			)
			(layer "B.Fab")
		)
		(fp_line
			(start -0.494 0.25)
			(end 0.504 0.25)
			(stroke
				(width 0.15)
				(type solid)
			)
			(layer "B.Fab")
		)
		(fp_line
			(start 0.504 -0.248)
			(end -0.494 -0.248)
			(stroke
				(width 0.15)
				(type solid)
			)
			(layer "B.Fab")
		)
		(fp_line
			(start 0.504 0.25)
			(end 0.504 -0.248)
			(stroke
				(width 0.15)
				(type solid)
			)
			(layer "B.Fab")
		)
		(fp_text user "License: Apache-2.0"
			(at -0.939 -5.799 180)
			(layer "B.Fab")
			(effects
				(font
					(size 0.7 0.7)
					(thickness 0.15)
				)
				(justify left bottom mirror)
			)
		)
		(fp_text user "Author: Antmicro"
			(at -0.939 -3.399 180)
			(layer "B.Fab")
			(effects
				(font
					(size 0.7 0.7)
					(thickness 0.15)
				)
				(justify left bottom mirror)
			)
		)
		(fp_text user "${REFERENCE}"
			(at -0.939 -4.599 180)
			(layer "B.Fab")
			(effects
				(font
					(size 0.7 0.7)
					(thickness 0.15)
				)
				(justify left bottom mirror)
			)
		)
		(pad "1" smd roundrect
			(at -0.48 0)
			(size 0.59 0.64)
			(layers "B.Cu" "B.Mask" "B.Paste")
			(roundrect_rratio 0.25)
			(net 382 "/M.2/PCIe_{C5x4}.TX0+")
			(pintype "passive")
		)
		(pad "2" smd roundrect
			(at 0.48 0)
			(size 0.59 0.64)
			(layers "B.Cu" "B.Mask" "B.Paste")
			(roundrect_rratio 0.25)
			(net 386 "/M.2/M2_M_PET0_P")
			(pintype "passive")
		)
	)
	(footprint "antmicro-footprints:C_0603_1608Metric_EIA"
		(layer "B.Cu")
		(at 124.6 120 180)
		(descr "Capacitor SMD 0603, IPC-7351 Density Level A")
		(tags "Capacitor 0603")
		(property "Reference" "C71"
			(at -3.47 -0.415 0)
			(layer "B.SilkS")
			(effects
				(font
					(size 0.7 0.7)
					(thickness 0.15)
				)
				(justify left bottom mirror)
			)
		)
		(property "Value" "C_22u_16V_0603"
			(at -1.42757 -1.770288 0)
			(layer "B.Fab")
			(effects
				(font
					(size 0.7 0.7)
					(thickness 0.15)
				)
				(justify left bottom mirror)
			)
		)
		(property "Datasheet" "https://product.samsungsem.com/mlcc/CL10A226MO7JZN.do"
			(at 0 0 0)
			(layer "B.Fab")
			(hide yes)
			(effects
				(font
					(size 1.27 1.27)
					(thickness 0.15)
				)
				(justify mirror)
			)
		)
		(property "Description" "SMD Multilayer Ceramic Capacitor"
			(at 0 0 0)
			(layer "B.Fab")
			(hide yes)
			(effects
				(font
					(size 1.27 1.27)
					(thickness 0.15)
				)
				(justify mirror)
			)
		)
		(property "MPN" "CL10A226MO7JZNC"
			(at 0 0 180)
			(unlocked yes)
			(layer "B.Fab")
			(hide yes)
			(effects
				(font
					(size 1 1)
					(thickness 0.15)
				)
				(justify mirror)
			)
		)
		(property "Manufacturer" "Samsung Electro-Mechanics"
			(at 0 0 180)
			(unlocked yes)
			(layer "B.Fab")
			(hide yes)
			(effects
				(font
					(size 1 1)
					(thickness 0.15)
				)
				(justify mirror)
			)
		)
		(property "License" "Apache-2.0"
			(at 0 0 180)
			(unlocked yes)
			(layer "B.Fab")
			(hide yes)
			(effects
				(font
					(size 1 1)
					(thickness 0.15)
				)
				(justify mirror)
			)
		)
		(property "Author" "Antmicro"
			(at 0 0 180)
			(unlocked yes)
			(layer "B.Fab")
			(hide yes)
			(effects
				(font
					(size 1 1)
					(thickness 0.15)
				)
				(justify mirror)
			)
		)
		(property "Val" "22u"
			(at 0 0 180)
			(unlocked yes)
			(layer "B.Fab")
			(hide yes)
			(effects
				(font
					(size 1 1)
					(thickness 0.15)
				)
				(justify mirror)
			)
		)
		(property "Voltage" "16V"
			(at 0 0 180)
			(unlocked yes)
			(layer "B.Fab")
			(hide yes)
			(effects
				(font
					(size 1 1)
					(thickness 0.15)
				)
				(justify mirror)
			)
		)
		(property "Dielectric" ""
			(at 0 0 180)
			(unlocked yes)
			(layer "B.Fab")
			(hide yes)
			(effects
				(font
					(size 1 1)
					(thickness 0.15)
				)
				(justify mirror)
			)
		)
		(sheetname "/M.2/")
		(sheetfile "m2.kicad_sch")
		(attr smd)
		(fp_line
			(start -0.15 0.55)
			(end 0.15 0.55)
			(stroke
				(width 0.15)
				(type solid)
			)
			(layer "B.SilkS")
		)
		(fp_line
			(start -0.15 -0.55)
			(end 0.15 -0.55)
			(stroke
				(width 0.15)
				(type solid)
			)
			(layer "B.SilkS")
		)
		(fp_rect
			(start -1.25 0.65)
			(end 1.25 -0.65)
			(stroke
				(width 0.05)
				(type solid)
			)
			(fill no)
			(layer "B.CrtYd")
		)
		(fp_rect
			(start -0.8 0.45)
			(end 0.8 -0.45)
			(stroke
				(width 0.15)
				(type solid)
			)
			(fill no)
			(layer "B.Fab")
		)
		(fp_text user "License: Apache-2.0"
			(at -1.682 -5.895 0)
			(layer "B.Fab")
			(effects
				(font
					(size 0.7 0.7)
					(thickness 0.15)
				)
				(justify left bottom mirror)
			)
		)
		(fp_text user "${REFERENCE}"
			(at -1.682 -3.895 0)
			(layer "B.Fab")
			(effects
				(font
					(size 0.7 0.7)
					(thickness 0.15)
				)
				(justify left bottom mirror)
			)
		)
		(fp_text user "Author: Antmicro"
			(at -1.682 -4.894 0)
			(layer "B.Fab")
			(effects
				(font
					(size 0.7 0.7)
					(thickness 0.15)
				)
				(justify left bottom mirror)
			)
		)
		(pad "1" smd roundrect
			(at -0.7 0 180)
			(size 0.8 1.1)
			(layers "B.Cu" "B.Mask" "B.Paste")
			(roundrect_rratio 0.2)
			(net 1 "GND")
			(pintype "passive")
		)
		(pad "2" smd roundrect
			(at 0.7 0 180)
			(size 0.8 1.1)
			(layers "B.Cu" "B.Mask" "B.Paste")
			(roundrect_rratio 0.2)
			(net 2 "+3V3")
			(pintype "passive")
		)
	)
	(footprint "antmicro-footprints:TP_SMD_0.75mm"
		(layer "B.Cu")
		(at 141.730532 71.31 90)
		(property "Reference" "TP60"
			(at -3.29 -0.430532 90)
			(layer "B.SilkS")
			(effects
				(font
					(size 0.7 0.7)
					(thickness 0.15)
				)
				(justify right top mirror)
			)
		)
		(property "Value" "TP_0.75mm_SMD"
			(at 0 -1.2 90)
			(layer "B.Fab")
			(effects
				(font
					(size 0.7 0.7)
					(thickness 0.15)
				)
				(justify right top mirror)
			)
		)
		(property "Description" "SMT test point"
			(at 0 0 90)
			(layer "B.Fab")
			(hide yes)
			(effects
				(font
					(size 1.27 1.27)
					(thickness 0.15)
				)
				(justify mirror)
			)
		)
		(property "MPN" ""
			(at 0 0 270)
			(unlocked yes)
			(layer "B.Fab")
			(hide yes)
			(effects
				(font
					(size 1 1)
					(thickness 0.15)
				)
				(justify mirror)
			)
		)
		(property "Manufacturer" ""
			(at 0 0 270)
			(unlocked yes)
			(layer "B.Fab")
			(hide yes)
			(effects
				(font
					(size 1 1)
					(thickness 0.15)
				)
				(justify mirror)
			)
		)
		(property "Author" "Antmicro"
			(at 0 0 270)
			(unlocked yes)
			(layer "B.Fab")
			(hide yes)
			(effects
				(font
					(size 1 1)
					(thickness 0.15)
				)
				(justify mirror)
			)
		)
		(property "License" "Apache-2.0"
			(at 0 0 270)
			(unlocked yes)
			(layer "B.Fab")
			(hide yes)
			(effects
				(font
					(size 1 1)
					(thickness 0.15)
				)
				(justify mirror)
			)
		)
		(sheetname "/SoM_Power/")
		(sheetfile "som_power.kicad_sch")
		(attr exclude_from_pos_files exclude_from_bom)
		(fp_circle
			(center 0 0)
			(end 0.475 0)
			(stroke
				(width 0.05)
				(type default)
			)
			(fill no)
			(layer "B.CrtYd")
		)
		(fp_text user "Author: Antmicro"
			(at -0.4 -3.901 90)
			(layer "B.Fab")
			(effects
				(font
					(size 0.7 0.7)
					(thickness 0.15)
				)
				(justify right top mirror)
			)
		)
		(fp_text user "License: Apache-2.0"
			(at -0.4 -5.101 90)
			(layer "B.Fab")
			(effects
				(font
					(size 0.7 0.7)
					(thickness 0.15)
				)
				(justify right top mirror)
			)
		)
		(fp_text user "${REFERENCE}"
			(at -0.4 -2.7 90)
			(layer "B.Fab")
			(effects
				(font
					(size 0.7 0.7)
					(thickness 0.15)
				)
				(justify right top mirror)
			)
		)
		(pad "1" smd circle
			(at 0 0 90)
			(size 0.75 0.75)
			(layers "B.Cu" "B.Mask")
			(net 760 "Net-(J1A-MODULE_POWER_GOOD)")
			(pinfunction "1")
			(pintype "passive")
		)
	)
	(footprint "antmicro-footprints:R_0603_1608Metric"
		(layer "B.Cu")
		(at 100.1 133.9 180)
		(descr "Resistor SMD 0603")
		(tags "resistor SMD 0603")
		(property "Reference" "R33"
			(at -3.4 -0.5 0)
			(layer "B.SilkS")
			(effects
				(font
					(size 0.7 0.7)
					(thickness 0.15)
				)
				(justify left bottom mirror)
			)
		)
		(property "Value" "R_0R_22.4A_0603"
			(at 0 -1.6 0)
			(layer "B.Fab")
			(effects
				(font
					(size 0.7 0.7)
					(thickness 0.15)
				)
				(justify left bottom mirror)
			)
		)
		(property "Datasheet" "https://fscdn.rohm.com/en/products/databook/datasheet/passive/resistor/chip_resistor/pmr-jpw-e.pdf"
			(at 0 0 0)
			(layer "B.Fab")
			(hide yes)
			(effects
				(font
					(size 1.27 1.27)
					(thickness 0.15)
				)
				(justify mirror)
			)
		)
		(property "Description" "SMD Chip Resistor"
			(at 0 0 0)
			(layer "B.Fab")
			(hide yes)
			(effects
				(font
					(size 1.27 1.27)
					(thickness 0.15)
				)
				(justify mirror)
			)
		)
		(property "MPN" "PMR03EZPJ000"
			(at 0 0 0)
			(unlocked yes)
			(layer "B.Fab")
			(hide yes)
			(effects
				(font
					(size 1 1)
					(thickness 0.15)
				)
				(justify mirror)
			)
		)
		(property "Manufacturer" "ROHM Semiconductor"
			(at 0 0 0)
			(unlocked yes)
			(layer "B.Fab")
			(hide yes)
			(effects
				(font
					(size 1 1)
					(thickness 0.15)
				)
				(justify mirror)
			)
		)
		(property "Val" "0R"
			(at 0 0 0)
			(unlocked yes)
			(layer "B.Fab")
			(hide yes)
			(effects
				(font
					(size 1 1)
					(thickness 0.15)
				)
				(justify mirror)
			)
		)
		(property "Max. Curr." "22.4A"
			(at 0 0 0)
			(unlocked yes)
			(layer "B.Fab")
			(hide yes)
			(effects
				(font
					(size 1 1)
					(thickness 0.15)
				)
				(justify mirror)
			)
		)
		(property "Author" "Antmicro"
			(at 0 0 0)
			(unlocked yes)
			(layer "B.Fab")
			(hide yes)
			(effects
				(font
					(size 1 1)
					(thickness 0.15)
				)
				(justify mirror)
			)
		)
		(property "License" "Apache-2.0"
			(at 0 0 0)
			(unlocked yes)
			(layer "B.Fab")
			(hide yes)
			(effects
				(font
					(size 1 1)
					(thickness 0.15)
				)
				(justify mirror)
			)
		)
		(property "Tolerance" "template_tolerance"
			(at 0 0 0)
			(unlocked yes)
			(layer "B.Fab")
			(hide yes)
			(effects
				(font
					(size 1 1)
					(thickness 0.15)
				)
				(justify mirror)
			)
		)
		(sheetname "/Expansion connector/")
		(sheetfile "expansion_connector.kicad_sch")
		(attr smd exclude_from_pos_files exclude_from_bom dnp)
		(fp_line
			(start -0.15 0.4)
			(end 0.15 0.4)
			(stroke
				(width 0.15)
				(type solid)
			)
			(layer "B.SilkS")
		)
		(fp_line
			(start -0.15 -0.4)
			(end 0.15 -0.4)
			(stroke
				(width 0.15)
				(type solid)
			)
			(layer "B.SilkS")
		)
		(fp_rect
			(start -1.25 0.65)
			(end 1.25 -0.65)
			(stroke
				(width 0.05)
				(type solid)
			)
			(fill no)
			(layer "B.CrtYd")
		)
		(fp_rect
			(start -0.8 0.4)
			(end 0.8 -0.4)
			(stroke
				(width 0.15)
				(type solid)
			)
			(fill no)
			(layer "B.Fab")
		)
		(fp_text user "License: Apache-2.0"
			(at -1.25 -5.9 0)
			(layer "B.Fab")
			(effects
				(font
					(size 0.7 0.7)
					(thickness 0.15)
				)
				(justify left bottom mirror)
			)
		)
		(fp_text user "Author: Antmicro"
			(at -1.25 -4.9 0)
			(layer "B.Fab")
			(effects
				(font
					(size 0.7 0.7)
					(thickness 0.15)
				)
				(justify left bottom mirror)
			)
		)
		(fp_text user "${REFERENCE}"
			(at -1.25 -3.898 0)
			(layer "B.Fab")
			(effects
				(font
					(size 0.7 0.7)
					(thickness 0.15)
				)
				(justify left bottom mirror)
			)
		)
		(pad "1" smd roundrect
			(at -0.7 0 180)
			(size 0.8 1)
			(layers "B.Cu" "B.Mask" "B.Paste")
			(roundrect_rratio 0.2)
			(net 13 "VCC")
			(pintype "passive")
		)
		(pad "2" smd roundrect
			(at 0.7 0 180)
			(size 0.8 1)
			(layers "B.Cu" "B.Mask" "B.Paste")
			(roundrect_rratio 0.2)
			(net 156 "/Expansion connector/+VCC_FMC")
			(pintype "passive")
		)
	)
	(footprint "antmicro-footprints:TP_SMD_0.75mm"
		(layer "B.Cu")
		(at 205.966532 142.82 -90)
		(property "Reference" "TP29"
			(at -2.13 0.600532 90)
			(layer "B.SilkS")
			(effects
				(font
					(size 0.7 0.7)
					(thickness 0.15)
				)
				(justify left bottom mirror)
			)
		)
		(property "Value" "TP_0.75mm_SMD"
			(at 0 -1.2 90)
			(layer "B.Fab")
			(effects
				(font
					(size 0.7 0.7)
					(thickness 0.15)
				)
				(justify left bottom mirror)
			)
		)
		(property "Description" "SMT test point"
			(at 0 0 90)
			(layer "B.Fab")
			(hide yes)
			(effects
				(font
					(size 1.27 1.27)
					(thickness 0.15)
				)
				(justify mirror)
			)
		)
		(property "MPN" ""
			(at 0 0 90)
			(unlocked yes)
			(layer "B.Fab")
			(hide yes)
			(effects
				(font
					(size 1 1)
					(thickness 0.15)
				)
				(justify mirror)
			)
		)
		(property "Manufacturer" ""
			(at 0 0 90)
			(unlocked yes)
			(layer "B.Fab")
			(hide yes)
			(effects
				(font
					(size 1 1)
					(thickness 0.15)
				)
				(justify mirror)
			)
		)
		(property "Author" "Antmicro"
			(at 0 0 90)
			(unlocked yes)
			(layer "B.Fab")
			(hide yes)
			(effects
				(font
					(size 1 1)
					(thickness 0.15)
				)
				(justify mirror)
			)
		)
		(property "License" "Apache-2.0"
			(at 0 0 90)
			(unlocked yes)
			(layer "B.Fab")
			(hide yes)
			(effects
				(font
					(size 1 1)
					(thickness 0.15)
				)
				(justify mirror)
			)
		)
		(sheetname "/SFP/")
		(sheetfile "sfp.kicad_sch")
		(attr exclude_from_pos_files exclude_from_bom)
		(fp_circle
			(center 0 0)
			(end 0.475 0)
			(stroke
				(width 0.05)
				(type default)
			)
			(fill no)
			(layer "B.CrtYd")
		)
		(fp_text user "Author: Antmicro"
			(at -0.4 -3.901 90)
			(layer "B.Fab")
			(effects
				(font
					(size 0.7 0.7)
					(thickness 0.15)
				)
				(justify left bottom mirror)
			)
		)
		(fp_text user "${REFERENCE}"
			(at -0.4 -2.7 90)
			(layer "B.Fab")
			(effects
				(font
					(size 0.7 0.7)
					(thickness 0.15)
				)
				(justify left bottom mirror)
			)
		)
		(fp_text user "License: Apache-2.0"
			(at -0.4 -5.101 90)
			(layer "B.Fab")
			(effects
				(font
					(size 0.7 0.7)
					(thickness 0.15)
				)
				(justify left bottom mirror)
			)
		)
		(pad "1" smd circle
			(at 0 0 270)
			(size 0.75 0.75)
			(layers "B.Cu" "B.Mask")
			(net 1370 "Net-(J12-RX_{LOS})")
			(pinfunction "1")
			(pintype "passive")
		)
	)
	(footprint "antmicro-footprints:TP_SMD_0.75mm"
		(layer "B.Cu")
		(at 167.39 58 180)
		(property "Reference" "TP132"
			(at -0.43 4.05 90)
			(layer "B.SilkS")
			(effects
				(font
					(size 0.7 0.7)
					(thickness 0.15)
				)
				(justify left bottom mirror)
			)
		)
		(property "Value" "TP_0.75mm_SMD"
			(at 0 -1.2 0)
			(layer "B.Fab")
			(effects
				(font
					(size 0.7 0.7)
					(thickness 0.15)
				)
				(justify left bottom mirror)
			)
		)
		(property "Description" "SMT test point"
			(at 0 0 0)
			(layer "B.Fab")
			(hide yes)
			(effects
				(font
					(size 1.27 1.27)
					(thickness 0.15)
				)
				(justify mirror)
			)
		)
		(property "MPN" ""
			(at 0 0 0)
			(unlocked yes)
			(layer "B.Fab")
			(hide yes)
			(effects
				(font
					(size 1 1)
					(thickness 0.15)
				)
				(justify mirror)
			)
		)
		(property "Manufacturer" ""
			(at 0 0 0)
			(unlocked yes)
			(layer "B.Fab")
			(hide yes)
			(effects
				(font
					(size 1 1)
					(thickness 0.15)
				)
				(justify mirror)
			)
		)
		(property "Author" "Antmicro"
			(at 0 0 0)
			(unlocked yes)
			(layer "B.Fab")
			(hide yes)
			(effects
				(font
					(size 1 1)
					(thickness 0.15)
				)
				(justify mirror)
			)
		)
		(property "License" "Apache-2.0"
			(at 0 0 0)
			(unlocked yes)
			(layer "B.Fab")
			(hide yes)
			(effects
				(font
					(size 1 1)
					(thickness 0.15)
				)
				(justify mirror)
			)
		)
		(sheetname "/Power/")
		(sheetfile "power.kicad_sch")
		(attr exclude_from_pos_files exclude_from_bom)
		(fp_circle
			(center 0 0)
			(end 0.475 0)
			(stroke
				(width 0.05)
				(type default)
			)
			(fill no)
			(layer "B.CrtYd")
		)
		(fp_text user "Author: Antmicro"
			(at -0.4 -3.901 0)
			(layer "B.Fab")
			(effects
				(font
					(size 0.7 0.7)
					(thickness 0.15)
				)
				(justify left bottom mirror)
			)
		)
		(fp_text user "${REFERENCE}"
			(at -0.4 -2.7 0)
			(layer "B.Fab")
			(effects
				(font
					(size 0.7 0.7)
					(thickness 0.15)
				)
				(justify left bottom mirror)
			)
		)
		(fp_text user "License: Apache-2.0"
			(at -0.4 -5.101 0)
			(layer "B.Fab")
			(effects
				(font
					(size 0.7 0.7)
					(thickness 0.15)
				)
				(justify left bottom mirror)
			)
		)
		(pad "1" smd circle
			(at 0 0 180)
			(size 0.75 0.75)
			(layers "B.Cu" "B.Mask")
			(net 2 "+3V3")
			(pinfunction "1")
			(pintype "passive")
		)
	)
	(footprint "antmicro-footprints:R_0402_1005Metric"
		(layer "B.Cu")
		(at 223.56 123.4)
		(descr "Resistor SMD 0402")
		(tags "resistor SMD 0402")
		(property "Reference" "R334"
			(at 0.94 -0.6 0)
			(layer "B.SilkS")
			(effects
				(font
					(size 0.7 0.7)
					(thickness 0.15)
				)
				(justify right top mirror)
			)
		)
		(property "Value" "R_10k_0402"
			(at -1.011843 -1.772047 0)
			(layer "B.Fab")
			(effects
				(font
					(size 0.7 0.7)
					(thickness 0.15)
				)
				(justify right top mirror)
			)
		)
		(property "Datasheet" "https://www.bourns.com/docs/product-datasheets/cr.pdf"
			(at 0 0 0)
			(layer "B.Fab")
			(hide yes)
			(effects
				(font
					(size 1.27 1.27)
					(thickness 0.15)
				)
				(justify mirror)
			)
		)
		(property "Description" "SMD Chip Resistor, 10 kohm, ± 1%, 62.5 mW, 0402 [1005 Metric], Thick Film, General Purpose"
			(at 0 0 0)
			(layer "B.Fab")
			(hide yes)
			(effects
				(font
					(size 1.27 1.27)
					(thickness 0.15)
				)
				(justify mirror)
			)
		)
		(property "MPN" "CR0402-FX-1002GLF"
			(at 0 0 180)
			(unlocked yes)
			(layer "B.Fab")
			(hide yes)
			(effects
				(font
					(size 1 1)
					(thickness 0.15)
				)
				(justify mirror)
			)
		)
		(property "Manufacturer" "Bourns"
			(at 0 0 180)
			(unlocked yes)
			(layer "B.Fab")
			(hide yes)
			(effects
				(font
					(size 1 1)
					(thickness 0.15)
				)
				(justify mirror)
			)
		)
		(property "License" "Apache-2.0"
			(at 0 0 180)
			(unlocked yes)
			(layer "B.Fab")
			(hide yes)
			(effects
				(font
					(size 1 1)
					(thickness 0.15)
				)
				(justify mirror)
			)
		)
		(property "Author" "Antmicro"
			(at 0 0 180)
			(unlocked yes)
			(layer "B.Fab")
			(hide yes)
			(effects
				(font
					(size 1 1)
					(thickness 0.15)
				)
				(justify mirror)
			)
		)
		(property "Val" "10k"
			(at 0 0 180)
			(unlocked yes)
			(layer "B.Fab")
			(hide yes)
			(effects
				(font
					(size 1 1)
					(thickness 0.15)
				)
				(justify mirror)
			)
		)
		(property "Tolerance" "1%"
			(at 0 0 180)
			(unlocked yes)
			(layer "B.Fab")
			(hide yes)
			(effects
				(font
					(size 1 1)
					(thickness 0.15)
				)
				(justify mirror)
			)
		)
		(sheetname "/USB Hub/")
		(sheetfile "usb_hub.kicad_sch")
		(attr smd)
		(fp_rect
			(start -0.925 0.47)
			(end 0.925 -0.47)
			(stroke
				(width 0.05)
				(type default)
			)
			(fill no)
			(layer "B.CrtYd")
		)
		(fp_rect
			(start -0.5 0.25)
			(end 0.5 -0.25)
			(stroke
				(width 0.15)
				(type solid)
			)
			(fill no)
			(layer "B.Fab")
		)
		(fp_text user "License: Apache-2.0"
			(at -0.95 -5.169 0)
			(layer "B.Fab")
			(effects
				(font
					(size 0.7 0.7)
					(thickness 0.15)
				)
				(justify right top mirror)
			)
		)
		(fp_text user "Author: Antmicro"
			(at -0.95 -4.169 0)
			(layer "B.Fab")
			(effects
				(font
					(size 0.7 0.7)
					(thickness 0.15)
				)
				(justify right top mirror)
			)
		)
		(fp_text user "${REFERENCE}"
			(at -0.95 -3.168 0)
			(layer "B.Fab")
			(effects
				(font
					(size 0.7 0.7)
					(thickness 0.15)
				)
				(justify right top mirror)
			)
		)
		(pad "1" smd roundrect
			(at -0.48 0)
			(size 0.59 0.64)
			(layers "B.Cu" "B.Mask" "B.Paste")
			(roundrect_rratio 0.25)
			(net 1084 "/USB Hub/DP1_VCONN1")
			(pintype "passive")
		)
		(pad "2" smd roundrect
			(at 0.48 0)
			(size 0.59 0.64)
			(layers "B.Cu" "B.Mask" "B.Paste")
			(roundrect_rratio 0.25)
			(net 1 "GND")
			(pintype "passive")
		)
	)
	(footprint "antmicro-footprints:C_0402_1005Metric"
		(layer "B.Cu")
		(at 110.25 103.5)
		(descr "Capacitor SMD 0402")
		(tags "capacitor SMD 0402")
		(property "Reference" "C182"
			(at -0.95 -0.4 0)
			(layer "B.SilkS")
			(effects
				(font
					(size 0.7 0.7)
					(thickness 0.15)
				)
				(justify left top mirror)
			)
		)
		(property "Value" "C_220n_0402"
			(at -1.022927 -2.155213 0)
			(layer "B.Fab")
			(effects
				(font
					(size 0.7 0.7)
					(thickness 0.15)
				)
				(justify right top mirror)
			)
		)
		(property "Datasheet" "https://www.yageo.com/en/Chart/Download/pdf/CC0402KRX5R6BB224"
			(at 0 0 0)
			(layer "B.Fab")
			(hide yes)
			(effects
				(font
					(size 1.27 1.27)
					(thickness 0.15)
				)
				(justify mirror)
			)
		)
		(property "Description" "SMD Multilayer Ceramic Capacitor, 0.22 µF, 10 V, 0402 [1005 Metric], ± 10%, X5R, CC Series"
			(at 0 0 0)
			(layer "B.Fab")
			(hide yes)
			(effects
				(font
					(size 1.27 1.27)
					(thickness 0.15)
				)
				(justify mirror)
			)
		)
		(property "MPN" "CC0402KRX5R6BB224"
			(at 0 0 0)
			(unlocked yes)
			(layer "B.Fab")
			(hide yes)
			(effects
				(font
					(size 1 1)
					(thickness 0.15)
				)
				(justify mirror)
			)
		)
		(property "Val" "220n"
			(at 0 0 0)
			(unlocked yes)
			(layer "B.Fab")
			(hide yes)
			(effects
				(font
					(size 1 1)
					(thickness 0.15)
				)
				(justify mirror)
			)
		)
		(property "Voltage" "25V"
			(at 0 0 0)
			(unlocked yes)
			(layer "B.Fab")
			(hide yes)
			(effects
				(font
					(size 1 1)
					(thickness 0.15)
				)
				(justify mirror)
			)
		)
		(property "Dielectric" "X7R"
			(at 0 0 0)
			(unlocked yes)
			(layer "B.Fab")
			(hide yes)
			(effects
				(font
					(size 1 1)
					(thickness 0.15)
				)
				(justify mirror)
			)
		)
		(property "Manufacturer" "YAGEO"
			(at 0 0 0)
			(unlocked yes)
			(layer "B.Fab")
			(hide yes)
			(effects
				(font
					(size 1 1)
					(thickness 0.15)
				)
				(justify mirror)
			)
		)
		(property "License" "Apache-2.0"
			(at 0 0 0)
			(unlocked yes)
			(layer "B.Fab")
			(hide yes)
			(effects
				(font
					(size 1 1)
					(thickness 0.15)
				)
				(justify mirror)
			)
		)
		(property "Author" "Antmicro"
			(at 0 0 0)
			(unlocked yes)
			(layer "B.Fab")
			(hide yes)
			(effects
				(font
					(size 1 1)
					(thickness 0.15)
				)
				(justify mirror)
			)
		)
		(property "Public" "False"
			(at 0 0 0)
			(unlocked yes)
			(layer "B.Fab")
			(hide yes)
			(effects
				(font
					(size 1 1)
					(thickness 0.15)
				)
				(justify mirror)
			)
		)
		(sheetname "/M.2/")
		(sheetfile "m2.kicad_sch")
		(attr smd)
		(fp_poly
			(pts
				(xy -0.925 0.47) (xy -0.925 -0.47) (xy 0.925 -0.47) (xy 0.925 0.47)
			)
			(stroke
				(width 0.05)
				(type default)
			)
			(fill no)
			(layer "B.CrtYd")
		)
		(fp_line
			(start -0.494 -0.248)
			(end -0.494 0.25)
			(stroke
				(width 0.15)
				(type solid)
			)
			(layer "B.Fab")
		)
		(fp_line
			(start -0.494 0.25)
			(end 0.504 0.25)
			(stroke
				(width 0.15)
				(type solid)
			)
			(layer "B.Fab")
		)
		(fp_line
			(start 0.504 -0.248)
			(end -0.494 -0.248)
			(stroke
				(width 0.15)
				(type solid)
			)
			(layer "B.Fab")
		)
		(fp_line
			(start 0.504 0.25)
			(end 0.504 -0.248)
			(stroke
				(width 0.15)
				(type solid)
			)
			(layer "B.Fab")
		)
		(fp_text user "License: Apache-2.0"
			(at -0.939 -5.799 0)
			(layer "B.Fab")
			(effects
				(font
					(size 0.7 0.7)
					(thickness 0.15)
				)
				(justify right top mirror)
			)
		)
		(fp_text user "Author: Antmicro"
			(at -0.939 -3.399 0)
			(layer "B.Fab")
			(effects
				(font
					(size 0.7 0.7)
					(thickness 0.15)
				)
				(justify right top mirror)
			)
		)
		(fp_text user "${REFERENCE}"
			(at -0.939 -4.599 0)
			(layer "B.Fab")
			(effects
				(font
					(size 0.7 0.7)
					(thickness 0.15)
				)
				(justify right top mirror)
			)
		)
		(pad "1" smd roundrect
			(at -0.48 0)
			(size 0.59 0.64)
			(layers "B.Cu" "B.Mask" "B.Paste")
			(roundrect_rratio 0.25)
			(net 392 "/M.2/PCIe_{C5x4}.TX1+")
			(pintype "passive")
		)
		(pad "2" smd roundrect
			(at 0.48 0)
			(size 0.59 0.64)
			(layers "B.Cu" "B.Mask" "B.Paste")
			(roundrect_rratio 0.25)
			(net 391 "/M.2/M2_M_PET1_P")
			(pintype "passive")
		)
	)
	(footprint "antmicro-footprints:R_0402_1005Metric"
		(layer "B.Cu")
		(at 170.805 60.71 90)
		(descr "Resistor SMD 0402")
		(tags "resistor SMD 0402")
		(property "Reference" "R84"
			(at -3.09 -0.405 90)
			(layer "B.SilkS")
			(effects
				(font
					(size 0.7 0.7)
					(thickness 0.15)
				)
				(justify right top mirror)
			)
		)
		(property "Value" "R_10k_0402"
			(at -1.011843 -1.772047 90)
			(layer "B.Fab")
			(effects
				(font
					(size 0.7 0.7)
					(thickness 0.15)
				)
				(justify right top mirror)
			)
		)
		(property "Datasheet" "https://www.bourns.com/docs/product-datasheets/cr.pdf"
			(at 0 0 90)
			(layer "B.Fab")
			(hide yes)
			(effects
				(font
					(size 1.27 1.27)
					(thickness 0.15)
				)
				(justify mirror)
			)
		)
		(property "Description" "SMD Chip Resistor, 10 kohm, ± 1%, 62.5 mW, 0402 [1005 Metric], Thick Film, General Purpose"
			(at 0 0 90)
			(layer "B.Fab")
			(hide yes)
			(effects
				(font
					(size 1.27 1.27)
					(thickness 0.15)
				)
				(justify mirror)
			)
		)
		(property "MPN" "CR0402-FX-1002GLF"
			(at 0 0 270)
			(unlocked yes)
			(layer "B.Fab")
			(hide yes)
			(effects
				(font
					(size 1 1)
					(thickness 0.15)
				)
				(justify mirror)
			)
		)
		(property "Manufacturer" "Bourns"
			(at 0 0 270)
			(unlocked yes)
			(layer "B.Fab")
			(hide yes)
			(effects
				(font
					(size 1 1)
					(thickness 0.15)
				)
				(justify mirror)
			)
		)
		(property "License" "Apache-2.0"
			(at 0 0 270)
			(unlocked yes)
			(layer "B.Fab")
			(hide yes)
			(effects
				(font
					(size 1 1)
					(thickness 0.15)
				)
				(justify mirror)
			)
		)
		(property "Author" "Antmicro"
			(at 0 0 270)
			(unlocked yes)
			(layer "B.Fab")
			(hide yes)
			(effects
				(font
					(size 1 1)
					(thickness 0.15)
				)
				(justify mirror)
			)
		)
		(property "Val" "10k"
			(at 0 0 270)
			(unlocked yes)
			(layer "B.Fab")
			(hide yes)
			(effects
				(font
					(size 1 1)
					(thickness 0.15)
				)
				(justify mirror)
			)
		)
		(property "Tolerance" "1%"
			(at 0 0 270)
			(unlocked yes)
			(layer "B.Fab")
			(hide yes)
			(effects
				(font
					(size 1 1)
					(thickness 0.15)
				)
				(justify mirror)
			)
		)
		(sheetname "/Power/")
		(sheetfile "power.kicad_sch")
		(attr smd)
		(fp_rect
			(start -0.925 0.47)
			(end 0.925 -0.47)
			(stroke
				(width 0.05)
				(type default)
			)
			(fill no)
			(layer "B.CrtYd")
		)
		(fp_rect
			(start -0.5 0.25)
			(end 0.5 -0.25)
			(stroke
				(width 0.15)
				(type solid)
			)
			(fill no)
			(layer "B.Fab")
		)
		(fp_text user "Author: Antmicro"
			(at -0.95 -4.169 90)
			(layer "B.Fab")
			(effects
				(font
					(size 0.7 0.7)
					(thickness 0.15)
				)
				(justify right top mirror)
			)
		)
		(fp_text user "${REFERENCE}"
			(at -0.95 -3.168 90)
			(layer "B.Fab")
			(effects
				(font
					(size 0.7 0.7)
					(thickness 0.15)
				)
				(justify right top mirror)
			)
		)
		(fp_text user "License: Apache-2.0"
			(at -0.95 -5.169 90)
			(layer "B.Fab")
			(effects
				(font
					(size 0.7 0.7)
					(thickness 0.15)
				)
				(justify right top mirror)
			)
		)
		(pad "1" smd roundrect
			(at -0.48 0 90)
			(size 0.59 0.64)
			(layers "B.Cu" "B.Mask" "B.Paste")
			(roundrect_rratio 0.25)
			(net 1 "GND")
			(pintype "passive")
		)
		(pad "2" smd roundrect
			(at 0.48 0 90)
			(size 0.59 0.64)
			(layers "B.Cu" "B.Mask" "B.Paste")
			(roundrect_rratio 0.25)
			(net 11 "+1V8")
			(pintype "passive")
		)
	)
	(footprint "antmicro-footprints:R_0402_1005Metric"
		(layer "B.Cu")
		(at 188.9 121.7 90)
		(descr "Resistor SMD 0402")
		(tags "resistor SMD 0402")
		(property "Reference" "R385"
			(at -3.7 -0.4 90)
			(layer "B.SilkS")
			(effects
				(font
					(size 0.7 0.7)
					(thickness 0.15)
				)
				(justify right top mirror)
			)
		)
		(property "Value" "R_0R_0402"
			(at -1.011843 -1.772047 90)
			(layer "B.Fab")
			(effects
				(font
					(size 0.7 0.7)
					(thickness 0.15)
				)
				(justify right top mirror)
			)
		)
		(property "Datasheet" "https://industrial.panasonic.com/cdbs/www-data/pdf/RDA0000/AOA0000C301.pdf"
			(at 0 0 90)
			(layer "B.Fab")
			(hide yes)
			(effects
				(font
					(size 1.27 1.27)
					(thickness 0.15)
				)
				(justify mirror)
			)
		)
		(property "Description" "SMD Chip Resistor, Jumper, 0 ohm, 100 mW, 0402 [1005 Metric], Thick Film, General Purpose"
			(at 0 0 90)
			(layer "B.Fab")
			(hide yes)
			(effects
				(font
					(size 1.27 1.27)
					(thickness 0.15)
				)
				(justify mirror)
			)
		)
		(property "MPN" "ERJ2GE0R00X"
			(at 0 0 270)
			(unlocked yes)
			(layer "B.Fab")
			(hide yes)
			(effects
				(font
					(size 1 1)
					(thickness 0.15)
				)
				(justify mirror)
			)
		)
		(property "Manufacturer" "Panasonic"
			(at 0 0 270)
			(unlocked yes)
			(layer "B.Fab")
			(hide yes)
			(effects
				(font
					(size 1 1)
					(thickness 0.15)
				)
				(justify mirror)
			)
		)
		(property "License" "Apache-2.0"
			(at 0 0 270)
			(unlocked yes)
			(layer "B.Fab")
			(hide yes)
			(effects
				(font
					(size 1 1)
					(thickness 0.15)
				)
				(justify mirror)
			)
		)
		(property "Author" "Antmicro"
			(at 0 0 270)
			(unlocked yes)
			(layer "B.Fab")
			(hide yes)
			(effects
				(font
					(size 1 1)
					(thickness 0.15)
				)
				(justify mirror)
			)
		)
		(property "Val" "0R"
			(at 0 0 270)
			(unlocked yes)
			(layer "B.Fab")
			(hide yes)
			(effects
				(font
					(size 1 1)
					(thickness 0.15)
				)
				(justify mirror)
			)
		)
		(property "Tolerance" "~"
			(at 0 0 270)
			(unlocked yes)
			(layer "B.Fab")
			(hide yes)
			(effects
				(font
					(size 1 1)
					(thickness 0.15)
				)
				(justify mirror)
			)
		)
		(property "Current" "1A"
			(at 0 0 270)
			(unlocked yes)
			(layer "B.Fab")
			(hide yes)
			(effects
				(font
					(size 1 1)
					(thickness 0.15)
				)
				(justify mirror)
			)
		)
		(sheetname "/USB Debug, PD/")
		(sheetfile "usb_debug_pd.kicad_sch")
		(attr smd exclude_from_pos_files exclude_from_bom dnp)
		(fp_rect
			(start -0.925 0.47)
			(end 0.925 -0.47)
			(stroke
				(width 0.05)
				(type default)
			)
			(fill no)
			(layer "B.CrtYd")
		)
		(fp_rect
			(start -0.5 0.25)
			(end 0.5 -0.25)
			(stroke
				(width 0.15)
				(type solid)
			)
			(fill no)
			(layer "B.Fab")
		)
		(fp_text user "Author: Antmicro"
			(at -0.95 -4.169 90)
			(layer "B.Fab")
			(effects
				(font
					(size 0.7 0.7)
					(thickness 0.15)
				)
				(justify right top mirror)
			)
		)
		(fp_text user "${REFERENCE}"
			(at -0.95 -3.168 90)
			(layer "B.Fab")
			(effects
				(font
					(size 0.7 0.7)
					(thickness 0.15)
				)
				(justify right top mirror)
			)
		)
		(fp_text user "License: Apache-2.0"
			(at -0.95 -5.169 90)
			(layer "B.Fab")
			(effects
				(font
					(size 0.7 0.7)
					(thickness 0.15)
				)
				(justify right top mirror)
			)
		)
		(pad "1" smd roundrect
			(at -0.48 0 90)
			(size 0.59 0.64)
			(layers "B.Cu" "B.Mask" "B.Paste")
			(roundrect_rratio 0.25)
			(net 532 "/USB Debug, PD/SCK")
			(pintype "passive")
		)
		(pad "2" smd roundrect
			(at 0.48 0 90)
			(size 0.59 0.64)
			(layers "B.Cu" "B.Mask" "B.Paste")
			(roundrect_rratio 0.25)
			(net 928 "/USB Debug, PD/SPI_{HUB_DEBUG}.SCK")
			(pintype "passive")
		)
	)
	(footprint "antmicro-footprints:QFN-32-1EP_5x5mm"
		(layer "B.Cu")
		(at 128.0345 146.571 -90)
		(property "Reference" "U14"
			(at -1.311 3.041 90)
			(layer "B.SilkS")
			(effects
				(font
					(size 0.7 0.7)
					(thickness 0.15)
				)
				(justify left bottom mirror)
			)
		)
		(property "Value" "SLB9673AU20FW2610XTMA1"
			(at -4.939 -3.91 90)
			(layer "B.Fab")
			(effects
				(font
					(size 0.7 0.7)
					(thickness 0.15)
				)
				(justify left bottom mirror)
			)
		)
		(property "Datasheet" "https://eu.mouser.com/datasheet/2/196/Infineon_OPTIGA_TPM_SLB_9673_FW26_DataSheet_v01_30-3363760.pdf"
			(at 0 0 90)
			(layer "B.Fab")
			(hide yes)
			(effects
				(font
					(size 1.27 1.27)
					(thickness 0.15)
				)
				(justify mirror)
			)
		)
		(property "Description" "Security ICs / Authentication ICs"
			(at 0 0 90)
			(layer "B.Fab")
			(hide yes)
			(effects
				(font
					(size 1.27 1.27)
					(thickness 0.15)
				)
				(justify mirror)
			)
		)
		(property "MPN" "SLB9673AU20FW2610XTMA1"
			(at 0 0 90)
			(unlocked yes)
			(layer "B.Fab")
			(hide yes)
			(effects
				(font
					(size 1 1)
					(thickness 0.15)
				)
				(justify mirror)
			)
		)
		(property "Manufacturer" "Infineon"
			(at 0 0 90)
			(unlocked yes)
			(layer "B.Fab")
			(hide yes)
			(effects
				(font
					(size 1 1)
					(thickness 0.15)
				)
				(justify mirror)
			)
		)
		(property "Author" "Antmicro"
			(at 0 0 90)
			(unlocked yes)
			(layer "B.Fab")
			(hide yes)
			(effects
				(font
					(size 1 1)
					(thickness 0.15)
				)
				(justify mirror)
			)
		)
		(property "License" "Apache-2.0"
			(at 0 0 90)
			(unlocked yes)
			(layer "B.Fab")
			(hide yes)
			(effects
				(font
					(size 1 1)
					(thickness 0.15)
				)
				(justify mirror)
			)
		)
		(sheetname "/Peripherals/")
		(sheetfile "peripherals.kicad_sch")
		(attr smd)
		(fp_line
			(start -2.221 2.551)
			(end -2.62 2.149)
			(stroke
				(width 0.15)
				(type solid)
			)
			(layer "B.SilkS")
		)
		(fp_line
			(start 2.581 2.551)
			(end 2.178 2.551)
			(stroke
				(width 0.15)
				(type solid)
			)
			(layer "B.SilkS")
		)
		(fp_line
			(start 2.581 2.551)
			(end 2.581 2.149)
			(stroke
				(width 0.15)
				(type solid)
			)
			(layer "B.SilkS")
		)
		(fp_line
			(start 2.581 -2.249)
			(end 2.581 -2.648)
			(stroke
				(width 0.15)
				(type solid)
			)
			(layer "B.SilkS")
		)
		(fp_line
			(start -2.62 -2.648)
			(end -2.62 -2.249)
			(stroke
				(width 0.15)
				(type solid)
			)
			(layer "B.SilkS")
		)
		(fp_line
			(start -2.221 -2.648)
			(end -2.62 -2.648)
			(stroke
				(width 0.15)
				(type solid)
			)
			(layer "B.SilkS")
		)
		(fp_line
			(start 2.581 -2.648)
			(end 2.178 -2.648)
			(stroke
				(width 0.15)
				(type solid)
			)
			(layer "B.SilkS")
		)
		(fp_circle
			(center -3.25 1.702)
			(end -3.2 1.702)
			(stroke
				(width 0.15)
				(type solid)
			)
			(fill yes)
			(layer "B.SilkS")
		)
		(fp_rect
			(start -1.446 0.175)
			(end -0.246 1.375)
			(stroke
				(width 0.2)
				(type solid)
			)
			(fill yes)
			(layer "B.Paste")
		)
		(fp_rect
			(start 0.203 0.175)
			(end 1.403 1.375)
			(stroke
				(width 0.2)
				(type solid)
			)
			(fill yes)
			(layer "B.Paste")
		)
		(fp_rect
			(start -1.446 -1.474)
			(end -0.246 -0.274)
			(stroke
				(width 0.2)
				(type solid)
			)
			(fill yes)
			(layer "B.Paste")
		)
		(fp_rect
			(start 0.203 -1.474)
			(end 1.403 -0.274)
			(stroke
				(width 0.2)
				(type solid)
			)
			(fill yes)
			(layer "B.Paste")
		)
		(fp_rect
			(start -2.74 2.75)
			(end 2.75 -2.74)
			(stroke
				(width 0.05)
				(type solid)
			)
			(fill no)
			(layer "B.CrtYd")
		)
		(fp_line
			(start -2.499 2.299)
			(end -2.298 2.5)
			(stroke
				(width 0.15)
				(type solid)
			)
			(layer "B.Fab")
		)
		(fp_rect
			(start -2.499 2.5)
			(end 2.5 -2.499)
			(stroke
				(width 0.15)
				(type solid)
			)
			(fill no)
			(layer "B.Fab")
		)
		(fp_text user "${REFERENCE}"
			(at -4.939 -7.11 90)
			(layer "B.Fab")
			(effects
				(font
					(size 0.7 0.7)
					(thickness 0.15)
				)
				(justify left bottom mirror)
			)
		)
		(fp_text user "License: Apache-2.0"
			(at -4.939 -5.91 90)
			(layer "B.Fab")
			(effects
				(font
					(size 0.7 0.7)
					(thickness 0.15)
				)
				(justify left bottom mirror)
			)
		)
		(fp_text user "Author: Antmicro"
			(at -4.939 -8.31 90)
			(layer "B.Fab")
			(effects
				(font
					(size 0.7 0.7)
					(thickness 0.15)
				)
				(justify left bottom mirror)
			)
		)
		(pad "1" smd rect
			(at -2.495 1.702)
			(size 0.28 0.85)
			(layers "B.Cu" "B.Mask" "B.Paste")
			(net 2 "+3V3")
			(pinfunction "VDD")
			(pintype "power_in")
			(solder_mask_margin 0.07)
		)
		(pad "2" smd rect
			(at -2.495 1.2)
			(size 0.28 0.85)
			(layers "B.Cu" "B.Mask" "B.Paste")
			(net 1 "GND")
			(pinfunction "GND")
			(pintype "power_in")
			(solder_mask_margin 0.07)
		)
		(pad "3" smd rect
			(at -2.495 0.701)
			(size 0.28 0.85)
			(layers "B.Cu" "B.Mask" "B.Paste")
			(net 1064 "unconnected-(U14-GPIO_00-Pad3)")
			(pinfunction "GPIO_00")
			(pintype "passive+no_connect")
			(solder_mask_margin 0.07)
		)
		(pad "4" smd rect
			(at -2.495 0.201)
			(size 0.28 0.85)
			(layers "B.Cu" "B.Mask" "B.Paste")
			(net 1068 "unconnected-(U14-GPIO_01-Pad4)")
			(pinfunction "GPIO_01")
			(pintype "passive+no_connect")
			(solder_mask_margin 0.07)
		)
		(pad "5" smd rect
			(at -2.495 -0.296)
			(size 0.28 0.85)
			(layers "B.Cu" "B.Mask" "B.Paste")
			(net 1072 "unconnected-(U14-NCI-Pad5)")
			(pinfunction "NCI")
			(pintype "no_connect")
			(solder_mask_margin 0.07)
		)
		(pad "6" smd rect
			(at -2.495 -0.8)
			(size 0.28 0.85)
			(layers "B.Cu" "B.Mask" "B.Paste")
			(net 1077 "unconnected-(U14-NC-Pad6)")
			(pinfunction "NC")
			(pintype "no_connect")
			(solder_mask_margin 0.07)
		)
		(pad "7" smd rect
			(at -2.495 -1.3)
			(size 0.28 0.85)
			(layers "B.Cu" "B.Mask" "B.Paste")
			(net 1069 "unconnected-(U14-GPIO_02-Pad7)")
			(pinfunction "GPIO_02")
			(pintype "passive+no_connect")
			(solder_mask_margin 0.07)
		)
		(pad "8" smd rect
			(at -2.495 -1.8)
			(size 0.28 0.85)
			(layers "B.Cu" "B.Mask" "B.Paste")
			(net 2 "+3V3")
			(pinfunction "NCI/VDD")
			(pintype "passive")
			(solder_mask_margin 0.07)
		)
		(pad "9" smd rect
			(at -1.768 -2.523)
			(size 0.85 0.28)
			(layers "B.Cu" "B.Mask" "B.Paste")
			(net 1 "GND")
			(pinfunction "GND")
			(pintype "passive")
			(solder_mask_margin 0.07)
		)
		(pad "10" smd rect
			(at -1.269 -2.523)
			(size 0.85 0.28)
			(layers "B.Cu" "B.Mask" "B.Paste")
			(net 1066 "unconnected-(U14-NCI-Pad10)")
			(pinfunction "NCI")
			(pintype "no_connect")
			(solder_mask_margin 0.07)
		)
		(pad "11" smd rect
			(at -0.772 -2.523)
			(size 0.85 0.28)
			(layers "B.Cu" "B.Mask" "B.Paste")
			(net 1061 "unconnected-(U14-NCI-Pad11)")
			(pinfunction "NCI")
			(pintype "no_connect")
			(solder_mask_margin 0.07)
		)
		(pad "12" smd rect
			(at -0.272 -2.523)
			(size 0.85 0.28)
			(layers "B.Cu" "B.Mask" "B.Paste")
			(net 1065 "unconnected-(U14-NCI-Pad12)")
			(pinfunction "NCI")
			(pintype "no_connect")
			(solder_mask_margin 0.07)
		)
		(pad "13" smd rect
			(at 0.229 -2.523)
			(size 0.85 0.28)
			(layers "B.Cu" "B.Mask" "B.Paste")
			(net 1074 "unconnected-(U14-NCI-Pad13)")
			(pinfunction "NCI")
			(pintype "no_connect")
			(solder_mask_margin 0.07)
		)
		(pad "14" smd rect
			(at 0.728 -2.523)
			(size 0.85 0.28)
			(layers "B.Cu" "B.Mask" "B.Paste")
			(net 2 "+3V3")
			(pinfunction "VDD")
			(pintype "passive")
			(solder_mask_margin 0.07)
		)
		(pad "15" smd rect
			(at 1.23 -2.523)
			(size 0.85 0.28)
			(layers "B.Cu" "B.Mask" "B.Paste")
			(net 1076 "unconnected-(U14-NCI-Pad15)")
			(pinfunction "NCI")
			(pintype "no_connect")
			(solder_mask_margin 0.07)
		)
		(pad "16" smd rect
			(at 1.73 -2.523)
			(size 0.85 0.28)
			(layers "B.Cu" "B.Mask" "B.Paste")
			(net 1 "GND")
			(pinfunction "NCI/GND")
			(pintype "passive")
			(solder_mask_margin 0.07)
		)
		(pad "17" smd rect
			(at 2.456 -1.8)
			(size 0.28 0.85)
			(layers "B.Cu" "B.Mask" "B.Paste")
			(net 1089 "Net-(Q1-D)")
			(pinfunction "RST#")
			(pintype "passive")
			(solder_mask_margin 0.07)
		)
		(pad "18" smd rect
			(at 2.456 -1.3)
			(size 0.28 0.85)
			(layers "B.Cu" "B.Mask" "B.Paste")
			(net 149 "/Peripherals/TPM_IRQ")
			(pinfunction "I2C_PIRQ#")
			(pintype "passive")
			(solder_mask_margin 0.07)
		)
		(pad "19" smd rect
			(at 2.456 -0.8)
			(size 0.28 0.85)
			(layers "B.Cu" "B.Mask" "B.Paste")
			(net 1067 "unconnected-(U14-NC-Pad19)")
			(pinfunction "NC")
			(pintype "no_connect")
			(solder_mask_margin 0.07)
		)
		(pad "20" smd rect
			(at 2.456 -0.296)
			(size 0.28 0.85)
			(layers "B.Cu" "B.Mask" "B.Paste")
			(net 2 "+3V3")
			(pinfunction "TEST#")
			(pintype "passive")
			(solder_mask_margin 0.07)
		)
		(pad "21" smd rect
			(at 2.456 0.201)
			(size 0.28 0.85)
			(layers "B.Cu" "B.Mask" "B.Paste")
			(net 1062 "unconnected-(U14-NC-Pad21)")
			(pinfunction "NC")
			(pintype "no_connect")
			(solder_mask_margin 0.07)
		)
		(pad "22" smd rect
			(at 2.456 0.701)
			(size 0.28 0.85)
			(layers "B.Cu" "B.Mask" "B.Paste")
			(net 2 "+3V3")
			(pinfunction "VDD")
			(pintype "passive")
			(solder_mask_margin 0.07)
		)
		(pad "23" smd rect
			(at 2.456 1.2)
			(size 0.28 0.85)
			(layers "B.Cu" "B.Mask" "B.Paste")
			(net 1 "GND")
			(pinfunction "GND")
			(pintype "passive")
			(solder_mask_margin 0.07)
		)
		(pad "24" smd rect
			(at 2.456 1.702)
			(size 0.28 0.85)
			(layers "B.Cu" "B.Mask" "B.Paste")
			(net 1063 "unconnected-(U14-NC-Pad24)")
			(pinfunction "NC")
			(pintype "no_connect")
			(solder_mask_margin 0.07)
		)
		(pad "25" smd rect
			(at 1.73 2.426)
			(size 0.85 0.28)
			(layers "B.Cu" "B.Mask" "B.Paste")
			(net 1073 "unconnected-(U14-NCI-Pad25)")
			(pinfunction "NCI")
			(pintype "no_connect")
			(solder_mask_margin 0.07)
		)
		(pad "26" smd rect
			(at 1.23 2.426)
			(size 0.85 0.28)
			(layers "B.Cu" "B.Mask" "B.Paste")
			(net 1071 "unconnected-(U14-NCI-Pad26)")
			(pinfunction "NCI")
			(pintype "no_connect")
			(solder_mask_margin 0.07)
		)
		(pad "27" smd rect
			(at 0.728 2.426)
			(size 0.85 0.28)
			(layers "B.Cu" "B.Mask" "B.Paste")
			(net 1075 "unconnected-(U14-NCI-Pad27)")
			(pinfunction "NCI")
			(pintype "no_connect")
			(solder_mask_margin 0.07)
		)
		(pad "28" smd rect
			(at 0.229 2.426)
			(size 0.85 0.28)
			(layers "B.Cu" "B.Mask" "B.Paste")
			(net 1060 "unconnected-(U14-NCI-Pad28)")
			(pinfunction "NCI")
			(pintype "no_connect")
			(solder_mask_margin 0.07)
		)
		(pad "29" smd rect
			(at -0.272 2.426)
			(size 0.85 0.28)
			(layers "B.Cu" "B.Mask" "B.Paste")
			(net 850 "/I2C_{SYS}.SDA")
			(pinfunction "SDA")
			(pintype "passive")
			(solder_mask_margin 0.07)
		)
		(pad "30" smd rect
			(at -0.772 2.426)
			(size 0.85 0.28)
			(layers "B.Cu" "B.Mask" "B.Paste")
			(net 853 "/I2C_{SYS}.SCL")
			(pinfunction "SCL")
			(pintype "passive")
			(solder_mask_margin 0.07)
		)
		(pad "31" smd rect
			(at -1.269 2.426)
			(size 0.85 0.28)
			(layers "B.Cu" "B.Mask" "B.Paste")
			(net 1070 "unconnected-(U14-NCI-Pad31)")
			(pinfunction "NCI")
			(pintype "no_connect")
			(solder_mask_margin 0.07)
		)
		(pad "32" smd rect
			(at -1.768 2.426)
			(size 0.85 0.28)
			(layers "B.Cu" "B.Mask" "B.Paste")
			(net 1 "GND")
			(pinfunction "GND")
			(pintype "passive")
			(solder_mask_margin 0.07)
		)
		(pad "33" smd rect
			(at -0.02 -0.048)
			(size 3.45 3.45)
			(layers "B.Cu" "B.Mask")
			(net 1 "GND")
			(pinfunction "EP")
			(pintype "passive")
		)
	)
	(footprint "antmicro-footprints:R_0402_1005Metric"
		(layer "B.Cu")
		(at 216.1 126.5)
		(descr "Resistor SMD 0402")
		(tags "resistor SMD 0402")
		(property "Reference" "R48"
			(at 1.029 -0.3 0)
			(layer "B.SilkS")
			(effects
				(font
					(size 0.7 0.7)
					(thickness 0.15)
				)
				(justify right top mirror)
			)
		)
		(property "Value" "R_0R_0402"
			(at -1.011843 -1.772046 0)
			(layer "B.Fab")
			(effects
				(font
					(size 0.7 0.7)
					(thickness 0.15)
				)
				(justify right top mirror)
			)
		)
		(property "Datasheet" "https://industrial.panasonic.com/cdbs/www-data/pdf/RDA0000/AOA0000C301.pdf"
			(at 0 0 0)
			(layer "B.Fab")
			(hide yes)
			(effects
				(font
					(size 1.27 1.27)
					(thickness 0.15)
				)
				(justify mirror)
			)
		)
		(property "Description" "SMD Chip Resistor, Jumper, 0 ohm, 100 mW, 0402 [1005 Metric], Thick Film, General Purpose"
			(at 0 0 0)
			(layer "B.Fab")
			(hide yes)
			(effects
				(font
					(size 1.27 1.27)
					(thickness 0.15)
				)
				(justify mirror)
			)
		)
		(property "Manufacturer" "Panasonic"
			(at 0 0 180)
			(unlocked yes)
			(layer "B.Fab")
			(hide yes)
			(effects
				(font
					(size 1 1)
					(thickness 0.15)
				)
				(justify mirror)
			)
		)
		(property "MPN" "ERJ2GE0R00X"
			(at 0 0 180)
			(unlocked yes)
			(layer "B.Fab")
			(hide yes)
			(effects
				(font
					(size 1 1)
					(thickness 0.15)
				)
				(justify mirror)
			)
		)
		(property "Val" "0R"
			(at 0 0 180)
			(unlocked yes)
			(layer "B.Fab")
			(hide yes)
			(effects
				(font
					(size 1 1)
					(thickness 0.15)
				)
				(justify mirror)
			)
		)
		(property "License" "Apache-2.0"
			(at 0 0 180)
			(unlocked yes)
			(layer "B.Fab")
			(hide yes)
			(effects
				(font
					(size 1 1)
					(thickness 0.15)
				)
				(justify mirror)
			)
		)
		(property "Author" "Antmicro"
			(at 0 0 180)
			(unlocked yes)
			(layer "B.Fab")
			(hide yes)
			(effects
				(font
					(size 1 1)
					(thickness 0.15)
				)
				(justify mirror)
			)
		)
		(property "Tolerance" "~"
			(at 0 0 180)
			(unlocked yes)
			(layer "B.Fab")
			(hide yes)
			(effects
				(font
					(size 1 1)
					(thickness 0.15)
				)
				(justify mirror)
			)
		)
		(property "Current" "1A"
			(at 0 0 180)
			(unlocked yes)
			(layer "B.Fab")
			(hide yes)
			(effects
				(font
					(size 1 1)
					(thickness 0.15)
				)
				(justify mirror)
			)
		)
		(sheetname "/USB Hub/")
		(sheetfile "usb_hub.kicad_sch")
		(attr smd)
		(fp_poly
			(pts
				(xy -0.925 0.47) (xy -0.925 -0.47) (xy 0.925 -0.47) (xy 0.925 0.47)
			)
			(stroke
				(width 0.05)
				(type default)
			)
			(fill no)
			(layer "B.CrtYd")
		)
		(fp_poly
			(pts
				(xy -0.5 0.25) (xy -0.5 -0.25) (xy 0.5 -0.25) (xy 0.5 0.25)
			)
			(stroke
				(width 0.15)
				(type solid)
			)
			(fill no)
			(layer "B.Fab")
		)
		(fp_text user "${REFERENCE}"
			(at -0.95 -3.168 0)
			(layer "B.Fab")
			(effects
				(font
					(size 0.7 0.7)
					(thickness 0.15)
				)
				(justify right top mirror)
			)
		)
		(fp_text user "Author: Antmicro"
			(at -0.95 -4.169 0)
			(layer "B.Fab")
			(effects
				(font
					(size 0.7 0.7)
					(thickness 0.15)
				)
				(justify right top mirror)
			)
		)
		(fp_text user "License: Apache-2.0"
			(at -0.949999 -5.169 0)
			(layer "B.Fab")
			(effects
				(font
					(size 0.7 0.7)
					(thickness 0.15)
				)
				(justify right top mirror)
			)
		)
		(pad "1" smd roundrect
			(at -0.48 0)
			(size 0.59 0.64)
			(layers "B.Cu" "B.Mask" "B.Paste")
			(roundrect_rratio 0.25)
			(net 1138 "Net-(U21-USB2DN_DP4)")
			(pintype "passive")
		)
		(pad "2" smd roundrect
			(at 0.48 0)
			(size 0.59 0.64)
			(layers "B.Cu" "B.Mask" "B.Paste")
			(roundrect_rratio 0.25)
			(net 2 "+3V3")
			(pintype "passive")
		)
	)
	(footprint "antmicro-footprints:SOT-523"
		(layer "B.Cu")
		(at 223.2 109.2 180)
		(property "Reference" "Q15"
			(at -1.1 -1.2 90)
			(layer "B.SilkS")
			(effects
				(font
					(size 0.7 0.7)
					(thickness 0.15)
				)
				(justify left bottom mirror)
			)
		)
		(property "Value" "DMG1012T-7"
			(at 0.1 -1.824 0)
			(layer "B.Fab")
			(effects
				(font
					(size 0.7 0.7)
					(thickness 0.15)
				)
				(justify left bottom mirror)
			)
		)
		(property "Datasheet" "https://www.diodes.com/assets/Datasheets/ds31783.pdf"
			(at 0 0 0)
			(layer "B.Fab")
			(hide yes)
			(effects
				(font
					(size 1.27 1.27)
					(thickness 0.15)
				)
				(justify mirror)
			)
		)
		(property "Description" "Power MOSFET, N Channel, 20 V, 630 mA, 0.3 ohm, SOT-523, Surface Mount"
			(at 0 0 0)
			(layer "B.Fab")
			(hide yes)
			(effects
				(font
					(size 1.27 1.27)
					(thickness 0.15)
				)
				(justify mirror)
			)
		)
		(property "MPN" "DMG1012T-7"
			(at 0 0 0)
			(unlocked yes)
			(layer "B.Fab")
			(hide yes)
			(effects
				(font
					(size 1 1)
					(thickness 0.15)
				)
				(justify mirror)
			)
		)
		(property "Manufacturer" "Diodes Incorporated"
			(at 0 0 0)
			(unlocked yes)
			(layer "B.Fab")
			(hide yes)
			(effects
				(font
					(size 1 1)
					(thickness 0.15)
				)
				(justify mirror)
			)
		)
		(property "Author" "Antmicro"
			(at 0 0 0)
			(unlocked yes)
			(layer "B.Fab")
			(hide yes)
			(effects
				(font
					(size 1 1)
					(thickness 0.15)
				)
				(justify mirror)
			)
		)
		(property "License" "Apache-2.0"
			(at 0 0 0)
			(unlocked yes)
			(layer "B.Fab")
			(hide yes)
			(effects
				(font
					(size 1 1)
					(thickness 0.15)
				)
				(justify mirror)
			)
		)
		(sheetname "/Recovery USB/")
		(sheetfile "recovery_usb.kicad_sch")
		(attr smd)
		(fp_line
			(start -0.277 0.551)
			(end -0.277 0.75)
			(stroke
				(width 0.15)
				(type solid)
			)
			(layer "B.SilkS")
		)
		(fp_line
			(start -0.725 0.551)
			(end -0.277 0.551)
			(stroke
				(width 0.15)
				(type solid)
			)
			(layer "B.SilkS")
		)
		(fp_line
			(start -0.927 0.351)
			(end -0.725 0.551)
			(stroke
				(width 0.15)
				(type solid)
			)
			(layer "B.SilkS")
		)
		(fp_line
			(start -0.927 0.051)
			(end -0.927 0.351)
			(stroke
				(width 0.15)
				(type solid)
			)
			(layer "B.SilkS")
		)
		(fp_circle
			(center -0.9652 -0.9652)
			(end -0.9152 -0.9652)
			(stroke
				(width 0.15)
				(type solid)
			)
			(fill yes)
			(layer "B.SilkS")
		)
		(fp_line
			(start 1.1 1.16)
			(end 1.1 -1.15)
			(stroke
				(width 0.05)
				(type solid)
			)
			(layer "B.CrtYd")
		)
		(fp_line
			(start -1.12 1.16)
			(end 1.1 1.16)
			(stroke
				(width 0.05)
				(type solid)
			)
			(layer "B.CrtYd")
		)
		(fp_line
			(start -1.12 1.16)
			(end -1.12 -1.15)
			(stroke
				(width 0.05)
				(type solid)
			)
			(layer "B.CrtYd")
		)
		(fp_line
			(start -1.12 -1.15)
			(end 1.1 -1.15)
			(stroke
				(width 0.05)
				(type solid)
			)
			(layer "B.CrtYd")
		)
		(fp_line
			(start 0.8 0.425)
			(end 0.8 -0.424)
			(stroke
				(width 0.15)
				(type solid)
			)
			(layer "B.Fab")
		)
		(fp_line
			(start 0.8 0.425)
			(end -0.652 0.425)
			(stroke
				(width 0.15)
				(type solid)
			)
			(layer "B.Fab")
		)
		(fp_line
			(start 0.8 -0.424)
			(end -0.802 -0.424)
			(stroke
				(width 0.15)
				(type solid)
			)
			(layer "B.Fab")
		)
		(fp_line
			(start -0.652 0.425)
			(end -0.802 0.276)
			(stroke
				(width 0.15)
				(type solid)
			)
			(layer "B.Fab")
		)
		(fp_line
			(start -0.802 0.276)
			(end -0.802 -0.424)
			(stroke
				(width 0.15)
				(type solid)
			)
			(layer "B.Fab")
		)
		(fp_circle
			(center -0.9652 -0.9652)
			(end -0.9144 -0.9652)
			(stroke
				(width 0.15)
				(type solid)
			)
			(fill no)
			(layer "B.Fab")
		)
		(fp_text user "${REFERENCE}"
			(at -1.12 -3.824 0)
			(layer "B.Fab")
			(effects
				(font
					(size 0.7 0.7)
					(thickness 0.15)
				)
				(justify left bottom mirror)
			)
		)
		(fp_text user "License: Apache-2.0"
			(at -1.12 -5.024 0)
			(layer "B.Fab")
			(effects
				(font
					(size 0.7 0.7)
					(thickness 0.15)
				)
				(justify left bottom mirror)
			)
		)
		(fp_text user "Author: Antmicro"
			(at -1.12 -6.224 0)
			(layer "B.Fab")
			(effects
				(font
					(size 0.7 0.7)
					(thickness 0.15)
				)
				(justify left bottom mirror)
			)
		)
		(pad "1" smd rect
			(at -0.5 -0.65 180)
			(size 0.4 0.51)
			(layers "B.Cu" "B.Mask" "B.Paste")
			(net 287 "/Recovery USB/USBC2_VBUS")
			(pinfunction "G")
			(pintype "input")
		)
		(pad "2" smd rect
			(at 0.498 -0.65 180)
			(size 0.4 0.51)
			(layers "B.Cu" "B.Mask" "B.Paste")
			(net 1 "GND")
			(pinfunction "S")
			(pintype "passive")
		)
		(pad "3" smd rect
			(at 0 0.652 180)
			(size 0.4 0.51)
			(layers "B.Cu" "B.Mask" "B.Paste")
			(net 1018 "/Recovery USB/USBC2_VBUS_DET")
			(pinfunction "D")
			(pintype "passive")
		)
	)
	(footprint "antmicro-footprints:TP_SMD_0.75mm"
		(layer "B.Cu")
		(at 63.5 121.999999)
		(property "Reference" "TP115"
			(at -0.5 1.800001 0)
			(layer "B.SilkS")
			(effects
				(font
					(size 0.7 0.7)
					(thickness 0.15)
				)
				(justify right top mirror)
			)
		)
		(property "Value" "TP_0.75mm_SMD"
			(at 0 -1.2 0)
			(layer "B.Fab")
			(effects
				(font
					(size 0.7 0.7)
					(thickness 0.15)
				)
				(justify right top mirror)
			)
		)
		(property "Description" "SMT test point"
			(at 0 0 0)
			(layer "B.Fab")
			(hide yes)
			(effects
				(font
					(size 1.27 1.27)
					(thickness 0.15)
				)
				(justify mirror)
			)
		)
		(property "MPN" ""
			(at 0 0 180)
			(unlocked yes)
			(layer "B.Fab")
			(hide yes)
			(effects
				(font
					(size 1 1)
					(thickness 0.15)
				)
				(justify mirror)
			)
		)
		(property "Manufacturer" ""
			(at 0 0 180)
			(unlocked yes)
			(layer "B.Fab")
			(hide yes)
			(effects
				(font
					(size 1 1)
					(thickness 0.15)
				)
				(justify mirror)
			)
		)
		(property "Author" "Antmicro"
			(at 0 0 180)
			(unlocked yes)
			(layer "B.Fab")
			(hide yes)
			(effects
				(font
					(size 1 1)
					(thickness 0.15)
				)
				(justify mirror)
			)
		)
		(property "License" "Apache-2.0"
			(at 0 0 180)
			(unlocked yes)
			(layer "B.Fab")
			(hide yes)
			(effects
				(font
					(size 1 1)
					(thickness 0.15)
				)
				(justify mirror)
			)
		)
		(sheetname "/Expansion connector/")
		(sheetfile "expansion_connector.kicad_sch")
		(attr exclude_from_pos_files exclude_from_bom)
		(fp_circle
			(center 0 0)
			(end 0.475 0)
			(stroke
				(width 0.05)
				(type default)
			)
			(fill no)
			(layer "B.CrtYd")
		)
		(fp_text user "License: Apache-2.0"
			(at -0.4 -5.101 0)
			(layer "B.Fab")
			(effects
				(font
					(size 0.7 0.7)
					(thickness 0.15)
				)
				(justify right top mirror)
			)
		)
		(fp_text user "Author: Antmicro"
			(at -0.4 -3.901 0)
			(layer "B.Fab")
			(effects
				(font
					(size 0.7 0.7)
					(thickness 0.15)
				)
				(justify right top mirror)
			)
		)
		(fp_text user "${REFERENCE}"
			(at -0.4 -2.7 0)
			(layer "B.Fab")
			(effects
				(font
					(size 0.7 0.7)
					(thickness 0.15)
				)
				(justify right top mirror)
			)
		)
		(pad "1" smd circle
			(at 0 0)
			(size 0.75 0.75)
			(layers "B.Cu" "B.Mask")
			(net 709 "Net-(J18-PadL33)")
			(pinfunction "1")
			(pintype "passive")
		)
	)
	(footprint "antmicro-footprints:C_0402_1005Metric"
		(layer "B.Cu")
		(at 178.405 78.175 180)
		(descr "Capacitor SMD 0402")
		(tags "capacitor SMD 0402")
		(property "Reference" "C264"
			(at 3.605 -0.425 0)
			(layer "B.SilkS")
			(effects
				(font
					(size 0.7 0.7)
					(thickness 0.15)
				)
				(justify left bottom mirror)
			)
		)
		(property "Value" "C_100n_0402"
			(at -1.022927 -2.155213 0)
			(layer "B.Fab")
			(effects
				(font
					(size 0.7 0.7)
					(thickness 0.15)
				)
				(justify left bottom mirror)
			)
		)
		(property "Datasheet" "https://www.murata.com/products/productdetail?partno=GRM155R61H104KE14%23"
			(at 0 0 0)
			(layer "B.Fab")
			(hide yes)
			(effects
				(font
					(size 1.27 1.27)
					(thickness 0.15)
				)
				(justify mirror)
			)
		)
		(property "Description" "SMD Multilayer Ceramic Capacitor, 0.1 µF, 50 V, 0402 [1005 Metric], ± 10%, X5R, GRM Series"
			(at 0 0 0)
			(layer "B.Fab")
			(hide yes)
			(effects
				(font
					(size 1.27 1.27)
					(thickness 0.15)
				)
				(justify mirror)
			)
		)
		(property "MPN" "GRM155R61H104KE14D"
			(at 0 0 0)
			(unlocked yes)
			(layer "B.Fab")
			(hide yes)
			(effects
				(font
					(size 1 1)
					(thickness 0.15)
				)
				(justify mirror)
			)
		)
		(property "Val" "100n"
			(at 0 0 0)
			(unlocked yes)
			(layer "B.Fab")
			(hide yes)
			(effects
				(font
					(size 1 1)
					(thickness 0.15)
				)
				(justify mirror)
			)
		)
		(property "Voltage" "50V"
			(at 0 0 0)
			(unlocked yes)
			(layer "B.Fab")
			(hide yes)
			(effects
				(font
					(size 1 1)
					(thickness 0.15)
				)
				(justify mirror)
			)
		)
		(property "Dielectric" "X5R"
			(at 0 0 0)
			(unlocked yes)
			(layer "B.Fab")
			(hide yes)
			(effects
				(font
					(size 1 1)
					(thickness 0.15)
				)
				(justify mirror)
			)
		)
		(property "Manufacturer" "Murata"
			(at 0 0 0)
			(unlocked yes)
			(layer "B.Fab")
			(hide yes)
			(effects
				(font
					(size 1 1)
					(thickness 0.15)
				)
				(justify mirror)
			)
		)
		(property "License" "Apache-2.0"
			(at 0 0 0)
			(unlocked yes)
			(layer "B.Fab")
			(hide yes)
			(effects
				(font
					(size 1 1)
					(thickness 0.15)
				)
				(justify mirror)
			)
		)
		(property "Author" "Antmicro"
			(at 0 0 0)
			(unlocked yes)
			(layer "B.Fab")
			(hide yes)
			(effects
				(font
					(size 1 1)
					(thickness 0.15)
				)
				(justify mirror)
			)
		)
		(sheetname "/Power/")
		(sheetfile "power.kicad_sch")
		(attr smd)
		(fp_rect
			(start -0.925 0.47)
			(end 0.925 -0.47)
			(stroke
				(width 0.05)
				(type default)
			)
			(fill no)
			(layer "B.CrtYd")
		)
		(fp_line
			(start 0.504 0.25)
			(end 0.504 -0.248)
			(stroke
				(width 0.15)
				(type solid)
			)
			(layer "B.Fab")
		)
		(fp_line
			(start 0.504 -0.248)
			(end -0.494 -0.248)
			(stroke
				(width 0.15)
				(type solid)
			)
			(layer "B.Fab")
		)
		(fp_line
			(start -0.494 0.25)
			(end 0.504 0.25)
			(stroke
				(width 0.15)
				(type solid)
			)
			(layer "B.Fab")
		)
		(fp_line
			(start -0.494 -0.248)
			(end -0.494 0.25)
			(stroke
				(width 0.15)
				(type solid)
			)
			(layer "B.Fab")
		)
		(fp_text user "License: Apache-2.0"
			(at -0.939 -5.799 0)
			(layer "B.Fab")
			(effects
				(font
					(size 0.7 0.7)
					(thickness 0.15)
				)
				(justify left bottom mirror)
			)
		)
		(fp_text user "Author: Antmicro"
			(at -0.939 -3.399 0)
			(layer "B.Fab")
			(effects
				(font
					(size 0.7 0.7)
					(thickness 0.15)
				)
				(justify left bottom mirror)
			)
		)
		(fp_text user "${REFERENCE}"
			(at -0.939 -4.599 0)
			(layer "B.Fab")
			(effects
				(font
					(size 0.7 0.7)
					(thickness 0.15)
				)
				(justify left bottom mirror)
			)
		)
		(pad "1" smd roundrect
			(at -0.48 0 180)
			(size 0.59 0.64)
			(layers "B.Cu" "B.Mask" "B.Paste")
			(roundrect_rratio 0.25)
			(net 1 "GND")
			(pintype "passive")
		)
		(pad "2" smd roundrect
			(at 0.48 0 180)
			(size 0.59 0.64)
			(layers "B.Cu" "B.Mask" "B.Paste")
			(roundrect_rratio 0.25)
			(net 904 "+20V")
			(pintype "passive")
		)
	)
	(footprint "antmicro-footprints:R_0402_1005Metric"
		(layer "B.Cu")
		(at 217.7 86.7 -90)
		(descr "Resistor SMD 0402")
		(tags "resistor SMD 0402")
		(property "Reference" "R133"
			(at -0.9 -2.5 90)
			(layer "B.SilkS")
			(effects
				(font
					(size 0.7 0.7)
					(thickness 0.15)
				)
				(justify left bottom mirror)
			)
		)
		(property "Value" "R_1k_0402"
			(at -1.011843 -1.772046 90)
			(layer "B.Fab")
			(effects
				(font
					(size 0.7 0.7)
					(thickness 0.15)
				)
				(justify left bottom mirror)
			)
		)
		(property "Datasheet" "https://www.bourns.com/docs/product-datasheets/cr.pdf"
			(at 0 0 90)
			(layer "B.Fab")
			(hide yes)
			(effects
				(font
					(size 1.27 1.27)
					(thickness 0.15)
				)
				(justify mirror)
			)
		)
		(property "Description" "SMD Chip Resistor, 1 kohm, ± 1%, 63 mW, 0402 [1005 Metric], Thick Film, General Purpose"
			(at 0 0 90)
			(layer "B.Fab")
			(hide yes)
			(effects
				(font
					(size 1.27 1.27)
					(thickness 0.15)
				)
				(justify mirror)
			)
		)
		(property "Manufacturer" "Bourns"
			(at 0 0 90)
			(unlocked yes)
			(layer "B.Fab")
			(hide yes)
			(effects
				(font
					(size 1 1)
					(thickness 0.15)
				)
				(justify mirror)
			)
		)
		(property "MPN" "CR0402-FX-1001GLF"
			(at 0 0 90)
			(unlocked yes)
			(layer "B.Fab")
			(hide yes)
			(effects
				(font
					(size 1 1)
					(thickness 0.15)
				)
				(justify mirror)
			)
		)
		(property "Val" "1k"
			(at 0 0 90)
			(unlocked yes)
			(layer "B.Fab")
			(hide yes)
			(effects
				(font
					(size 1 1)
					(thickness 0.15)
				)
				(justify mirror)
			)
		)
		(property "License" "Apache-2.0"
			(at 0 0 90)
			(unlocked yes)
			(layer "B.Fab")
			(hide yes)
			(effects
				(font
					(size 1 1)
					(thickness 0.15)
				)
				(justify mirror)
			)
		)
		(property "Author" "Antmicro"
			(at 0 0 90)
			(unlocked yes)
			(layer "B.Fab")
			(hide yes)
			(effects
				(font
					(size 1 1)
					(thickness 0.15)
				)
				(justify mirror)
			)
		)
		(property "Tolerance" "1%"
			(at 0 0 90)
			(unlocked yes)
			(layer "B.Fab")
			(hide yes)
			(effects
				(font
					(size 1 1)
					(thickness 0.15)
				)
				(justify mirror)
			)
		)
		(sheetname "/USB DP Alt mode/")
		(sheetfile "usb_dp.kicad_sch")
		(attr smd)
		(fp_poly
			(pts
				(xy -0.925 0.47) (xy 0.925 0.47) (xy 0.925 -0.47) (xy -0.925 -0.47)
			)
			(stroke
				(width 0.05)
				(type default)
			)
			(fill no)
			(layer "B.CrtYd")
		)
		(fp_poly
			(pts
				(xy -0.5 0.25) (xy 0.5 0.25) (xy 0.5 -0.25) (xy -0.5 -0.25)
			)
			(stroke
				(width 0.15)
				(type solid)
			)
			(fill no)
			(layer "B.Fab")
		)
		(fp_text user "License: Apache-2.0"
			(at -0.949999 -5.169 90)
			(layer "B.Fab")
			(effects
				(font
					(size 0.7 0.7)
					(thickness 0.15)
				)
				(justify left bottom mirror)
			)
		)
		(fp_text user "${REFERENCE}"
			(at -0.95 -3.168 90)
			(layer "B.Fab")
			(effects
				(font
					(size 0.7 0.7)
					(thickness 0.15)
				)
				(justify left bottom mirror)
			)
		)
		(fp_text user "Author: Antmicro"
			(at -0.95 -4.169 90)
			(layer "B.Fab")
			(effects
				(font
					(size 0.7 0.7)
					(thickness 0.15)
				)
				(justify left bottom mirror)
			)
		)
		(pad "1" smd roundrect
			(at -0.48 0 270)
			(size 0.59 0.64)
			(layers "B.Cu" "B.Mask" "B.Paste")
			(roundrect_rratio 0.25)
			(net 965 "/USB DP Alt mode/USBC1_SSEQ1")
			(pintype "passive")
		)
		(pad "2" smd roundrect
			(at 0.48 0 270)
			(size 0.59 0.64)
			(layers "B.Cu" "B.Mask" "B.Paste")
			(roundrect_rratio 0.25)
			(net 1 "GND")
			(pintype "passive")
		)
	)
	(footprint "antmicro-footprints:C_0603_1608Metric_EIA"
		(layer "B.Cu")
		(at 109.61 69.49)
		(descr "Capacitor SMD 0603, IPC-7351 Density Level A")
		(tags "Capacitor 0603")
		(property "Reference" "C22"
			(at 1.19 -0.89 180)
			(layer "B.SilkS")
			(effects
				(font
					(size 0.7 0.7)
					(thickness 0.15)
				)
				(justify left bottom mirror)
			)
		)
		(property "Value" "C_22u_16V_0603"
			(at -1.42757 -1.770288 180)
			(layer "B.Fab")
			(effects
				(font
					(size 0.7 0.7)
					(thickness 0.15)
				)
				(justify left bottom mirror)
			)
		)
		(property "Datasheet" "https://product.samsungsem.com/mlcc/CL10A226MO7JZN.do"
			(at 0 0 180)
			(layer "B.Fab")
			(hide yes)
			(effects
				(font
					(size 1.27 1.27)
					(thickness 0.15)
				)
				(justify mirror)
			)
		)
		(property "Description" "SMD Multilayer Ceramic Capacitor"
			(at 0 0 180)
			(layer "B.Fab")
			(hide yes)
			(effects
				(font
					(size 1.27 1.27)
					(thickness 0.15)
				)
				(justify mirror)
			)
		)
		(property "MPN" "CL10A226MO7JZNC"
			(at 0 0 0)
			(unlocked yes)
			(layer "B.Fab")
			(hide yes)
			(effects
				(font
					(size 1 1)
					(thickness 0.15)
				)
				(justify mirror)
			)
		)
		(property "Manufacturer" "Samsung Electro-Mechanics"
			(at 0 0 0)
			(unlocked yes)
			(layer "B.Fab")
			(hide yes)
			(effects
				(font
					(size 1 1)
					(thickness 0.15)
				)
				(justify mirror)
			)
		)
		(property "License" "Apache-2.0"
			(at 0 0 0)
			(unlocked yes)
			(layer "B.Fab")
			(hide yes)
			(effects
				(font
					(size 1 1)
					(thickness 0.15)
				)
				(justify mirror)
			)
		)
		(property "Author" "Antmicro"
			(at 0 0 0)
			(unlocked yes)
			(layer "B.Fab")
			(hide yes)
			(effects
				(font
					(size 1 1)
					(thickness 0.15)
				)
				(justify mirror)
			)
		)
		(property "Val" "22u"
			(at 0 0 0)
			(unlocked yes)
			(layer "B.Fab")
			(hide yes)
			(effects
				(font
					(size 1 1)
					(thickness 0.15)
				)
				(justify mirror)
			)
		)
		(property "Voltage" "16V"
			(at 0 0 0)
			(unlocked yes)
			(layer "B.Fab")
			(hide yes)
			(effects
				(font
					(size 1 1)
					(thickness 0.15)
				)
				(justify mirror)
			)
		)
		(property "Dielectric" "X7R"
			(at 0 0 0)
			(unlocked yes)
			(layer "B.Fab")
			(hide yes)
			(effects
				(font
					(size 1 1)
					(thickness 0.15)
				)
				(justify mirror)
			)
		)
		(property "Public" "False"
			(at 0 0 0)
			(unlocked yes)
			(layer "B.Fab")
			(hide yes)
			(effects
				(font
					(size 1 1)
					(thickness 0.15)
				)
				(justify mirror)
			)
		)
		(sheetname "/SoM_Power/")
		(sheetfile "som_power.kicad_sch")
		(attr smd)
		(fp_line
			(start -0.15 -0.55)
			(end 0.15 -0.55)
			(stroke
				(width 0.15)
				(type solid)
			)
			(layer "B.SilkS")
		)
		(fp_line
			(start -0.15 0.55)
			(end 0.15 0.55)
			(stroke
				(width 0.15)
				(type solid)
			)
			(layer "B.SilkS")
		)
		(fp_rect
			(start -1.25 0.65)
			(end 1.25 -0.65)
			(stroke
				(width 0.05)
				(type solid)
			)
			(fill no)
			(layer "B.CrtYd")
		)
		(fp_rect
			(start -0.8 0.45)
			(end 0.8 -0.45)
			(stroke
				(width 0.15)
				(type solid)
			)
			(fill no)
			(layer "B.Fab")
		)
		(fp_text user "Author: Antmicro"
			(at -1.682 -4.894 180)
			(layer "B.Fab")
			(effects
				(font
					(size 0.7 0.7)
					(thickness 0.15)
				)
				(justify left bottom mirror)
			)
		)
		(fp_text user "${REFERENCE}"
			(at -1.682 -3.895 180)
			(layer "B.Fab")
			(effects
				(font
					(size 0.7 0.7)
					(thickness 0.15)
				)
				(justify left bottom mirror)
			)
		)
		(fp_text user "License: Apache-2.0"
			(at -1.682 -5.895 180)
			(layer "B.Fab")
			(effects
				(font
					(size 0.7 0.7)
					(thickness 0.15)
				)
				(justify left bottom mirror)
			)
		)
		(pad "1" smd roundrect
			(at -0.7 0)
			(size 0.8 1.1)
			(layers "B.Cu" "B.Mask" "B.Paste")
			(roundrect_rratio 0.2)
			(net 1 "GND")
			(pintype "passive")
		)
		(pad "2" smd roundrect
			(at 0.7 0)
			(size 0.8 1.1)
			(layers "B.Cu" "B.Mask" "B.Paste")
			(roundrect_rratio 0.2)
			(net 213 "+5V_SOM")
			(pintype "passive")
		)
	)
	(footprint "antmicro-footprints:C_0402_1005Metric"
		(layer "B.Cu")
		(at 102.48 62 90)
		(descr "Capacitor SMD 0402")
		(tags "capacitor SMD 0402")
		(property "Reference" "C199"
			(at -3.6 -0.28 90)
			(layer "B.SilkS")
			(effects
				(font
					(size 0.7 0.7)
					(thickness 0.15)
				)
				(justify right top mirror)
			)
		)
		(property "Value" "C_100n_0402"
			(at -1.022927 -2.155213 90)
			(layer "B.Fab")
			(effects
				(font
					(size 0.7 0.7)
					(thickness 0.15)
				)
				(justify right top mirror)
			)
		)
		(property "Datasheet" "https://www.murata.com/products/productdetail?partno=GRM155R61H104KE14%23"
			(at 0 0 90)
			(layer "B.Fab")
			(hide yes)
			(effects
				(font
					(size 1.27 1.27)
					(thickness 0.15)
				)
				(justify mirror)
			)
		)
		(property "Description" "SMD Multilayer Ceramic Capacitor, 0.1 µF, 50 V, 0402 [1005 Metric], ± 10%, X5R, GRM Series"
			(at 0 0 90)
			(layer "B.Fab")
			(hide yes)
			(effects
				(font
					(size 1.27 1.27)
					(thickness 0.15)
				)
				(justify mirror)
			)
		)
		(property "MPN" "GRM155R61H104KE14D"
			(at 0 0 270)
			(unlocked yes)
			(layer "B.Fab")
			(hide yes)
			(effects
				(font
					(size 1 1)
					(thickness 0.15)
				)
				(justify mirror)
			)
		)
		(property "Manufacturer" "Murata"
			(at 0 0 270)
			(unlocked yes)
			(layer "B.Fab")
			(hide yes)
			(effects
				(font
					(size 1 1)
					(thickness 0.15)
				)
				(justify mirror)
			)
		)
		(property "License" "Apache-2.0"
			(at 0 0 270)
			(unlocked yes)
			(layer "B.Fab")
			(hide yes)
			(effects
				(font
					(size 1 1)
					(thickness 0.15)
				)
				(justify mirror)
			)
		)
		(property "Author" "Antmicro"
			(at 0 0 270)
			(unlocked yes)
			(layer "B.Fab")
			(hide yes)
			(effects
				(font
					(size 1 1)
					(thickness 0.15)
				)
				(justify mirror)
			)
		)
		(property "Val" "100n"
			(at 0 0 270)
			(unlocked yes)
			(layer "B.Fab")
			(hide yes)
			(effects
				(font
					(size 1 1)
					(thickness 0.15)
				)
				(justify mirror)
			)
		)
		(property "Voltage" "50V"
			(at 0 0 270)
			(unlocked yes)
			(layer "B.Fab")
			(hide yes)
			(effects
				(font
					(size 1 1)
					(thickness 0.15)
				)
				(justify mirror)
			)
		)
		(property "Dielectric" "X5R"
			(at 0 0 270)
			(unlocked yes)
			(layer "B.Fab")
			(hide yes)
			(effects
				(font
					(size 1 1)
					(thickness 0.15)
				)
				(justify mirror)
			)
		)
		(sheetname "/SoM_IO2/")
		(sheetfile "som_io2.kicad_sch")
		(attr smd)
		(fp_rect
			(start -0.925 0.47)
			(end 0.925 -0.47)
			(stroke
				(width 0.05)
				(type default)
			)
			(fill no)
			(layer "B.CrtYd")
		)
		(fp_line
			(start 0.504 -0.248)
			(end -0.494 -0.248)
			(stroke
				(width 0.15)
				(type solid)
			)
			(layer "B.Fab")
		)
		(fp_line
			(start -0.494 -0.248)
			(end -0.494 0.25)
			(stroke
				(width 0.15)
				(type solid)
			)
			(layer "B.Fab")
		)
		(fp_line
			(start 0.504 0.25)
			(end 0.504 -0.248)
			(stroke
				(width 0.15)
				(type solid)
			)
			(layer "B.Fab")
		)
		(fp_line
			(start -0.494 0.25)
			(end 0.504 0.25)
			(stroke
				(width 0.15)
				(type solid)
			)
			(layer "B.Fab")
		)
		(fp_text user "License: Apache-2.0"
			(at -0.939 -5.799 90)
			(layer "B.Fab")
			(effects
				(font
					(size 0.7 0.7)
					(thickness 0.15)
				)
				(justify right top mirror)
			)
		)
		(fp_text user "Author: Antmicro"
			(at -0.939 -3.399 90)
			(layer "B.Fab")
			(effects
				(font
					(size 0.7 0.7)
					(thickness 0.15)
				)
				(justify right top mirror)
			)
		)
		(fp_text user "${REFERENCE}"
			(at -0.939 -4.599 90)
			(layer "B.Fab")
			(effects
				(font
					(size 0.7 0.7)
					(thickness 0.15)
				)
				(justify right top mirror)
			)
		)
		(pad "1" smd roundrect
			(at -0.48 0 90)
			(size 0.59 0.64)
			(layers "B.Cu" "B.Mask" "B.Paste")
			(roundrect_rratio 0.25)
			(net 1 "GND")
			(pintype "passive")
		)
		(pad "2" smd roundrect
			(at 0.48 0 90)
			(size 0.59 0.64)
			(layers "B.Cu" "B.Mask" "B.Paste")
			(roundrect_rratio 0.25)
			(net 2 "+3V3")
			(pintype "passive")
		)
	)
	(footprint "antmicro-footprints:R_0402_1005Metric"
		(layer "B.Cu")
		(at 195.4 127.08 90)
		(descr "Resistor SMD 0402")
		(tags "resistor SMD 0402")
		(property "Reference" "R323"
			(at -1.52 -1.4 90)
			(layer "B.SilkS")
			(effects
				(font
					(size 0.7 0.7)
					(thickness 0.15)
				)
				(justify right top mirror)
			)
		)
		(property "Value" "R_10k_0402"
			(at -1.011843 -1.772046 90)
			(layer "B.Fab")
			(effects
				(font
					(size 0.7 0.7)
					(thickness 0.15)
				)
				(justify right top mirror)
			)
		)
		(property "Datasheet" "https://www.bourns.com/docs/product-datasheets/cr.pdf"
			(at 0 0 90)
			(layer "B.Fab")
			(hide yes)
			(effects
				(font
					(size 1.27 1.27)
					(thickness 0.15)
				)
				(justify mirror)
			)
		)
		(property "Description" "SMD Chip Resistor, 10 kohm, ± 1%, 62.5 mW, 0402 [1005 Metric], Thick Film, General Purpose"
			(at 0 0 90)
			(layer "B.Fab")
			(hide yes)
			(effects
				(font
					(size 1.27 1.27)
					(thickness 0.15)
				)
				(justify mirror)
			)
		)
		(property "Manufacturer" "Bourns"
			(at 0 0 270)
			(unlocked yes)
			(layer "B.Fab")
			(hide yes)
			(effects
				(font
					(size 1 1)
					(thickness 0.15)
				)
				(justify mirror)
			)
		)
		(property "MPN" "CR0402-FX-1002GLF"
			(at 0 0 270)
			(unlocked yes)
			(layer "B.Fab")
			(hide yes)
			(effects
				(font
					(size 1 1)
					(thickness 0.15)
				)
				(justify mirror)
			)
		)
		(property "Val" "10k"
			(at 0 0 270)
			(unlocked yes)
			(layer "B.Fab")
			(hide yes)
			(effects
				(font
					(size 1 1)
					(thickness 0.15)
				)
				(justify mirror)
			)
		)
		(property "License" "Apache-2.0"
			(at 0 0 270)
			(unlocked yes)
			(layer "B.Fab")
			(hide yes)
			(effects
				(font
					(size 1 1)
					(thickness 0.15)
				)
				(justify mirror)
			)
		)
		(property "Author" "Antmicro"
			(at 0 0 270)
			(unlocked yes)
			(layer "B.Fab")
			(hide yes)
			(effects
				(font
					(size 1 1)
					(thickness 0.15)
				)
				(justify mirror)
			)
		)
		(property "Tolerance" "1%"
			(at 0 0 270)
			(unlocked yes)
			(layer "B.Fab")
			(hide yes)
			(effects
				(font
					(size 1 1)
					(thickness 0.15)
				)
				(justify mirror)
			)
		)
		(sheetname "/USB Hub/")
		(sheetfile "usb_hub.kicad_sch")
		(attr smd exclude_from_pos_files exclude_from_bom dnp)
		(fp_poly
			(pts
				(xy -0.925 0.47) (xy -0.925 -0.47) (xy 0.925 -0.47) (xy 0.925 0.47)
			)
			(stroke
				(width 0.05)
				(type default)
			)
			(fill no)
			(layer "B.CrtYd")
		)
		(fp_poly
			(pts
				(xy -0.5 0.25) (xy -0.5 -0.25) (xy 0.5 -0.25) (xy 0.5 0.25)
			)
			(stroke
				(width 0.15)
				(type solid)
			)
			(fill no)
			(layer "B.Fab")
		)
		(fp_text user "License: Apache-2.0"
			(at -0.949999 -5.169 90)
			(layer "B.Fab")
			(effects
				(font
					(size 0.7 0.7)
					(thickness 0.15)
				)
				(justify right top mirror)
			)
		)
		(fp_text user "Author: Antmicro"
			(at -0.95 -4.169 90)
			(layer "B.Fab")
			(effects
				(font
					(size 0.7 0.7)
					(thickness 0.15)
				)
				(justify right top mirror)
			)
		)
		(fp_text user "${REFERENCE}"
			(at -0.95 -3.168 90)
			(layer "B.Fab")
			(effects
				(font
					(size 0.7 0.7)
					(thickness 0.15)
				)
				(justify right top mirror)
			)
		)
		(pad "1" smd roundrect
			(at -0.48 0 90)
			(size 0.59 0.64)
			(layers "B.Cu" "B.Mask" "B.Paste")
			(roundrect_rratio 0.25)
			(net 925 "/USB Hub/HUB_SPI_D0")
			(pintype "passive")
		)
		(pad "2" smd roundrect
			(at 0.48 0 90)
			(size 0.59 0.64)
			(layers "B.Cu" "B.Mask" "B.Paste")
			(roundrect_rratio 0.25)
			(net 2 "+3V3")
			(pintype "passive")
		)
	)
	(footprint "antmicro-footprints:R_0402_1005Metric"
		(layer "B.Cu")
		(at 101.24 60 90)
		(descr "Resistor SMD 0402")
		(tags "resistor SMD 0402")
		(property "Reference" "R1"
			(at -0.8 -1.24 90)
			(layer "B.SilkS")
			(effects
				(font
					(size 0.7 0.7)
					(thickness 0.15)
				)
				(justify right top mirror)
			)
		)
		(property "Value" "R_100k_0402"
			(at -1.011843 -1.772047 90)
			(layer "B.Fab")
			(effects
				(font
					(size 0.7 0.7)
					(thickness 0.15)
				)
				(justify right top mirror)
			)
		)
		(property "Datasheet" "https://www.bourns.com/docs/product-datasheets/cr.pdf"
			(at 0 0 90)
			(layer "B.Fab")
			(hide yes)
			(effects
				(font
					(size 1.27 1.27)
					(thickness 0.15)
				)
				(justify mirror)
			)
		)
		(property "Description" "SMD Chip Resistor, 100 kohm, ± 1%, 62.5 mW, 0402 [1005 Metric], Thick Film, General Purpose"
			(at 0 0 90)
			(layer "B.Fab")
			(hide yes)
			(effects
				(font
					(size 1.27 1.27)
					(thickness 0.15)
				)
				(justify mirror)
			)
		)
		(property "MPN" "CR0402-FX-1003GLF"
			(at 0 0 270)
			(unlocked yes)
			(layer "B.Fab")
			(hide yes)
			(effects
				(font
					(size 1 1)
					(thickness 0.15)
				)
				(justify mirror)
			)
		)
		(property "Manufacturer" "Bourns"
			(at 0 0 270)
			(unlocked yes)
			(layer "B.Fab")
			(hide yes)
			(effects
				(font
					(size 1 1)
					(thickness 0.15)
				)
				(justify mirror)
			)
		)
		(property "License" "Apache-2.0"
			(at 0 0 270)
			(unlocked yes)
			(layer "B.Fab")
			(hide yes)
			(effects
				(font
					(size 1 1)
					(thickness 0.15)
				)
				(justify mirror)
			)
		)
		(property "Author" "Antmicro"
			(at 0 0 270)
			(unlocked yes)
			(layer "B.Fab")
			(hide yes)
			(effects
				(font
					(size 1 1)
					(thickness 0.15)
				)
				(justify mirror)
			)
		)
		(property "Val" "100k"
			(at 0 0 270)
			(unlocked yes)
			(layer "B.Fab")
			(hide yes)
			(effects
				(font
					(size 1 1)
					(thickness 0.15)
				)
				(justify mirror)
			)
		)
		(property "Tolerance" "1%"
			(at 0 0 270)
			(unlocked yes)
			(layer "B.Fab")
			(hide yes)
			(effects
				(font
					(size 1 1)
					(thickness 0.15)
				)
				(justify mirror)
			)
		)
		(sheetname "/SoM_IO2/")
		(sheetfile "som_io2.kicad_sch")
		(attr smd)
		(fp_rect
			(start -0.925 0.47)
			(end 0.925 -0.47)
			(stroke
				(width 0.05)
				(type default)
			)
			(fill no)
			(layer "B.CrtYd")
		)
		(fp_rect
			(start -0.5 0.25)
			(end 0.5 -0.25)
			(stroke
				(width 0.15)
				(type solid)
			)
			(fill no)
			(layer "B.Fab")
		)
		(fp_text user "Author: Antmicro"
			(at -0.95 -4.169 90)
			(layer "B.Fab")
			(effects
				(font
					(size 0.7 0.7)
					(thickness 0.15)
				)
				(justify right top mirror)
			)
		)
		(fp_text user "License: Apache-2.0"
			(at -0.95 -5.169 90)
			(layer "B.Fab")
			(effects
				(font
					(size 0.7 0.7)
					(thickness 0.15)
				)
				(justify right top mirror)
			)
		)
		(fp_text user "${REFERENCE}"
			(at -0.95 -3.168 90)
			(layer "B.Fab")
			(effects
				(font
					(size 0.7 0.7)
					(thickness 0.15)
				)
				(justify right top mirror)
			)
		)
		(pad "1" smd roundrect
			(at -0.48 0 90)
			(size 0.59 0.64)
			(layers "B.Cu" "B.Mask" "B.Paste")
			(roundrect_rratio 0.25)
			(net 2 "+3V3")
			(pintype "passive")
		)
		(pad "2" smd roundrect
			(at 0.48 0 90)
			(size 0.59 0.64)
			(layers "B.Cu" "B.Mask" "B.Paste")
			(roundrect_rratio 0.25)
			(net 1101 "Net-(Y5-EN)")
			(pintype "passive")
		)
	)
	(footprint "antmicro-footprints:C_0402_1005Metric"
		(layer "B.Cu")
		(at 195.476532 137.84 -90)
		(descr "Capacitor SMD 0402")
		(tags "capacitor SMD 0402")
		(property "Reference" "C169"
			(at -0.8 0.870532 90)
			(layer "B.SilkS")
			(effects
				(font
					(size 0.7 0.7)
					(thickness 0.15)
				)
				(justify left bottom mirror)
			)
		)
		(property "Value" "C_100n_0402"
			(at -1.022927 -2.155213 90)
			(layer "B.Fab")
			(effects
				(font
					(size 0.7 0.7)
					(thickness 0.15)
				)
				(justify left bottom mirror)
			)
		)
		(property "Datasheet" "https://www.murata.com/products/productdetail?partno=GRM155R61H104KE14%23"
			(at 0 0 90)
			(layer "B.Fab")
			(hide yes)
			(effects
				(font
					(size 1.27 1.27)
					(thickness 0.15)
				)
				(justify mirror)
			)
		)
		(property "Description" "SMD Multilayer Ceramic Capacitor, 0.1 µF, 50 V, 0402 [1005 Metric], ± 10%, X5R, GRM Series"
			(at 0 0 90)
			(layer "B.Fab")
			(hide yes)
			(effects
				(font
					(size 1.27 1.27)
					(thickness 0.15)
				)
				(justify mirror)
			)
		)
		(property "MPN" "GRM155R61H104KE14D"
			(at 0 0 90)
			(unlocked yes)
			(layer "B.Fab")
			(hide yes)
			(effects
				(font
					(size 1 1)
					(thickness 0.15)
				)
				(justify mirror)
			)
		)
		(property "Manufacturer" "Murata"
			(at 0 0 90)
			(unlocked yes)
			(layer "B.Fab")
			(hide yes)
			(effects
				(font
					(size 1 1)
					(thickness 0.15)
				)
				(justify mirror)
			)
		)
		(property "License" "Apache-2.0"
			(at 0 0 90)
			(unlocked yes)
			(layer "B.Fab")
			(hide yes)
			(effects
				(font
					(size 1 1)
					(thickness 0.15)
				)
				(justify mirror)
			)
		)
		(property "Author" "Antmicro"
			(at 0 0 90)
			(unlocked yes)
			(layer "B.Fab")
			(hide yes)
			(effects
				(font
					(size 1 1)
					(thickness 0.15)
				)
				(justify mirror)
			)
		)
		(property "Val" "100n"
			(at 0 0 90)
			(unlocked yes)
			(layer "B.Fab")
			(hide yes)
			(effects
				(font
					(size 1 1)
					(thickness 0.15)
				)
				(justify mirror)
			)
		)
		(property "Voltage" "50V"
			(at 0 0 90)
			(unlocked yes)
			(layer "B.Fab")
			(hide yes)
			(effects
				(font
					(size 1 1)
					(thickness 0.15)
				)
				(justify mirror)
			)
		)
		(property "Dielectric" "X5R"
			(at 0 0 90)
			(unlocked yes)
			(layer "B.Fab")
			(hide yes)
			(effects
				(font
					(size 1 1)
					(thickness 0.15)
				)
				(justify mirror)
			)
		)
		(sheetname "/SFP/")
		(sheetfile "sfp.kicad_sch")
		(attr smd)
		(fp_rect
			(start -0.925 0.47)
			(end 0.925 -0.47)
			(stroke
				(width 0.05)
				(type default)
			)
			(fill no)
			(layer "B.CrtYd")
		)
		(fp_line
			(start -0.494 0.25)
			(end 0.504 0.25)
			(stroke
				(width 0.15)
				(type solid)
			)
			(layer "B.Fab")
		)
		(fp_line
			(start 0.504 0.25)
			(end 0.504 -0.248)
			(stroke
				(width 0.15)
				(type solid)
			)
			(layer "B.Fab")
		)
		(fp_line
			(start -0.494 -0.248)
			(end -0.494 0.25)
			(stroke
				(width 0.15)
				(type solid)
			)
			(layer "B.Fab")
		)
		(fp_line
			(start 0.504 -0.248)
			(end -0.494 -0.248)
			(stroke
				(width 0.15)
				(type solid)
			)
			(layer "B.Fab")
		)
		(fp_text user "License: Apache-2.0"
			(at -0.939 -5.799 90)
			(layer "B.Fab")
			(effects
				(font
					(size 0.7 0.7)
					(thickness 0.15)
				)
				(justify left bottom mirror)
			)
		)
		(fp_text user "Author: Antmicro"
			(at -0.939 -3.399 90)
			(layer "B.Fab")
			(effects
				(font
					(size 0.7 0.7)
					(thickness 0.15)
				)
				(justify left bottom mirror)
			)
		)
		(fp_text user "${REFERENCE}"
			(at -0.939 -4.599 90)
			(layer "B.Fab")
			(effects
				(font
					(size 0.7 0.7)
					(thickness 0.15)
				)
				(justify left bottom mirror)
			)
		)
		(pad "1" smd roundrect
			(at -0.48 0 270)
			(size 0.59 0.64)
			(layers "B.Cu" "B.Mask" "B.Paste")
			(roundrect_rratio 0.25)
			(net 1 "GND")
			(pintype "passive")
		)
		(pad "2" smd roundrect
			(at 0.48 0 270)
			(size 0.59 0.64)
			(layers "B.Cu" "B.Mask" "B.Paste")
			(roundrect_rratio 0.25)
			(net 379 "/SFP/SH")
			(pintype "passive")
		)
	)
	(footprint "antmicro-footprints:C_0402_1005Metric"
		(layer "B.Cu")
		(at 131 132 -90)
		(descr "Capacitor SMD 0402")
		(tags "capacitor SMD 0402")
		(property "Reference" "C189"
			(at -4 -0.41 90)
			(layer "B.SilkS")
			(effects
				(font
					(size 0.7 0.7)
					(thickness 0.15)
				)
				(justify left bottom mirror)
			)
		)
		(property "Value" "C_100n_0402"
			(at -1.022927 -2.155213 90)
			(layer "B.Fab")
			(effects
				(font
					(size 0.7 0.7)
					(thickness 0.15)
				)
				(justify left bottom mirror)
			)
		)
		(property "Datasheet" "https://www.murata.com/products/productdetail?partno=GRM155R61H104KE14%23"
			(at 0 0 90)
			(layer "B.Fab")
			(hide yes)
			(effects
				(font
					(size 1.27 1.27)
					(thickness 0.15)
				)
				(justify mirror)
			)
		)
		(property "Description" "SMD Multilayer Ceramic Capacitor, 0.1 µF, 50 V, 0402 [1005 Metric], ± 10%, X5R, GRM Series"
			(at 0 0 90)
			(layer "B.Fab")
			(hide yes)
			(effects
				(font
					(size 1.27 1.27)
					(thickness 0.15)
				)
				(justify mirror)
			)
		)
		(property "Manufacturer" "Murata"
			(at 0 0 90)
			(unlocked yes)
			(layer "B.Fab")
			(hide yes)
			(effects
				(font
					(size 1 1)
					(thickness 0.15)
				)
				(justify mirror)
			)
		)
		(property "MPN" "GRM155R61H104KE14D"
			(at 0 0 90)
			(unlocked yes)
			(layer "B.Fab")
			(hide yes)
			(effects
				(font
					(size 1 1)
					(thickness 0.15)
				)
				(justify mirror)
			)
		)
		(property "Val" "100n"
			(at 0 0 90)
			(unlocked yes)
			(layer "B.Fab")
			(hide yes)
			(effects
				(font
					(size 1 1)
					(thickness 0.15)
				)
				(justify mirror)
			)
		)
		(property "License" "Apache-2.0"
			(at 0 0 90)
			(unlocked yes)
			(layer "B.Fab")
			(hide yes)
			(effects
				(font
					(size 1 1)
					(thickness 0.15)
				)
				(justify mirror)
			)
		)
		(property "Author" "Antmicro"
			(at 0 0 90)
			(unlocked yes)
			(layer "B.Fab")
			(hide yes)
			(effects
				(font
					(size 1 1)
					(thickness 0.15)
				)
				(justify mirror)
			)
		)
		(property "Voltage" "50V"
			(at 0 0 90)
			(unlocked yes)
			(layer "B.Fab")
			(hide yes)
			(effects
				(font
					(size 1 1)
					(thickness 0.15)
				)
				(justify mirror)
			)
		)
		(property "Dielectric" "X5R"
			(at 0 0 90)
			(unlocked yes)
			(layer "B.Fab")
			(hide yes)
			(effects
				(font
					(size 1 1)
					(thickness 0.15)
				)
				(justify mirror)
			)
		)
		(sheetname "/M.2/")
		(sheetfile "m2.kicad_sch")
		(attr smd)
		(fp_poly
			(pts
				(xy -0.925 0.47) (xy 0.925 0.47) (xy 0.925 -0.47) (xy -0.925 -0.47)
			)
			(stroke
				(width 0.05)
				(type default)
			)
			(fill no)
			(layer "B.CrtYd")
		)
		(fp_line
			(start -0.494 0.25)
			(end 0.504 0.25)
			(stroke
				(width 0.15)
				(type solid)
			)
			(layer "B.Fab")
		)
		(fp_line
			(start 0.504 0.25)
			(end 0.504 -0.248)
			(stroke
				(width 0.15)
				(type solid)
			)
			(layer "B.Fab")
		)
		(fp_line
			(start -0.494 -0.248)
			(end -0.494 0.25)
			(stroke
				(width 0.15)
				(type solid)
			)
			(layer "B.Fab")
		)
		(fp_line
			(start 0.504 -0.248)
			(end -0.494 -0.248)
			(stroke
				(width 0.15)
				(type solid)
			)
			(layer "B.Fab")
		)
		(fp_text user "Author: Antmicro"
			(at -0.939 -3.399 90)
			(layer "B.Fab")
			(effects
				(font
					(size 0.7 0.7)
					(thickness 0.15)
				)
				(justify left bottom mirror)
			)
		)
		(fp_text user "${REFERENCE}"
			(at -0.939 -4.599 90)
			(layer "B.Fab")
			(effects
				(font
					(size 0.7 0.7)
					(thickness 0.15)
				)
				(justify left bottom mirror)
			)
		)
		(fp_text user "License: Apache-2.0"
			(at -0.939 -5.799 90)
			(layer "B.Fab")
			(effects
				(font
					(size 0.7 0.7)
					(thickness 0.15)
				)
				(justify left bottom mirror)
			)
		)
		(pad "1" smd roundrect
			(at -0.48 0 270)
			(size 0.59 0.64)
			(layers "B.Cu" "B.Mask" "B.Paste")
			(roundrect_rratio 0.25)
			(net 2 "+3V3")
			(pintype "passive")
		)
		(pad "2" smd roundrect
			(at 0.48 0 270)
			(size 0.59 0.64)
			(layers "B.Cu" "B.Mask" "B.Paste")
			(roundrect_rratio 0.25)
			(net 1 "GND")
			(pintype "passive")
		)
	)
	(footprint "antmicro-footprints:TP_SMD_0.75mm"
		(layer "B.Cu")
		(at 63 73.1 -90)
		(property "Reference" "TP109"
			(at -0.7 0.7 270)
			(layer "B.SilkS")
			(effects
				(font
					(size 0.7 0.7)
					(thickness 0.15)
				)
				(justify left bottom mirror)
			)
		)
		(property "Value" "TP_0.75mm_SMD"
			(at 0 -1.2 90)
			(layer "B.Fab")
			(effects
				(font
					(size 0.7 0.7)
					(thickness 0.15)
				)
				(justify left bottom mirror)
			)
		)
		(property "Description" "SMT test point"
			(at 0 0 90)
			(layer "B.Fab")
			(hide yes)
			(effects
				(font
					(size 1.27 1.27)
					(thickness 0.15)
				)
				(justify mirror)
			)
		)
		(property "MPN" ""
			(at 0 0 90)
			(unlocked yes)
			(layer "B.Fab")
			(hide yes)
			(effects
				(font
					(size 1 1)
					(thickness 0.15)
				)
				(justify mirror)
			)
		)
		(property "Manufacturer" ""
			(at 0 0 90)
			(unlocked yes)
			(layer "B.Fab")
			(hide yes)
			(effects
				(font
					(size 1 1)
					(thickness 0.15)
				)
				(justify mirror)
			)
		)
		(property "Author" "Antmicro"
			(at 0 0 90)
			(unlocked yes)
			(layer "B.Fab")
			(hide yes)
			(effects
				(font
					(size 1 1)
					(thickness 0.15)
				)
				(justify mirror)
			)
		)
		(property "License" "Apache-2.0"
			(at 0 0 90)
			(unlocked yes)
			(layer "B.Fab")
			(hide yes)
			(effects
				(font
					(size 1 1)
					(thickness 0.15)
				)
				(justify mirror)
			)
		)
		(sheetname "/Expansion connector/")
		(sheetfile "expansion_connector.kicad_sch")
		(attr exclude_from_pos_files exclude_from_bom)
		(fp_circle
			(center 0 0)
			(end 0.475 0)
			(stroke
				(width 0.05)
				(type default)
			)
			(fill no)
			(layer "B.CrtYd")
		)
		(fp_text user "Author: Antmicro"
			(at -0.4 -3.901 90)
			(layer "B.Fab")
			(effects
				(font
					(size 0.7 0.7)
					(thickness 0.15)
				)
				(justify left bottom mirror)
			)
		)
		(fp_text user "${REFERENCE}"
			(at -0.4 -2.7 90)
			(layer "B.Fab")
			(effects
				(font
					(size 0.7 0.7)
					(thickness 0.15)
				)
				(justify left bottom mirror)
			)
		)
		(fp_text user "License: Apache-2.0"
			(at -0.4 -5.101 90)
			(layer "B.Fab")
			(effects
				(font
					(size 0.7 0.7)
					(thickness 0.15)
				)
				(justify left bottom mirror)
			)
		)
		(pad "1" smd circle
			(at 0 0 270)
			(size 0.75 0.75)
			(layers "B.Cu" "B.Mask")
			(net 431 "Net-(J18-PadH01)")
			(pinfunction "1")
			(pintype "passive")
		)
	)
	(footprint "antmicro-footprints:R_0402_1005Metric"
		(layer "B.Cu")
		(at 109.83 134.33)
		(descr "Resistor SMD 0402")
		(tags "resistor SMD 0402")
		(property "Reference" "R216"
			(at -3.82 -0.24 0)
			(layer "B.SilkS")
			(effects
				(font
					(size 0.7 0.7)
					(thickness 0.15)
				)
				(justify right top mirror)
			)
		)
		(property "Value" "R_0R_0402"
			(at -1.011843 -1.772047 0)
			(layer "B.Fab")
			(effects
				(font
					(size 0.7 0.7)
					(thickness 0.15)
				)
				(justify right top mirror)
			)
		)
		(property "Datasheet" "https://industrial.panasonic.com/cdbs/www-data/pdf/RDA0000/AOA0000C301.pdf"
			(at 0 0 0)
			(layer "B.Fab")
			(hide yes)
			(effects
				(font
					(size 1.27 1.27)
					(thickness 0.15)
				)
				(justify mirror)
			)
		)
		(property "Description" "SMD Chip Resistor, Jumper, 0 ohm, 100 mW, 0402 [1005 Metric], Thick Film, General Purpose"
			(at 0 0 0)
			(layer "B.Fab")
			(hide yes)
			(effects
				(font
					(size 1.27 1.27)
					(thickness 0.15)
				)
				(justify mirror)
			)
		)
		(property "MPN" "ERJ2GE0R00X"
			(at 0 0 180)
			(unlocked yes)
			(layer "B.Fab")
			(hide yes)
			(effects
				(font
					(size 1 1)
					(thickness 0.15)
				)
				(justify mirror)
			)
		)
		(property "Manufacturer" "Panasonic"
			(at 0 0 180)
			(unlocked yes)
			(layer "B.Fab")
			(hide yes)
			(effects
				(font
					(size 1 1)
					(thickness 0.15)
				)
				(justify mirror)
			)
		)
		(property "License" "Apache-2.0"
			(at 0 0 180)
			(unlocked yes)
			(layer "B.Fab")
			(hide yes)
			(effects
				(font
					(size 1 1)
					(thickness 0.15)
				)
				(justify mirror)
			)
		)
		(property "Author" "Antmicro"
			(at 0 0 180)
			(unlocked yes)
			(layer "B.Fab")
			(hide yes)
			(effects
				(font
					(size 1 1)
					(thickness 0.15)
				)
				(justify mirror)
			)
		)
		(property "Val" "0R"
			(at 0 0 180)
			(unlocked yes)
			(layer "B.Fab")
			(hide yes)
			(effects
				(font
					(size 1 1)
					(thickness 0.15)
				)
				(justify mirror)
			)
		)
		(property "Tolerance" "~"
			(at 0 0 180)
			(unlocked yes)
			(layer "B.Fab")
			(hide yes)
			(effects
				(font
					(size 1 1)
					(thickness 0.15)
				)
				(justify mirror)
			)
		)
		(property "Current" "1A"
			(at 0 0 180)
			(unlocked yes)
			(layer "B.Fab")
			(hide yes)
			(effects
				(font
					(size 1 1)
					(thickness 0.15)
				)
				(justify mirror)
			)
		)
		(sheetname "/M.2/")
		(sheetfile "m2.kicad_sch")
		(attr smd)
		(fp_rect
			(start -0.925 0.47)
			(end 0.925 -0.47)
			(stroke
				(width 0.05)
				(type default)
			)
			(fill no)
			(layer "B.CrtYd")
		)
		(fp_rect
			(start -0.5 0.25)
			(end 0.5 -0.25)
			(stroke
				(width 0.15)
				(type solid)
			)
			(fill no)
			(layer "B.Fab")
		)
		(fp_text user "${REFERENCE}"
			(at -0.95 -3.168 0)
			(layer "B.Fab")
			(effects
				(font
					(size 0.7 0.7)
					(thickness 0.15)
				)
				(justify right top mirror)
			)
		)
		(fp_text user "Author: Antmicro"
			(at -0.95 -4.169 0)
			(layer "B.Fab")
			(effects
				(font
					(size 0.7 0.7)
					(thickness 0.15)
				)
				(justify right top mirror)
			)
		)
		(fp_text user "License: Apache-2.0"
			(at -0.95 -5.169 0)
			(layer "B.Fab")
			(effects
				(font
					(size 0.7 0.7)
					(thickness 0.15)
				)
				(justify right top mirror)
			)
		)
		(pad "1" smd roundrect
			(at -0.48 0)
			(size 0.59 0.64)
			(layers "B.Cu" "B.Mask" "B.Paste")
			(roundrect_rratio 0.25)
			(net 104 "/M.2/~{PEWAKE}")
			(pintype "passive")
		)
		(pad "2" smd roundrect
			(at 0.48 0)
			(size 0.59 0.64)
			(layers "B.Cu" "B.Mask" "B.Paste")
			(roundrect_rratio 0.25)
			(net 833 "/M.2/~{PEWAKE_E}")
			(pintype "passive")
		)
	)
	(footprint "antmicro-footprints:C_0603_1608Metric_EIA"
		(layer "B.Cu")
		(at 124.6 97)
		(descr "Capacitor SMD 0603, IPC-7351 Density Level A")
		(tags "Capacitor 0603")
		(property "Reference" "C193"
			(at 1.2 -0.4 0)
			(layer "B.SilkS")
			(effects
				(font
					(size 0.7 0.7)
					(thickness 0.15)
				)
				(justify right top mirror)
			)
		)
		(property "Value" "C_22u_16V_0603"
			(at -1.42757 -1.770288 0)
			(layer "B.Fab")
			(effects
				(font
					(size 0.7 0.7)
					(thickness 0.15)
				)
				(justify right top mirror)
			)
		)
		(property "Datasheet" "https://product.samsungsem.com/mlcc/CL10A226MO7JZN.do"
			(at 0 0 0)
			(layer "B.Fab")
			(hide yes)
			(effects
				(font
					(size 1.27 1.27)
					(thickness 0.15)
				)
				(justify mirror)
			)
		)
		(property "Description" "SMD Multilayer Ceramic Capacitor"
			(at 0 0 0)
			(layer "B.Fab")
			(hide yes)
			(effects
				(font
					(size 1.27 1.27)
					(thickness 0.15)
				)
				(justify mirror)
			)
		)
		(property "Manufacturer" "Samsung Electro-Mechanics"
			(at 0 0 180)
			(unlocked yes)
			(layer "B.Fab")
			(hide yes)
			(effects
				(font
					(size 1 1)
					(thickness 0.15)
				)
				(justify mirror)
			)
		)
		(property "MPN" "CL10A226MO7JZNC"
			(at 0 0 180)
			(unlocked yes)
			(layer "B.Fab")
			(hide yes)
			(effects
				(font
					(size 1 1)
					(thickness 0.15)
				)
				(justify mirror)
			)
		)
		(property "Val" "22u"
			(at 0 0 180)
			(unlocked yes)
			(layer "B.Fab")
			(hide yes)
			(effects
				(font
					(size 1 1)
					(thickness 0.15)
				)
				(justify mirror)
			)
		)
		(property "License" "Apache-2.0"
			(at 0 0 180)
			(unlocked yes)
			(layer "B.Fab")
			(hide yes)
			(effects
				(font
					(size 1 1)
					(thickness 0.15)
				)
				(justify mirror)
			)
		)
		(property "Author" "Antmicro"
			(at 0 0 180)
			(unlocked yes)
			(layer "B.Fab")
			(hide yes)
			(effects
				(font
					(size 1 1)
					(thickness 0.15)
				)
				(justify mirror)
			)
		)
		(property "Voltage" "16V"
			(at 0 0 180)
			(unlocked yes)
			(layer "B.Fab")
			(hide yes)
			(effects
				(font
					(size 1 1)
					(thickness 0.15)
				)
				(justify mirror)
			)
		)
		(property "Dielectric" "template_dielectric"
			(at 0 0 180)
			(unlocked yes)
			(layer "B.Fab")
			(hide yes)
			(effects
				(font
					(size 1 1)
					(thickness 0.15)
				)
				(justify mirror)
			)
		)
		(sheetname "/M.2/")
		(sheetfile "m2.kicad_sch")
		(attr smd)
		(fp_line
			(start -0.15 -0.55)
			(end 0.15 -0.55)
			(stroke
				(width 0.15)
				(type solid)
			)
			(layer "B.SilkS")
		)
		(fp_line
			(start -0.15 0.55)
			(end 0.15 0.55)
			(stroke
				(width 0.15)
				(type solid)
			)
			(layer "B.SilkS")
		)
		(fp_poly
			(pts
				(xy -1.25 0.65) (xy -1.25 -0.65) (xy 1.25 -0.65) (xy 1.25 0.65)
			)
			(stroke
				(width 0.05)
				(type solid)
			)
			(fill no)
			(layer "B.CrtYd")
		)
		(fp_poly
			(pts
				(xy -0.799999 0.45) (xy -0.799999 -0.45) (xy 0.799999 -0.45) (xy 0.799999 0.45)
			)
			(stroke
				(width 0.15)
				(type solid)
			)
			(fill no)
			(layer "B.Fab")
		)
		(fp_text user "${REFERENCE}"
			(at -1.682001 -3.895 0)
			(layer "B.Fab")
			(effects
				(font
					(size 0.7 0.7)
					(thickness 0.15)
				)
				(justify right top mirror)
			)
		)
		(fp_text user "Author: Antmicro"
			(at -1.682 -4.894 0)
			(layer "B.Fab")
			(effects
				(font
					(size 0.7 0.7)
					(thickness 0.15)
				)
				(justify right top mirror)
			)
		)
		(fp_text user "License: Apache-2.0"
			(at -1.682 -5.895 0)
			(layer "B.Fab")
			(effects
				(font
					(size 0.7 0.7)
					(thickness 0.15)
				)
				(justify right top mirror)
			)
		)
		(pad "1" smd roundrect
			(at -0.7 0)
			(size 0.8 1.1)
			(layers "B.Cu" "B.Mask" "B.Paste")
			(roundrect_rratio 0.2)
			(net 14 "/M.2/3V3_M2")
			(pintype "passive")
		)
		(pad "2" smd roundrect
			(at 0.7 0)
			(size 0.8 1.1)
			(layers "B.Cu" "B.Mask" "B.Paste")
			(roundrect_rratio 0.2)
			(net 1 "GND")
			(pintype "passive")
		)
	)
	(footprint "antmicro-footprints:C_0402_1005Metric"
		(layer "B.Cu")
		(at 142.6 65.2 -90)
		(descr "Capacitor SMD 0402")
		(tags "capacitor SMD 0402")
		(property "Reference" "C210"
			(at 0.9 -0.4 90)
			(layer "B.SilkS")
			(effects
				(font
					(size 0.7 0.7)
					(thickness 0.15)
				)
				(justify left bottom mirror)
			)
		)
		(property "Value" "C_100n_0402"
			(at -1.022927 -2.155213 90)
			(layer "B.Fab")
			(effects
				(font
					(size 0.7 0.7)
					(thickness 0.15)
				)
				(justify left bottom mirror)
			)
		)
		(property "Datasheet" "https://www.murata.com/products/productdetail?partno=GRM155R61H104KE14%23"
			(at 0 0 90)
			(layer "B.Fab")
			(hide yes)
			(effects
				(font
					(size 1.27 1.27)
					(thickness 0.15)
				)
				(justify mirror)
			)
		)
		(property "Description" "SMD Multilayer Ceramic Capacitor, 0.1 µF, 50 V, 0402 [1005 Metric], ± 10%, X5R, GRM Series"
			(at 0 0 90)
			(layer "B.Fab")
			(hide yes)
			(effects
				(font
					(size 1.27 1.27)
					(thickness 0.15)
				)
				(justify mirror)
			)
		)
		(property "Manufacturer" "Murata"
			(at 0 0 90)
			(unlocked yes)
			(layer "B.Fab")
			(hide yes)
			(effects
				(font
					(size 1 1)
					(thickness 0.15)
				)
				(justify mirror)
			)
		)
		(property "MPN" "GRM155R61H104KE14D"
			(at 0 0 90)
			(unlocked yes)
			(layer "B.Fab")
			(hide yes)
			(effects
				(font
					(size 1 1)
					(thickness 0.15)
				)
				(justify mirror)
			)
		)
		(property "Val" "100n"
			(at 0 0 90)
			(unlocked yes)
			(layer "B.Fab")
			(hide yes)
			(effects
				(font
					(size 1 1)
					(thickness 0.15)
				)
				(justify mirror)
			)
		)
		(property "License" "Apache-2.0"
			(at 0 0 90)
			(unlocked yes)
			(layer "B.Fab")
			(hide yes)
			(effects
				(font
					(size 1 1)
					(thickness 0.15)
				)
				(justify mirror)
			)
		)
		(property "Author" "Antmicro"
			(at 0 0 90)
			(unlocked yes)
			(layer "B.Fab")
			(hide yes)
			(effects
				(font
					(size 1 1)
					(thickness 0.15)
				)
				(justify mirror)
			)
		)
		(property "Voltage" "50V"
			(at 0 0 90)
			(unlocked yes)
			(layer "B.Fab")
			(hide yes)
			(effects
				(font
					(size 1 1)
					(thickness 0.15)
				)
				(justify mirror)
			)
		)
		(property "Dielectric" "X5R"
			(at 0 0 90)
			(unlocked yes)
			(layer "B.Fab")
			(hide yes)
			(effects
				(font
					(size 1 1)
					(thickness 0.15)
				)
				(justify mirror)
			)
		)
		(sheetname "/Peripherals/")
		(sheetfile "peripherals.kicad_sch")
		(attr smd)
		(fp_poly
			(pts
				(xy -0.925 0.47) (xy 0.925 0.47) (xy 0.925 -0.47) (xy -0.925 -0.47)
			)
			(stroke
				(width 0.05)
				(type default)
			)
			(fill no)
			(layer "B.CrtYd")
		)
		(fp_line
			(start -0.494 0.25)
			(end 0.504 0.25)
			(stroke
				(width 0.15)
				(type solid)
			)
			(layer "B.Fab")
		)
		(fp_line
			(start 0.504 0.25)
			(end 0.504 -0.248)
			(stroke
				(width 0.15)
				(type solid)
			)
			(layer "B.Fab")
		)
		(fp_line
			(start -0.494 -0.248)
			(end -0.494 0.25)
			(stroke
				(width 0.15)
				(type solid)
			)
			(layer "B.Fab")
		)
		(fp_line
			(start 0.504 -0.248)
			(end -0.494 -0.248)
			(stroke
				(width 0.15)
				(type solid)
			)
			(layer "B.Fab")
		)
		(fp_text user "${REFERENCE}"
			(at -0.939 -4.599 90)
			(layer "B.Fab")
			(effects
				(font
					(size 0.7 0.7)
					(thickness 0.15)
				)
				(justify left bottom mirror)
			)
		)
		(fp_text user "License: Apache-2.0"
			(at -0.939 -5.799 90)
			(layer "B.Fab")
			(effects
				(font
					(size 0.7 0.7)
					(thickness 0.15)
				)
				(justify left bottom mirror)
			)
		)
		(fp_text user "Author: Antmicro"
			(at -0.939 -3.399 90)
			(layer "B.Fab")
			(effects
				(font
					(size 0.7 0.7)
					(thickness 0.15)
				)
				(justify left bottom mirror)
			)
		)
		(pad "1" smd roundrect
			(at -0.48 0 270)
			(size 0.59 0.64)
			(layers "B.Cu" "B.Mask" "B.Paste")
			(roundrect_rratio 0.25)
			(net 2 "+3V3")
			(pintype "passive")
		)
		(pad "2" smd roundrect
			(at 0.48 0 270)
			(size 0.59 0.64)
			(layers "B.Cu" "B.Mask" "B.Paste")
			(roundrect_rratio 0.25)
			(net 1 "GND")
			(pintype "passive")
		)
	)
	(footprint "antmicro-footprints:TP_SMD_0.75mm"
		(layer "B.Cu")
		(at 202.8 116.4 180)
		(property "Reference" "TP67"
			(at 0.4 0.6 90)
			(layer "B.SilkS")
			(effects
				(font
					(size 0.7 0.7)
					(thickness 0.15)
				)
				(justify right top mirror)
			)
		)
		(property "Value" "TP_0.75mm_SMD"
			(at 0 -1.2 180)
			(layer "B.Fab")
			(effects
				(font
					(size 0.7 0.7)
					(thickness 0.15)
				)
				(justify right top mirror)
			)
		)
		(property "Description" "SMT test point"
			(at 0 0 180)
			(layer "B.Fab")
			(hide yes)
			(effects
				(font
					(size 1.27 1.27)
					(thickness 0.15)
				)
				(justify mirror)
			)
		)
		(property "MPN" ""
			(at 0 0 0)
			(unlocked yes)
			(layer "B.Fab")
			(hide yes)
			(effects
				(font
					(size 1 1)
					(thickness 0.15)
				)
				(justify mirror)
			)
		)
		(property "Manufacturer" ""
			(at 0 0 0)
			(unlocked yes)
			(layer "B.Fab")
			(hide yes)
			(effects
				(font
					(size 1 1)
					(thickness 0.15)
				)
				(justify mirror)
			)
		)
		(property "Author" "Antmicro"
			(at 0 0 0)
			(unlocked yes)
			(layer "B.Fab")
			(hide yes)
			(effects
				(font
					(size 1 1)
					(thickness 0.15)
				)
				(justify mirror)
			)
		)
		(property "License" "Apache-2.0"
			(at 0 0 0)
			(unlocked yes)
			(layer "B.Fab")
			(hide yes)
			(effects
				(font
					(size 1 1)
					(thickness 0.15)
				)
				(justify mirror)
			)
		)
		(sheetname "/USB Hub/")
		(sheetfile "usb_hub.kicad_sch")
		(attr exclude_from_pos_files exclude_from_bom)
		(fp_circle
			(center 0 0)
			(end 0.475 0)
			(stroke
				(width 0.05)
				(type default)
			)
			(fill no)
			(layer "B.CrtYd")
		)
		(fp_text user "Author: Antmicro"
			(at -0.4 -3.901 180)
			(layer "B.Fab")
			(effects
				(font
					(size 0.7 0.7)
					(thickness 0.15)
				)
				(justify right top mirror)
			)
		)
		(fp_text user "${REFERENCE}"
			(at -0.4 -2.7 180)
			(layer "B.Fab")
			(effects
				(font
					(size 0.7 0.7)
					(thickness 0.15)
				)
				(justify right top mirror)
			)
		)
		(fp_text user "License: Apache-2.0"
			(at -0.4 -5.101 180)
			(layer "B.Fab")
			(effects
				(font
					(size 0.7 0.7)
					(thickness 0.15)
				)
				(justify right top mirror)
			)
		)
		(pad "1" smd circle
			(at 0 0 180)
			(size 0.75 0.75)
			(layers "B.Cu" "B.Mask")
			(net 1084 "/USB Hub/DP1_VCONN1")
			(pinfunction "1")
			(pintype "passive")
		)
	)
	(footprint "antmicro-footprints:SOD-523"
		(layer "B.Cu")
		(at 221.98 123.9 90)
		(property "Reference" "D59"
			(at -3.1 0.5 90)
			(layer "B.SilkS")
			(effects
				(font
					(size 0.7 0.7)
					(thickness 0.15)
				)
				(justify right top mirror)
			)
		)
		(property "Value" "RB521S30T1G"
			(at 0 -1.499 90)
			(layer "B.Fab")
			(effects
				(font
					(size 0.7 0.7)
					(thickness 0.15)
				)
				(justify right top mirror)
			)
		)
		(property "Datasheet" "https://www.onsemi.com/pdf/datasheet/rb521s30t1-d.pdf"
			(at 0 0 90)
			(layer "B.Fab")
			(hide yes)
			(effects
				(font
					(size 1.27 1.27)
					(thickness 0.15)
				)
				(justify mirror)
			)
		)
		(property "Description" "Small Signal Schottky Diode, Single, 30 V, 200 mA, 500 mV, 1 A, 125 °C"
			(at 0 0 90)
			(layer "B.Fab")
			(hide yes)
			(effects
				(font
					(size 1.27 1.27)
					(thickness 0.15)
				)
				(justify mirror)
			)
		)
		(property "MPN" "RB521S30T1G"
			(at 0 0 270)
			(unlocked yes)
			(layer "B.Fab")
			(hide yes)
			(effects
				(font
					(size 1 1)
					(thickness 0.15)
				)
				(justify mirror)
			)
		)
		(property "Manufacturer" "ON Semiconductor"
			(at 0 0 270)
			(unlocked yes)
			(layer "B.Fab")
			(hide yes)
			(effects
				(font
					(size 1 1)
					(thickness 0.15)
				)
				(justify mirror)
			)
		)
		(property "Author" "Antmicro"
			(at 0 0 270)
			(unlocked yes)
			(layer "B.Fab")
			(hide yes)
			(effects
				(font
					(size 1 1)
					(thickness 0.15)
				)
				(justify mirror)
			)
		)
		(property "License" "Apache-2.0"
			(at 0 0 270)
			(unlocked yes)
			(layer "B.Fab")
			(hide yes)
			(effects
				(font
					(size 1 1)
					(thickness 0.15)
				)
				(justify mirror)
			)
		)
		(sheetname "/USB Hub/")
		(sheetfile "usb_hub.kicad_sch")
		(attr smd)
		(fp_line
			(start -0.35 0.5)
			(end -0.35 -0.5)
			(stroke
				(width 0.15)
				(type solid)
			)
			(layer "B.SilkS")
		)
		(fp_rect
			(start -1 0.6)
			(end 1 -0.6)
			(stroke
				(width 0.05)
				(type solid)
			)
			(fill no)
			(layer "B.CrtYd")
		)
		(fp_line
			(start -0.652 -0.423)
			(end 0.65 -0.423)
			(stroke
				(width 0.15)
				(type solid)
			)
			(layer "B.Fab")
		)
		(fp_line
			(start -0.652 -0.423)
			(end -0.652 0.425)
			(stroke
				(width 0.15)
				(type solid)
			)
			(layer "B.Fab")
		)
		(fp_line
			(start -0.35 0.4)
			(end -0.35 -0.4)
			(stroke
				(width 0.15)
				(type solid)
			)
			(layer "B.Fab")
		)
		(fp_line
			(start 0.65 0.425)
			(end 0.65 -0.423)
			(stroke
				(width 0.15)
				(type solid)
			)
			(layer "B.Fab")
		)
		(fp_line
			(start -0.652 0.425)
			(end 0.65 0.425)
			(stroke
				(width 0.15)
				(type solid)
			)
			(layer "B.Fab")
		)
		(fp_text user "${REFERENCE}"
			(at -1.276 -3.499 90)
			(layer "B.Fab")
			(effects
				(font
					(size 0.7 0.7)
					(thickness 0.15)
				)
				(justify right top mirror)
			)
		)
		(fp_text user "License: Apache-2.0"
			(at -1.276 -5.9 90)
			(layer "B.Fab")
			(effects
				(font
					(size 0.7 0.7)
					(thickness 0.15)
				)
				(justify right top mirror)
			)
		)
		(fp_text user "Author: Antmicro"
			(at -1.276 -4.7 90)
			(layer "B.Fab")
			(effects
				(font
					(size 0.7 0.7)
					(thickness 0.15)
				)
				(justify right top mirror)
			)
		)
		(pad "1" smd roundrect
			(at -0.701 0 90)
			(size 0.5 0.6)
			(layers "B.Cu" "B.Mask" "B.Paste")
			(roundrect_rratio 0.25)
			(net 1238 "Net-(D59-C)")
			(pinfunction "C")
			(pintype "passive")
		)
		(pad "2" smd roundrect
			(at 0.699 0 90)
			(size 0.5 0.6)
			(layers "B.Cu" "B.Mask" "B.Paste")
			(roundrect_rratio 0.25)
			(net 1239 "Net-(D59-A)")
			(pinfunction "A")
			(pintype "passive")
		)
	)
	(footprint "antmicro-footprints:R_0402_1005Metric"
		(layer "B.Cu")
		(at 67.4 65.7 -90)
		(descr "Resistor SMD 0402")
		(tags "resistor SMD 0402")
		(property "Reference" "R393"
			(at 0.9 -0.5 90)
			(layer "B.SilkS")
			(effects
				(font
					(size 0.7 0.7)
					(thickness 0.15)
				)
				(justify left bottom mirror)
			)
		)
		(property "Value" "R_2k2_0402"
			(at -1.011843 -1.772047 90)
			(layer "B.Fab")
			(effects
				(font
					(size 0.7 0.7)
					(thickness 0.15)
				)
				(justify left bottom mirror)
			)
		)
		(property "Datasheet" "https://www.bourns.com/docs/product-datasheets/cr.pdf"
			(at 0 0 90)
			(layer "B.Fab")
			(hide yes)
			(effects
				(font
					(size 1.27 1.27)
					(thickness 0.15)
				)
				(justify mirror)
			)
		)
		(property "Description" "SMD Chip Resistor, 2.2 kohm, ± 1%, 62.5 mW, 0402 [1005 Metric], Thick Film, General Purpose"
			(at 0 0 90)
			(layer "B.Fab")
			(hide yes)
			(effects
				(font
					(size 1.27 1.27)
					(thickness 0.15)
				)
				(justify mirror)
			)
		)
		(property "MPN" "CR0402-FX-2201GLF"
			(at 0 0 90)
			(unlocked yes)
			(layer "B.Fab")
			(hide yes)
			(effects
				(font
					(size 1 1)
					(thickness 0.15)
				)
				(justify mirror)
			)
		)
		(property "Manufacturer" "Bourns"
			(at 0 0 90)
			(unlocked yes)
			(layer "B.Fab")
			(hide yes)
			(effects
				(font
					(size 1 1)
					(thickness 0.15)
				)
				(justify mirror)
			)
		)
		(property "License" "Apache-2.0"
			(at 0 0 90)
			(unlocked yes)
			(layer "B.Fab")
			(hide yes)
			(effects
				(font
					(size 1 1)
					(thickness 0.15)
				)
				(justify mirror)
			)
		)
		(property "Author" "Antmicro"
			(at 0 0 90)
			(unlocked yes)
			(layer "B.Fab")
			(hide yes)
			(effects
				(font
					(size 1 1)
					(thickness 0.15)
				)
				(justify mirror)
			)
		)
		(property "Val" "2k2"
			(at 0 0 90)
			(unlocked yes)
			(layer "B.Fab")
			(hide yes)
			(effects
				(font
					(size 1 1)
					(thickness 0.15)
				)
				(justify mirror)
			)
		)
		(property "Tolerance" "1%"
			(at 0 0 90)
			(unlocked yes)
			(layer "B.Fab")
			(hide yes)
			(effects
				(font
					(size 1 1)
					(thickness 0.15)
				)
				(justify mirror)
			)
		)
		(sheetname "/CSI/")
		(sheetfile "csi.kicad_sch")
		(attr smd)
		(fp_rect
			(start -0.925 0.47)
			(end 0.925 -0.47)
			(stroke
				(width 0.05)
				(type default)
			)
			(fill no)
			(layer "B.CrtYd")
		)
		(fp_rect
			(start -0.5 0.25)
			(end 0.5 -0.25)
			(stroke
				(width 0.15)
				(type solid)
			)
			(fill no)
			(layer "B.Fab")
		)
		(fp_text user "License: Apache-2.0"
			(at -0.95 -5.169 90)
			(layer "B.Fab")
			(effects
				(font
					(size 0.7 0.7)
					(thickness 0.15)
				)
				(justify left bottom mirror)
			)
		)
		(fp_text user "Author: Antmicro"
			(at -0.95 -4.169 90)
			(layer "B.Fab")
			(effects
				(font
					(size 0.7 0.7)
					(thickness 0.15)
				)
				(justify left bottom mirror)
			)
		)
		(fp_text user "${REFERENCE}"
			(at -0.95 -3.168 90)
			(layer "B.Fab")
			(effects
				(font
					(size 0.7 0.7)
					(thickness 0.15)
				)
				(justify left bottom mirror)
			)
		)
		(pad "1" smd roundrect
			(at -0.48 0 270)
			(size 0.59 0.64)
			(layers "B.Cu" "B.Mask" "B.Paste")
			(roundrect_rratio 0.25)
			(net 990 "/CSI/CSIB_I2C_VCC")
			(pintype "passive")
		)
		(pad "2" smd roundrect
			(at 0.48 0 270)
			(size 0.59 0.64)
			(layers "B.Cu" "B.Mask" "B.Paste")
			(roundrect_rratio 0.25)
			(net 991 "/CSI/SDA_CAM3")
			(pintype "passive")
		)
	)
	(footprint "antmicro-footprints:R_0402_1005Metric"
		(layer "B.Cu")
		(at 214.9 95.1 -90)
		(descr "Resistor SMD 0402")
		(tags "resistor SMD 0402")
		(property "Reference" "R118"
			(at 1 -0.4 90)
			(layer "B.SilkS")
			(effects
				(font
					(size 0.7 0.7)
					(thickness 0.15)
				)
				(justify left bottom mirror)
			)
		)
		(property "Value" "R_0R_0402"
			(at -1.011843 -1.772046 90)
			(layer "B.Fab")
			(effects
				(font
					(size 0.7 0.7)
					(thickness 0.15)
				)
				(justify left bottom mirror)
			)
		)
		(property "Datasheet" "https://industrial.panasonic.com/cdbs/www-data/pdf/RDA0000/AOA0000C301.pdf"
			(at 0 0 90)
			(layer "B.Fab")
			(hide yes)
			(effects
				(font
					(size 1.27 1.27)
					(thickness 0.15)
				)
				(justify mirror)
			)
		)
		(property "Description" "SMD Chip Resistor, Jumper, 0 ohm, 100 mW, 0402 [1005 Metric], Thick Film, General Purpose"
			(at 0 0 90)
			(layer "B.Fab")
			(hide yes)
			(effects
				(font
					(size 1.27 1.27)
					(thickness 0.15)
				)
				(justify mirror)
			)
		)
		(property "Manufacturer" "Panasonic"
			(at 0 0 90)
			(unlocked yes)
			(layer "B.Fab")
			(hide yes)
			(effects
				(font
					(size 1 1)
					(thickness 0.15)
				)
				(justify mirror)
			)
		)
		(property "MPN" "ERJ2GE0R00X"
			(at 0 0 90)
			(unlocked yes)
			(layer "B.Fab")
			(hide yes)
			(effects
				(font
					(size 1 1)
					(thickness 0.15)
				)
				(justify mirror)
			)
		)
		(property "Val" "0R"
			(at 0 0 90)
			(unlocked yes)
			(layer "B.Fab")
			(hide yes)
			(effects
				(font
					(size 1 1)
					(thickness 0.15)
				)
				(justify mirror)
			)
		)
		(property "License" "Apache-2.0"
			(at 0 0 90)
			(unlocked yes)
			(layer "B.Fab")
			(hide yes)
			(effects
				(font
					(size 1 1)
					(thickness 0.15)
				)
				(justify mirror)
			)
		)
		(property "Author" "Antmicro"
			(at 0 0 90)
			(unlocked yes)
			(layer "B.Fab")
			(hide yes)
			(effects
				(font
					(size 1 1)
					(thickness 0.15)
				)
				(justify mirror)
			)
		)
		(property "Tolerance" "~"
			(at 0 0 90)
			(unlocked yes)
			(layer "B.Fab")
			(hide yes)
			(effects
				(font
					(size 1 1)
					(thickness 0.15)
				)
				(justify mirror)
			)
		)
		(property "Current" "1A"
			(at 0 0 90)
			(unlocked yes)
			(layer "B.Fab")
			(hide yes)
			(effects
				(font
					(size 1 1)
					(thickness 0.15)
				)
				(justify mirror)
			)
		)
		(sheetname "/USB DP Alt mode/")
		(sheetfile "usb_dp.kicad_sch")
		(attr smd)
		(fp_poly
			(pts
				(xy -0.925 0.47) (xy -0.925 -0.47) (xy 0.925 -0.47) (xy 0.925 0.47)
			)
			(stroke
				(width 0.05)
				(type default)
			)
			(fill no)
			(layer "B.CrtYd")
		)
		(fp_poly
			(pts
				(xy -0.5 0.25) (xy -0.5 -0.25) (xy 0.5 -0.25) (xy 0.5 0.25)
			)
			(stroke
				(width 0.15)
				(type solid)
			)
			(fill no)
			(layer "B.Fab")
		)
		(fp_text user "Author: Antmicro"
			(at -0.95 -4.169 90)
			(layer "B.Fab")
			(effects
				(font
					(size 0.7 0.7)
					(thickness 0.15)
				)
				(justify left bottom mirror)
			)
		)
		(fp_text user "${REFERENCE}"
			(at -0.95 -3.168 90)
			(layer "B.Fab")
			(effects
				(font
					(size 0.7 0.7)
					(thickness 0.15)
				)
				(justify left bottom mirror)
			)
		)
		(fp_text user "License: Apache-2.0"
			(at -0.949999 -5.169 90)
			(layer "B.Fab")
			(effects
				(font
					(size 0.7 0.7)
					(thickness 0.15)
				)
				(justify left bottom mirror)
			)
		)
		(pad "1" smd roundrect
			(at -0.48 0 270)
			(size 0.59 0.64)
			(layers "B.Cu" "B.Mask" "B.Paste")
			(roundrect_rratio 0.25)
			(net 788 "/SoM_IO2/DP0.HPD")
			(pintype "passive")
		)
		(pad "2" smd roundrect
			(at 0.48 0 270)
			(size 0.59 0.64)
			(layers "B.Cu" "B.Mask" "B.Paste")
			(roundrect_rratio 0.25)
			(net 1301 "Net-(Q35-D)")
			(pintype "passive")
		)
	)
	(footprint "antmicro-footprints:R_0402_1005Metric"
		(layer "B.Cu")
		(at 207.8 79.3 180)
		(descr "Resistor SMD 0402")
		(tags "resistor SMD 0402")
		(property "Reference" "R95"
			(at -3.1 -0.425 0)
			(layer "B.SilkS")
			(effects
				(font
					(size 0.7 0.7)
					(thickness 0.15)
				)
				(justify left bottom mirror)
			)
		)
		(property "Value" "R_100k_0402"
			(at -1.011843 -1.772047 0)
			(layer "B.Fab")
			(effects
				(font
					(size 0.7 0.7)
					(thickness 0.15)
				)
				(justify left bottom mirror)
			)
		)
		(property "Datasheet" "https://www.bourns.com/docs/product-datasheets/cr.pdf"
			(at 0 0 0)
			(layer "B.Fab")
			(hide yes)
			(effects
				(font
					(size 1.27 1.27)
					(thickness 0.15)
				)
				(justify mirror)
			)
		)
		(property "Description" "SMD Chip Resistor, 100 kohm, ± 1%, 62.5 mW, 0402 [1005 Metric], Thick Film, General Purpose"
			(at 0 0 0)
			(layer "B.Fab")
			(hide yes)
			(effects
				(font
					(size 1.27 1.27)
					(thickness 0.15)
				)
				(justify mirror)
			)
		)
		(property "Manufacturer" "Bourns"
			(at 0 0 0)
			(unlocked yes)
			(layer "B.Fab")
			(hide yes)
			(effects
				(font
					(size 1 1)
					(thickness 0.15)
				)
				(justify mirror)
			)
		)
		(property "MPN" "CR0402-FX-1003GLF"
			(at 0 0 0)
			(unlocked yes)
			(layer "B.Fab")
			(hide yes)
			(effects
				(font
					(size 1 1)
					(thickness 0.15)
				)
				(justify mirror)
			)
		)
		(property "Val" "100k"
			(at 0 0 0)
			(unlocked yes)
			(layer "B.Fab")
			(hide yes)
			(effects
				(font
					(size 1 1)
					(thickness 0.15)
				)
				(justify mirror)
			)
		)
		(property "License" "Apache-2.0"
			(at 0 0 0)
			(unlocked yes)
			(layer "B.Fab")
			(hide yes)
			(effects
				(font
					(size 1 1)
					(thickness 0.15)
				)
				(justify mirror)
			)
		)
		(property "Author" "Antmicro"
			(at 0 0 0)
			(unlocked yes)
			(layer "B.Fab")
			(hide yes)
			(effects
				(font
					(size 1 1)
					(thickness 0.15)
				)
				(justify mirror)
			)
		)
		(property "Tolerance" "1%"
			(at 0 0 0)
			(unlocked yes)
			(layer "B.Fab")
			(hide yes)
			(effects
				(font
					(size 1 1)
					(thickness 0.15)
				)
				(justify mirror)
			)
		)
		(sheetname "/USB Debug, PD/")
		(sheetfile "usb_debug_pd.kicad_sch")
		(attr smd)
		(fp_rect
			(start -0.925 0.47)
			(end 0.925 -0.47)
			(stroke
				(width 0.05)
				(type default)
			)
			(fill no)
			(layer "B.CrtYd")
		)
		(fp_rect
			(start -0.5 0.25)
			(end 0.5 -0.25)
			(stroke
				(width 0.15)
				(type solid)
			)
			(fill no)
			(layer "B.Fab")
		)
		(fp_text user "License: Apache-2.0"
			(at -0.95 -5.169 0)
			(layer "B.Fab")
			(effects
				(font
					(size 0.7 0.7)
					(thickness 0.15)
				)
				(justify left bottom mirror)
			)
		)
		(fp_text user "Author: Antmicro"
			(at -0.95 -4.169 0)
			(layer "B.Fab")
			(effects
				(font
					(size 0.7 0.7)
					(thickness 0.15)
				)
				(justify left bottom mirror)
			)
		)
		(fp_text user "${REFERENCE}"
			(at -0.95 -3.168 0)
			(layer "B.Fab")
			(effects
				(font
					(size 0.7 0.7)
					(thickness 0.15)
				)
				(justify left bottom mirror)
			)
		)
		(pad "1" smd roundrect
			(at -0.48 0 180)
			(size 0.59 0.64)
			(layers "B.Cu" "B.Mask" "B.Paste")
			(roundrect_rratio 0.25)
			(net 294 "/USB Debug, PD/PDC_LDO_3V3")
			(pintype "passive")
		)
		(pad "2" smd roundrect
			(at 0.48 0 180)
			(size 0.59 0.64)
			(layers "B.Cu" "B.Mask" "B.Paste")
			(roundrect_rratio 0.25)
			(net 934 "/USB Debug, PD/PDC_ADCIN1")
			(pintype "passive")
		)
	)
	(footprint "antmicro-footprints:TP_SMD_0.75mm"
		(layer "B.Cu")
		(at 171.89 58 180)
		(property "Reference" "TP129"
			(at -0.42 4.05 90)
			(layer "B.SilkS")
			(effects
				(font
					(size 0.7 0.7)
					(thickness 0.15)
				)
				(justify left bottom mirror)
			)
		)
		(property "Value" "TP_0.75mm_SMD"
			(at 0 -1.2 0)
			(layer "B.Fab")
			(effects
				(font
					(size 0.7 0.7)
					(thickness 0.15)
				)
				(justify left bottom mirror)
			)
		)
		(property "Description" "SMT test point"
			(at 0 0 0)
			(layer "B.Fab")
			(hide yes)
			(effects
				(font
					(size 1.27 1.27)
					(thickness 0.15)
				)
				(justify mirror)
			)
		)
		(property "MPN" ""
			(at 0 0 0)
			(unlocked yes)
			(layer "B.Fab")
			(hide yes)
			(effects
				(font
					(size 1 1)
					(thickness 0.15)
				)
				(justify mirror)
			)
		)
		(property "Manufacturer" ""
			(at 0 0 0)
			(unlocked yes)
			(layer "B.Fab")
			(hide yes)
			(effects
				(font
					(size 1 1)
					(thickness 0.15)
				)
				(justify mirror)
			)
		)
		(property "Author" "Antmicro"
			(at 0 0 0)
			(unlocked yes)
			(layer "B.Fab")
			(hide yes)
			(effects
				(font
					(size 1 1)
					(thickness 0.15)
				)
				(justify mirror)
			)
		)
		(property "License" "Apache-2.0"
			(at 0 0 0)
			(unlocked yes)
			(layer "B.Fab")
			(hide yes)
			(effects
				(font
					(size 1 1)
					(thickness 0.15)
				)
				(justify mirror)
			)
		)
		(sheetname "/Power/")
		(sheetfile "power.kicad_sch")
		(attr exclude_from_pos_files exclude_from_bom)
		(fp_circle
			(center 0 0)
			(end 0.475 0)
			(stroke
				(width 0.05)
				(type default)
			)
			(fill no)
			(layer "B.CrtYd")
		)
		(fp_text user "${REFERENCE}"
			(at -0.4 -2.7 0)
			(layer "B.Fab")
			(effects
				(font
					(size 0.7 0.7)
					(thickness 0.15)
				)
				(justify left bottom mirror)
			)
		)
		(fp_text user "License: Apache-2.0"
			(at -0.4 -5.101 0)
			(layer "B.Fab")
			(effects
				(font
					(size 0.7 0.7)
					(thickness 0.15)
				)
				(justify left bottom mirror)
			)
		)
		(fp_text user "Author: Antmicro"
			(at -0.4 -3.901 0)
			(layer "B.Fab")
			(effects
				(font
					(size 0.7 0.7)
					(thickness 0.15)
				)
				(justify left bottom mirror)
			)
		)
		(pad "1" smd circle
			(at 0 0 180)
			(size 0.75 0.75)
			(layers "B.Cu" "B.Mask")
			(net 5 "+5V")
			(pinfunction "1")
			(pintype "passive")
		)
	)
	(footprint "antmicro-footprints:TP_SMD_0.75mm"
		(layer "B.Cu")
		(at 92.1 60.454 180)
		(property "Reference" "TP117"
			(at -0.59 -0.466 90)
			(layer "B.SilkS")
			(effects
				(font
					(size 0.7 0.7)
					(thickness 0.15)
				)
				(justify left bottom mirror)
			)
		)
		(property "Value" "TP_0.75mm_SMD"
			(at 0 -1.2 0)
			(layer "B.Fab")
			(effects
				(font
					(size 0.7 0.7)
					(thickness 0.15)
				)
				(justify left bottom mirror)
			)
		)
		(property "Description" "SMT test point"
			(at 0 0 0)
			(layer "B.Fab")
			(hide yes)
			(effects
				(font
					(size 1.27 1.27)
					(thickness 0.15)
				)
				(justify mirror)
			)
		)
		(property "MPN" ""
			(at 0 0 0)
			(unlocked yes)
			(layer "B.Fab")
			(hide yes)
			(effects
				(font
					(size 1 1)
					(thickness 0.15)
				)
				(justify mirror)
			)
		)
		(property "Manufacturer" ""
			(at 0 0 0)
			(unlocked yes)
			(layer "B.Fab")
			(hide yes)
			(effects
				(font
					(size 1 1)
					(thickness 0.15)
				)
				(justify mirror)
			)
		)
		(property "Author" "Antmicro"
			(at 0 0 0)
			(unlocked yes)
			(layer "B.Fab")
			(hide yes)
			(effects
				(font
					(size 1 1)
					(thickness 0.15)
				)
				(justify mirror)
			)
		)
		(property "License" "Apache-2.0"
			(at 0 0 0)
			(unlocked yes)
			(layer "B.Fab")
			(hide yes)
			(effects
				(font
					(size 1 1)
					(thickness 0.15)
				)
				(justify mirror)
			)
		)
		(sheetname "/SoM_Power/")
		(sheetfile "som_power.kicad_sch")
		(attr exclude_from_pos_files exclude_from_bom)
		(fp_circle
			(center 0 0)
			(end 0.475 0)
			(stroke
				(width 0.05)
				(type default)
			)
			(fill no)
			(layer "B.CrtYd")
		)
		(fp_text user "Author: Antmicro"
			(at -0.4 -3.901 0)
			(layer "B.Fab")
			(effects
				(font
					(size 0.7 0.7)
					(thickness 0.15)
				)
				(justify left bottom mirror)
			)
		)
		(fp_text user "License: Apache-2.0"
			(at -0.4 -5.101 0)
			(layer "B.Fab")
			(effects
				(font
					(size 0.7 0.7)
					(thickness 0.15)
				)
				(justify left bottom mirror)
			)
		)
		(fp_text user "${REFERENCE}"
			(at -0.4 -2.7 0)
			(layer "B.Fab")
			(effects
				(font
					(size 0.7 0.7)
					(thickness 0.15)
				)
				(justify left bottom mirror)
			)
		)
		(pad "1" smd circle
			(at 0 0 180)
			(size 0.75 0.75)
			(layers "B.Cu" "B.Mask")
			(net 610 "/SoM_Power/~{PWR_BTN}")
			(pinfunction "1")
			(pintype "passive")
		)
	)
	(footprint "antmicro-footprints:R_0402_1005Metric"
		(layer "B.Cu")
		(at 109.82 133.3)
		(descr "Resistor SMD 0402")
		(tags "resistor SMD 0402")
		(property "Reference" "R215"
			(at -3.82 -0.24 0)
			(layer "B.SilkS")
			(effects
				(font
					(size 0.7 0.7)
					(thickness 0.15)
				)
				(justify right top mirror)
			)
		)
		(property "Value" "R_0R_0402"
			(at -1.011843 -1.772047 0)
			(layer "B.Fab")
			(effects
				(font
					(size 0.7 0.7)
					(thickness 0.15)
				)
				(justify right top mirror)
			)
		)
		(property "Datasheet" "https://industrial.panasonic.com/cdbs/www-data/pdf/RDA0000/AOA0000C301.pdf"
			(at 0 0 0)
			(layer "B.Fab")
			(hide yes)
			(effects
				(font
					(size 1.27 1.27)
					(thickness 0.15)
				)
				(justify mirror)
			)
		)
		(property "Description" "SMD Chip Resistor, Jumper, 0 ohm, 100 mW, 0402 [1005 Metric], Thick Film, General Purpose"
			(at 0 0 0)
			(layer "B.Fab")
			(hide yes)
			(effects
				(font
					(size 1.27 1.27)
					(thickness 0.15)
				)
				(justify mirror)
			)
		)
		(property "MPN" "ERJ2GE0R00X"
			(at 0 0 180)
			(unlocked yes)
			(layer "B.Fab")
			(hide yes)
			(effects
				(font
					(size 1 1)
					(thickness 0.15)
				)
				(justify mirror)
			)
		)
		(property "Manufacturer" "Panasonic"
			(at 0 0 180)
			(unlocked yes)
			(layer "B.Fab")
			(hide yes)
			(effects
				(font
					(size 1 1)
					(thickness 0.15)
				)
				(justify mirror)
			)
		)
		(property "License" "Apache-2.0"
			(at 0 0 180)
			(unlocked yes)
			(layer "B.Fab")
			(hide yes)
			(effects
				(font
					(size 1 1)
					(thickness 0.15)
				)
				(justify mirror)
			)
		)
		(property "Author" "Antmicro"
			(at 0 0 180)
			(unlocked yes)
			(layer "B.Fab")
			(hide yes)
			(effects
				(font
					(size 1 1)
					(thickness 0.15)
				)
				(justify mirror)
			)
		)
		(property "Val" "0R"
			(at 0 0 180)
			(unlocked yes)
			(layer "B.Fab")
			(hide yes)
			(effects
				(font
					(size 1 1)
					(thickness 0.15)
				)
				(justify mirror)
			)
		)
		(property "Tolerance" "~"
			(at 0 0 180)
			(unlocked yes)
			(layer "B.Fab")
			(hide yes)
			(effects
				(font
					(size 1 1)
					(thickness 0.15)
				)
				(justify mirror)
			)
		)
		(property "Current" "1A"
			(at 0 0 180)
			(unlocked yes)
			(layer "B.Fab")
			(hide yes)
			(effects
				(font
					(size 1 1)
					(thickness 0.15)
				)
				(justify mirror)
			)
		)
		(sheetname "/M.2/")
		(sheetfile "m2.kicad_sch")
		(attr smd)
		(fp_rect
			(start -0.925 0.47)
			(end 0.925 -0.47)
			(stroke
				(width 0.05)
				(type default)
			)
			(fill no)
			(layer "B.CrtYd")
		)
		(fp_rect
			(start -0.5 0.25)
			(end 0.5 -0.25)
			(stroke
				(width 0.15)
				(type solid)
			)
			(fill no)
			(layer "B.Fab")
		)
		(fp_text user "Author: Antmicro"
			(at -0.95 -4.169 0)
			(layer "B.Fab")
			(effects
				(font
					(size 0.7 0.7)
					(thickness 0.15)
				)
				(justify right top mirror)
			)
		)
		(fp_text user "License: Apache-2.0"
			(at -0.95 -5.169 0)
			(layer "B.Fab")
			(effects
				(font
					(size 0.7 0.7)
					(thickness 0.15)
				)
				(justify right top mirror)
			)
		)
		(fp_text user "${REFERENCE}"
			(at -0.95 -3.168 0)
			(layer "B.Fab")
			(effects
				(font
					(size 0.7 0.7)
					(thickness 0.15)
				)
				(justify right top mirror)
			)
		)
		(pad "1" smd roundrect
			(at -0.48 0)
			(size 0.59 0.64)
			(layers "B.Cu" "B.Mask" "B.Paste")
			(roundrect_rratio 0.25)
			(net 137 "/M.2/PCIe_{C1x1}.~{CLKREQ}")
			(pintype "passive")
		)
		(pad "2" smd roundrect
			(at 0.48 0)
			(size 0.59 0.64)
			(layers "B.Cu" "B.Mask" "B.Paste")
			(roundrect_rratio 0.25)
			(net 834 "/M.2/~{CLKREQ_E}")
			(pintype "passive")
		)
	)
	(footprint "antmicro-footprints:R_0402_1005Metric"
		(layer "B.Cu")
		(at 168.5 57.5 -90)
		(descr "Resistor SMD 0402")
		(tags "resistor SMD 0402")
		(property "Reference" "R32"
			(at -3.58 -0.315532 90)
			(layer "B.SilkS")
			(effects
				(font
					(size 0.7 0.7)
					(thickness 0.15)
				)
				(justify left bottom mirror)
			)
		)
		(property "Value" "R_200R_0402"
			(at -1.011843 -1.772047 90)
			(layer "B.Fab")
			(effects
				(font
					(size 0.7 0.7)
					(thickness 0.15)
				)
				(justify left bottom mirror)
			)
		)
		(property "Datasheet" "https://www.bourns.com/docs/product-datasheets/cr.pdf"
			(at 0 0 90)
			(layer "B.Fab")
			(hide yes)
			(effects
				(font
					(size 1.27 1.27)
					(thickness 0.15)
				)
				(justify mirror)
			)
		)
		(property "Description" "SMD Chip Resistor, 200 ohm, ± 1%, 62.5 mW, 0402 [1005 Metric], Thick Film, General Purpose"
			(at 0 0 90)
			(layer "B.Fab")
			(hide yes)
			(effects
				(font
					(size 1.27 1.27)
					(thickness 0.15)
				)
				(justify mirror)
			)
		)
		(property "Manufacturer" "Bourns"
			(at 0 0 90)
			(unlocked yes)
			(layer "B.Fab")
			(hide yes)
			(effects
				(font
					(size 1 1)
					(thickness 0.15)
				)
				(justify mirror)
			)
		)
		(property "MPN" "CR0402-FX-2000GLF"
			(at 0 0 90)
			(unlocked yes)
			(layer "B.Fab")
			(hide yes)
			(effects
				(font
					(size 1 1)
					(thickness 0.15)
				)
				(justify mirror)
			)
		)
		(property "Val" "200R"
			(at 0 0 90)
			(unlocked yes)
			(layer "B.Fab")
			(hide yes)
			(effects
				(font
					(size 1 1)
					(thickness 0.15)
				)
				(justify mirror)
			)
		)
		(property "License" "Apache-2.0"
			(at 0 0 90)
			(unlocked yes)
			(layer "B.Fab")
			(hide yes)
			(effects
				(font
					(size 1 1)
					(thickness 0.15)
				)
				(justify mirror)
			)
		)
		(property "Author" "Antmicro"
			(at 0 0 90)
			(unlocked yes)
			(layer "B.Fab")
			(hide yes)
			(effects
				(font
					(size 1 1)
					(thickness 0.15)
				)
				(justify mirror)
			)
		)
		(property "Tolerance" "1%"
			(at 0 0 90)
			(unlocked yes)
			(layer "B.Fab")
			(hide yes)
			(effects
				(font
					(size 1 1)
					(thickness 0.15)
				)
				(justify mirror)
			)
		)
		(sheetname "/Power/")
		(sheetfile "power.kicad_sch")
		(attr smd)
		(fp_rect
			(start -0.925 0.47)
			(end 0.925 -0.47)
			(stroke
				(width 0.05)
				(type default)
			)
			(fill no)
			(layer "B.CrtYd")
		)
		(fp_rect
			(start -0.5 0.25)
			(end 0.5 -0.25)
			(stroke
				(width 0.15)
				(type solid)
			)
			(fill no)
			(layer "B.Fab")
		)
		(fp_text user "License: Apache-2.0"
			(at -0.95 -5.169 90)
			(layer "B.Fab")
			(effects
				(font
					(size 0.7 0.7)
					(thickness 0.15)
				)
				(justify left bottom mirror)
			)
		)
		(fp_text user "Author: Antmicro"
			(at -0.95 -4.169 90)
			(layer "B.Fab")
			(effects
				(font
					(size 0.7 0.7)
					(thickness 0.15)
				)
				(justify left bottom mirror)
			)
		)
		(fp_text user "${REFERENCE}"
			(at -0.95 -3.168 90)
			(layer "B.Fab")
			(effects
				(font
					(size 0.7 0.7)
					(thickness 0.15)
				)
				(justify left bottom mirror)
			)
		)
		(pad "1" smd roundrect
			(at -0.48 0 270)
			(size 0.59 0.64)
			(layers "B.Cu" "B.Mask" "B.Paste")
			(roundrect_rratio 0.25)
			(net 526 "Net-(D3-A)")
			(pintype "passive")
		)
		(pad "2" smd roundrect
			(at 0.48 0 270)
			(size 0.59 0.64)
			(layers "B.Cu" "B.Mask" "B.Paste")
			(roundrect_rratio 0.25)
			(net 4 "+3V3_AON")
			(pintype "passive")
		)
	)
	(footprint "antmicro-footprints:TP_SMD_0.75mm"
		(layer "B.Cu")
		(at 178.61 58 -90)
		(property "Reference" "TP125"
			(at -4.04 -0.43 90)
			(layer "B.SilkS")
			(effects
				(font
					(size 0.7 0.7)
					(thickness 0.15)
				)
				(justify left bottom mirror)
			)
		)
		(property "Value" "TP_0.75mm_SMD"
			(at 0 -1.2 90)
			(layer "B.Fab")
			(effects
				(font
					(size 0.7 0.7)
					(thickness 0.15)
				)
				(justify left bottom mirror)
			)
		)
		(property "Description" "SMT test point"
			(at 0 0 90)
			(layer "B.Fab")
			(hide yes)
			(effects
				(font
					(size 1.27 1.27)
					(thickness 0.15)
				)
				(justify mirror)
			)
		)
		(property "MPN" ""
			(at 0 0 90)
			(unlocked yes)
			(layer "B.Fab")
			(hide yes)
			(effects
				(font
					(size 1 1)
					(thickness 0.15)
				)
				(justify mirror)
			)
		)
		(property "Manufacturer" ""
			(at 0 0 90)
			(unlocked yes)
			(layer "B.Fab")
			(hide yes)
			(effects
				(font
					(size 1 1)
					(thickness 0.15)
				)
				(justify mirror)
			)
		)
		(property "Author" "Antmicro"
			(at 0 0 90)
			(unlocked yes)
			(layer "B.Fab")
			(hide yes)
			(effects
				(font
					(size 1 1)
					(thickness 0.15)
				)
				(justify mirror)
			)
		)
		(property "License" "Apache-2.0"
			(at 0 0 90)
			(unlocked yes)
			(layer "B.Fab")
			(hide yes)
			(effects
				(font
					(size 1 1)
					(thickness 0.15)
				)
				(justify mirror)
			)
		)
		(sheetname "/Power/")
		(sheetfile "power.kicad_sch")
		(attr exclude_from_pos_files exclude_from_bom)
		(fp_circle
			(center 0 0)
			(end 0.475 0)
			(stroke
				(width 0.05)
				(type default)
			)
			(fill no)
			(layer "B.CrtYd")
		)
		(fp_text user "Author: Antmicro"
			(at -0.4 -3.901 90)
			(layer "B.Fab")
			(effects
				(font
					(size 0.7 0.7)
					(thickness 0.15)
				)
				(justify left bottom mirror)
			)
		)
		(fp_text user "${REFERENCE}"
			(at -0.4 -2.7 90)
			(layer "B.Fab")
			(effects
				(font
					(size 0.7 0.7)
					(thickness 0.15)
				)
				(justify left bottom mirror)
			)
		)
		(fp_text user "License: Apache-2.0"
			(at -0.4 -5.101 90)
			(layer "B.Fab")
			(effects
				(font
					(size 0.7 0.7)
					(thickness 0.15)
				)
				(justify left bottom mirror)
			)
		)
		(pad "1" smd circle
			(at 0 0 270)
			(size 0.75 0.75)
			(layers "B.Cu" "B.Mask")
			(net 634 "+12V")
			(pinfunction "1")
			(pintype "passive")
		)
	)
	(footprint "antmicro-footprints:TP_SMD_0.75mm"
		(layer "B.Cu")
		(at 124.5 72.6 90)
		(property "Reference" "TP51"
			(at -3.2 -0.3 90)
			(layer "B.SilkS")
			(effects
				(font
					(size 0.7 0.7)
					(thickness 0.15)
				)
				(justify right top mirror)
			)
		)
		(property "Value" "TP_0.75mm_SMD"
			(at 0 -1.2 90)
			(layer "B.Fab")
			(effects
				(font
					(size 0.7 0.7)
					(thickness 0.15)
				)
				(justify right top mirror)
			)
		)
		(property "Description" "SMT test point"
			(at 0 0 90)
			(layer "B.Fab")
			(hide yes)
			(effects
				(font
					(size 1.27 1.27)
					(thickness 0.15)
				)
				(justify mirror)
			)
		)
		(property "MPN" ""
			(at 0 0 270)
			(unlocked yes)
			(layer "B.Fab")
			(hide yes)
			(effects
				(font
					(size 1 1)
					(thickness 0.15)
				)
				(justify mirror)
			)
		)
		(property "Manufacturer" ""
			(at 0 0 270)
			(unlocked yes)
			(layer "B.Fab")
			(hide yes)
			(effects
				(font
					(size 1 1)
					(thickness 0.15)
				)
				(justify mirror)
			)
		)
		(property "Author" "Antmicro"
			(at 0 0 270)
			(unlocked yes)
			(layer "B.Fab")
			(hide yes)
			(effects
				(font
					(size 1 1)
					(thickness 0.15)
				)
				(justify mirror)
			)
		)
		(property "License" "Apache-2.0"
			(at 0 0 270)
			(unlocked yes)
			(layer "B.Fab")
			(hide yes)
			(effects
				(font
					(size 1 1)
					(thickness 0.15)
				)
				(justify mirror)
			)
		)
		(sheetname "/SoM_Power/")
		(sheetfile "som_power.kicad_sch")
		(attr exclude_from_pos_files exclude_from_bom)
		(fp_circle
			(center 0 0)
			(end 0.475 0)
			(stroke
				(width 0.05)
				(type default)
			)
			(fill no)
			(layer "B.CrtYd")
		)
		(fp_text user "${REFERENCE}"
			(at -0.4 -2.7 90)
			(layer "B.Fab")
			(effects
				(font
					(size 0.7 0.7)
					(thickness 0.15)
				)
				(justify right top mirror)
			)
		)
		(fp_text user "Author: Antmicro"
			(at -0.4 -3.901 90)
			(layer "B.Fab")
			(effects
				(font
					(size 0.7 0.7)
					(thickness 0.15)
				)
				(justify right top mirror)
			)
		)
		(fp_text user "License: Apache-2.0"
			(at -0.4 -5.101 90)
			(layer "B.Fab")
			(effects
				(font
					(size 0.7 0.7)
					(thickness 0.15)
				)
				(justify right top mirror)
			)
		)
		(pad "1" smd circle
			(at 0 0 90)
			(size 0.75 0.75)
			(layers "B.Cu" "B.Mask")
			(net 762 "Net-(J1A-SYSTEM_OC_N)")
			(pinfunction "1")
			(pintype "passive")
		)
	)
	(footprint "antmicro-footprints:TP_SMD_0.75mm"
		(layer "B.Cu")
		(at 98.15 69.7 -90)
		(property "Reference" "TP99"
			(at 0 0.6 90)
			(layer "B.SilkS")
			(effects
				(font
					(size 0.7 0.7)
					(thickness 0.15)
				)
				(justify left bottom mirror)
			)
		)
		(property "Value" "TP_0.75mm_SMD"
			(at 0 -1.2 90)
			(layer "B.Fab")
			(effects
				(font
					(size 0.7 0.7)
					(thickness 0.15)
				)
				(justify left bottom mirror)
			)
		)
		(property "Description" "SMT test point"
			(at 0 0 90)
			(layer "B.Fab")
			(hide yes)
			(effects
				(font
					(size 1.27 1.27)
					(thickness 0.15)
				)
				(justify mirror)
			)
		)
		(property "MPN" ""
			(at 0 0 90)
			(unlocked yes)
			(layer "B.Fab")
			(hide yes)
			(effects
				(font
					(size 1 1)
					(thickness 0.15)
				)
				(justify mirror)
			)
		)
		(property "Manufacturer" ""
			(at 0 0 90)
			(unlocked yes)
			(layer "B.Fab")
			(hide yes)
			(effects
				(font
					(size 1 1)
					(thickness 0.15)
				)
				(justify mirror)
			)
		)
		(property "Author" "Antmicro"
			(at 0 0 90)
			(unlocked yes)
			(layer "B.Fab")
			(hide yes)
			(effects
				(font
					(size 1 1)
					(thickness 0.15)
				)
				(justify mirror)
			)
		)
		(property "License" "Apache-2.0"
			(at 0 0 90)
			(unlocked yes)
			(layer "B.Fab")
			(hide yes)
			(effects
				(font
					(size 1 1)
					(thickness 0.15)
				)
				(justify mirror)
			)
		)
		(sheetname "/SoM_IO/")
		(sheetfile "som_io.kicad_sch")
		(attr exclude_from_pos_files exclude_from_bom)
		(fp_circle
			(center 0 0)
			(end 0.475 0)
			(stroke
				(width 0.05)
				(type default)
			)
			(fill no)
			(layer "B.CrtYd")
		)
		(fp_text user "License: Apache-2.0"
			(at -0.4 -5.101 90)
			(layer "B.Fab")
			(effects
				(font
					(size 0.7 0.7)
					(thickness 0.15)
				)
				(justify left bottom mirror)
			)
		)
		(fp_text user "${REFERENCE}"
			(at -0.4 -2.7 90)
			(layer "B.Fab")
			(effects
				(font
					(size 0.7 0.7)
					(thickness 0.15)
				)
				(justify left bottom mirror)
			)
		)
		(fp_text user "Author: Antmicro"
			(at -0.4 -3.901 90)
			(layer "B.Fab")
			(effects
				(font
					(size 0.7 0.7)
					(thickness 0.15)
				)
				(justify left bottom mirror)
			)
		)
		(pad "1" smd circle
			(at 0 0 270)
			(size 0.75 0.75)
			(layers "B.Cu" "B.Mask")
			(net 107 "/SoM_IO/I2S_{M.2}.CLK")
			(pinfunction "1")
			(pintype "passive")
		)
	)
	(footprint "antmicro-footprints:C_0805_2012Metric"
		(layer "B.Cu")
		(at 229.1 95.1 90)
		(descr "Capacitor SMD 0805")
		(tags "capacitor SMD 0805")
		(property "Reference" "C68"
			(at -3.8 0.6 90)
			(layer "B.SilkS")
			(effects
				(font
					(size 0.7 0.7)
					(thickness 0.15)
				)
				(justify right top mirror)
			)
		)
		(property "Value" "C_22u_25V_0805"
			(at -2.055717 -1.963153 90)
			(layer "B.Fab")
			(effects
				(font
					(size 0.7 0.7)
					(thickness 0.15)
				)
				(justify right top mirror)
			)
		)
		(property "Datasheet" "https://product.samsungsem.com/mlcc/CL21A226MAYNNN.do"
			(at 0 0 90)
			(layer "B.Fab")
			(hide yes)
			(effects
				(font
					(size 1.27 1.27)
					(thickness 0.15)
				)
				(justify mirror)
			)
		)
		(property "Description" "SMT Multilayer Ceramic Capacitor, 22uF, +/-20%, 25V, X5R, 0805 [2012 Metric]"
			(at 0 0 90)
			(layer "B.Fab")
			(hide yes)
			(effects
				(font
					(size 1.27 1.27)
					(thickness 0.15)
				)
				(justify mirror)
			)
		)
		(property "Manufacturer" "Samsung Electro-Mechanics"
			(at 0 0 90)
			(unlocked yes)
			(layer "B.Fab")
			(hide yes)
			(effects
				(font
					(size 1 1)
					(thickness 0.15)
				)
				(justify mirror)
			)
		)
		(property "MPN" "CL21A226MAYNNNE"
			(at 0 0 90)
			(unlocked yes)
			(layer "B.Fab")
			(hide yes)
			(effects
				(font
					(size 1 1)
					(thickness 0.15)
				)
				(justify mirror)
			)
		)
		(property "Val" "22u"
			(at 0 0 90)
			(unlocked yes)
			(layer "B.Fab")
			(hide yes)
			(effects
				(font
					(size 1 1)
					(thickness 0.15)
				)
				(justify mirror)
			)
		)
		(property "License" "Apache-2.0"
			(at 0 0 90)
			(unlocked yes)
			(layer "B.Fab")
			(hide yes)
			(effects
				(font
					(size 1 1)
					(thickness 0.15)
				)
				(justify mirror)
			)
		)
		(property "Author" "Antmicro"
			(at 0 0 90)
			(unlocked yes)
			(layer "B.Fab")
			(hide yes)
			(effects
				(font
					(size 1 1)
					(thickness 0.15)
				)
				(justify mirror)
			)
		)
		(property "Voltage" "25V"
			(at 0 0 90)
			(unlocked yes)
			(layer "B.Fab")
			(hide yes)
			(effects
				(font
					(size 1 1)
					(thickness 0.15)
				)
				(justify mirror)
			)
		)
		(property "Dielectric" "X5R"
			(at 0 0 90)
			(unlocked yes)
			(layer "B.Fab")
			(hide yes)
			(effects
				(font
					(size 1 1)
					(thickness 0.15)
				)
				(justify mirror)
			)
		)
		(property "Public" "False"
			(at 0 0 90)
			(unlocked yes)
			(layer "B.Fab")
			(hide yes)
			(effects
				(font
					(size 1 1)
					(thickness 0.15)
				)
				(justify mirror)
			)
		)
		(sheetname "/USB DP Alt mode/")
		(sheetfile "usb_dp.kicad_sch")
		(attr smd)
		(fp_line
			(start -0.3 -0.7)
			(end 0.3 -0.7)
			(stroke
				(width 0.15)
				(type solid)
			)
			(layer "B.SilkS")
		)
		(fp_line
			(start -0.3 0.7)
			(end 0.3 0.7)
			(stroke
				(width 0.15)
				(type solid)
			)
			(layer "B.SilkS")
		)
		(fp_poly
			(pts
				(xy 1.95 0.9) (xy -1.95 0.9) (xy -1.95 -0.9) (xy 1.95 -0.9)
			)
			(stroke
				(width 0.05)
				(type default)
			)
			(fill no)
			(layer "B.CrtYd")
		)
		(fp_poly
			(pts
				(xy -0.95 0.675001) (xy 0.95 0.675001) (xy 0.95 -0.675001) (xy -0.95 -0.675001)
			)
			(stroke
				(width 0.15)
				(type solid)
			)
			(fill no)
			(layer "B.Fab")
		)
		(fp_text user "Author: Antmicro"
			(at -1.9 -5.947 90)
			(layer "B.Fab")
			(effects
				(font
					(size 0.7 0.7)
					(thickness 0.15)
				)
				(justify right top mirror)
			)
		)
		(fp_text user "${REFERENCE}"
			(at -1.899999 -3.947 90)
			(layer "B.Fab")
			(effects
				(font
					(size 0.7 0.7)
					(thickness 0.15)
				)
				(justify right top mirror)
			)
		)
		(fp_text user "License: Apache-2.0"
			(at -1.9 -4.947 90)
			(layer "B.Fab")
			(effects
				(font
					(size 0.7 0.7)
					(thickness 0.15)
				)
				(justify right top mirror)
			)
		)
		(pad "1" smd roundrect
			(at -1.099999 0 90)
			(size 1.2 1.3)
			(layers "B.Cu" "B.Mask" "B.Paste")
			(roundrect_rratio 0.25)
			(net 376 "/USB DP Alt mode/USBC1_VBUS")
			(pintype "passive")
		)
		(pad "2" smd roundrect
			(at 1.099999 0 90)
			(size 1.2 1.3)
			(layers "B.Cu" "B.Mask" "B.Paste")
			(roundrect_rratio 0.25)
			(net 1 "GND")
			(pintype "passive")
		)
	)
	(footprint "antmicro-footprints:R_0402_1005Metric"
		(layer "B.Cu")
		(at 200.8 128.2 180)
		(descr "Resistor SMD 0402")
		(tags "resistor SMD 0402")
		(property "Reference" "R194"
			(at -3.8 -0.4 0)
			(layer "B.SilkS")
			(effects
				(font
					(size 0.7 0.7)
					(thickness 0.15)
				)
				(justify left bottom mirror)
			)
		)
		(property "Value" "R_100k_0402"
			(at -1.011843 -1.772046 0)
			(layer "B.Fab")
			(effects
				(font
					(size 0.7 0.7)
					(thickness 0.15)
				)
				(justify left bottom mirror)
			)
		)
		(property "Datasheet" "https://www.bourns.com/docs/product-datasheets/cr.pdf"
			(at 0 0 0)
			(layer "B.Fab")
			(hide yes)
			(effects
				(font
					(size 1.27 1.27)
					(thickness 0.15)
				)
				(justify mirror)
			)
		)
		(property "Description" "SMD Chip Resistor, 100 kohm, ± 1%, 62.5 mW, 0402 [1005 Metric], Thick Film, General Purpose"
			(at 0 0 0)
			(layer "B.Fab")
			(hide yes)
			(effects
				(font
					(size 1.27 1.27)
					(thickness 0.15)
				)
				(justify mirror)
			)
		)
		(property "MPN" "CR0402-FX-1003GLF"
			(at 0 0 0)
			(unlocked yes)
			(layer "B.Fab")
			(hide yes)
			(effects
				(font
					(size 1 1)
					(thickness 0.15)
				)
				(justify mirror)
			)
		)
		(property "Manufacturer" "Bourns"
			(at 0 0 0)
			(unlocked yes)
			(layer "B.Fab")
			(hide yes)
			(effects
				(font
					(size 1 1)
					(thickness 0.15)
				)
				(justify mirror)
			)
		)
		(property "License" "Apache-2.0"
			(at 0 0 0)
			(unlocked yes)
			(layer "B.Fab")
			(hide yes)
			(effects
				(font
					(size 1 1)
					(thickness 0.15)
				)
				(justify mirror)
			)
		)
		(property "Author" "Antmicro"
			(at 0 0 0)
			(unlocked yes)
			(layer "B.Fab")
			(hide yes)
			(effects
				(font
					(size 1 1)
					(thickness 0.15)
				)
				(justify mirror)
			)
		)
		(property "Val" "100k"
			(at 0 0 0)
			(unlocked yes)
			(layer "B.Fab")
			(hide yes)
			(effects
				(font
					(size 1 1)
					(thickness 0.15)
				)
				(justify mirror)
			)
		)
		(property "Tolerance" "1%"
			(at 0 0 0)
			(unlocked yes)
			(layer "B.Fab")
			(hide yes)
			(effects
				(font
					(size 1 1)
					(thickness 0.15)
				)
				(justify mirror)
			)
		)
		(sheetname "/USB Hub/")
		(sheetfile "usb_hub.kicad_sch")
		(attr smd)
		(fp_poly
			(pts
				(xy -0.925 0.47) (xy -0.925 -0.47) (xy 0.925 -0.47) (xy 0.925 0.47)
			)
			(stroke
				(width 0.05)
				(type default)
			)
			(fill no)
			(layer "B.CrtYd")
		)
		(fp_poly
			(pts
				(xy -0.5 0.25) (xy -0.5 -0.25) (xy 0.5 -0.25) (xy 0.5 0.25)
			)
			(stroke
				(width 0.15)
				(type solid)
			)
			(fill no)
			(layer "B.Fab")
		)
		(fp_text user "License: Apache-2.0"
			(at -0.949999 -5.169 0)
			(layer "B.Fab")
			(effects
				(font
					(size 0.7 0.7)
					(thickness 0.15)
				)
				(justify left bottom mirror)
			)
		)
		(fp_text user "${REFERENCE}"
			(at -0.95 -3.168 0)
			(layer "B.Fab")
			(effects
				(font
					(size 0.7 0.7)
					(thickness 0.15)
				)
				(justify left bottom mirror)
			)
		)
		(fp_text user "Author: Antmicro"
			(at -0.95 -4.169 0)
			(layer "B.Fab")
			(effects
				(font
					(size 0.7 0.7)
					(thickness 0.15)
				)
				(justify left bottom mirror)
			)
		)
		(pad "1" smd roundrect
			(at -0.48 0 180)
			(size 0.59 0.64)
			(layers "B.Cu" "B.Mask" "B.Paste")
			(roundrect_rratio 0.25)
			(net 1 "GND")
			(pintype "passive")
		)
		(pad "2" smd roundrect
			(at 0.48 0 180)
			(size 0.59 0.64)
			(layers "B.Cu" "B.Mask" "B.Paste")
			(roundrect_rratio 0.25)
			(net 924 "/USB Hub/HUB_SPI_D3")
			(pintype "passive")
		)
	)
	(footprint "antmicro-footprints:C_0805_2012Metric"
		(layer "B.Cu")
		(at 212.12 73.51 180)
		(descr "Capacitor SMD 0805")
		(tags "capacitor SMD 0805")
		(property "Reference" "C123"
			(at 2.02 -0.49 0)
			(layer "B.SilkS")
			(effects
				(font
					(size 0.7 0.7)
					(thickness 0.15)
				)
				(justify left bottom mirror)
			)
		)
		(property "Value" "C_22u_25V_0805"
			(at -2.055717 -1.963152 0)
			(layer "B.Fab")
			(effects
				(font
					(size 0.7 0.7)
					(thickness 0.15)
				)
				(justify left bottom mirror)
			)
		)
		(property "Datasheet" "https://product.samsungsem.com/mlcc/CL21A226MAYNNN.do"
			(at 0 0 0)
			(layer "B.Fab")
			(hide yes)
			(effects
				(font
					(size 1.27 1.27)
					(thickness 0.15)
				)
				(justify mirror)
			)
		)
		(property "Description" "SMT Multilayer Ceramic Capacitor, 22uF, +/-20%, 25V, X5R, 0805 [2012 Metric]"
			(at 0 0 0)
			(layer "B.Fab")
			(hide yes)
			(effects
				(font
					(size 1.27 1.27)
					(thickness 0.15)
				)
				(justify mirror)
			)
		)
		(property "Manufacturer" "Samsung Electro-Mechanics"
			(at 0 0 180)
			(unlocked yes)
			(layer "B.Fab")
			(hide yes)
			(effects
				(font
					(size 1 1)
					(thickness 0.15)
				)
				(justify mirror)
			)
		)
		(property "MPN" "CL21A226MAYNNNE"
			(at 0 0 180)
			(unlocked yes)
			(layer "B.Fab")
			(hide yes)
			(effects
				(font
					(size 1 1)
					(thickness 0.15)
				)
				(justify mirror)
			)
		)
		(property "Val" "22u"
			(at 0 0 180)
			(unlocked yes)
			(layer "B.Fab")
			(hide yes)
			(effects
				(font
					(size 1 1)
					(thickness 0.15)
				)
				(justify mirror)
			)
		)
		(property "License" "Apache-2.0"
			(at 0 0 180)
			(unlocked yes)
			(layer "B.Fab")
			(hide yes)
			(effects
				(font
					(size 1 1)
					(thickness 0.15)
				)
				(justify mirror)
			)
		)
		(property "Author" "Antmicro"
			(at 0 0 180)
			(unlocked yes)
			(layer "B.Fab")
			(hide yes)
			(effects
				(font
					(size 1 1)
					(thickness 0.15)
				)
				(justify mirror)
			)
		)
		(property "Voltage" "25V"
			(at 0 0 180)
			(unlocked yes)
			(layer "B.Fab")
			(hide yes)
			(effects
				(font
					(size 1 1)
					(thickness 0.15)
				)
				(justify mirror)
			)
		)
		(property "Dielectric" "X5R"
			(at 0 0 180)
			(unlocked yes)
			(layer "B.Fab")
			(hide yes)
			(effects
				(font
					(size 1 1)
					(thickness 0.15)
				)
				(justify mirror)
			)
		)
		(property "Public" "False"
			(at 0 0 180)
			(unlocked yes)
			(layer "B.Fab")
			(hide yes)
			(effects
				(font
					(size 1 1)
					(thickness 0.15)
				)
				(justify mirror)
			)
		)
		(sheetname "/USB Debug, PD/")
		(sheetfile "usb_debug_pd.kicad_sch")
		(attr smd)
		(fp_line
			(start -0.3 0.7)
			(end 0.3 0.7)
			(stroke
				(width 0.15)
				(type solid)
			)
			(layer "B.SilkS")
		)
		(fp_line
			(start -0.3 -0.7)
			(end 0.3 -0.7)
			(stroke
				(width 0.15)
				(type solid)
			)
			(layer "B.SilkS")
		)
		(fp_rect
			(start 1.95 0.9)
			(end -1.95 -0.9)
			(stroke
				(width 0.05)
				(type default)
			)
			(fill no)
			(layer "B.CrtYd")
		)
		(fp_rect
			(start -0.95 0.675)
			(end 0.95 -0.675)
			(stroke
				(width 0.15)
				(type solid)
			)
			(fill no)
			(layer "B.Fab")
		)
		(fp_text user "${REFERENCE}"
			(at -1.9 -3.947 0)
			(layer "B.Fab")
			(effects
				(font
					(size 0.7 0.7)
					(thickness 0.15)
				)
				(justify left bottom mirror)
			)
		)
		(fp_text user "License: Apache-2.0"
			(at -1.9 -4.947 0)
			(layer "B.Fab")
			(effects
				(font
					(size 0.7 0.7)
					(thickness 0.15)
				)
				(justify left bottom mirror)
			)
		)
		(fp_text user "Author: Antmicro"
			(at -1.9 -5.947 0)
			(layer "B.Fab")
			(effects
				(font
					(size 0.7 0.7)
					(thickness 0.15)
				)
				(justify left bottom mirror)
			)
		)
		(pad "1" smd roundrect
			(at -1.1 0 180)
			(size 1.2 1.3)
			(layers "B.Cu" "B.Mask" "B.Paste")
			(roundrect_rratio 0.25)
			(net 176 "/USB Debug, PD/USBC0_VBUS")
			(pintype "passive")
		)
		(pad "2" smd roundrect
			(at 1.1 0 180)
			(size 1.2 1.3)
			(layers "B.Cu" "B.Mask" "B.Paste")
			(roundrect_rratio 0.25)
			(net 1 "GND")
			(pintype "passive")
		)
	)
	(footprint "antmicro-footprints:C_0402_1005Metric"
		(layer "B.Cu")
		(at 132 146 -90)
		(descr "Capacitor SMD 0402")
		(tags "capacitor SMD 0402")
		(property "Reference" "C205"
			(at -1.710532 -1.32 90)
			(layer "B.SilkS")
			(effects
				(font
					(size 0.7 0.7)
					(thickness 0.15)
				)
				(justify left bottom mirror)
			)
		)
		(property "Value" "C_100n_0402"
			(at -1.022927 -2.155213 90)
			(layer "B.Fab")
			(effects
				(font
					(size 0.7 0.7)
					(thickness 0.15)
				)
				(justify left bottom mirror)
			)
		)
		(property "Datasheet" "https://www.murata.com/products/productdetail?partno=GRM155R61H104KE14%23"
			(at 0 0 90)
			(layer "B.Fab")
			(hide yes)
			(effects
				(font
					(size 1.27 1.27)
					(thickness 0.15)
				)
				(justify mirror)
			)
		)
		(property "Description" "SMD Multilayer Ceramic Capacitor, 0.1 µF, 50 V, 0402 [1005 Metric], ± 10%, X5R, GRM Series"
			(at 0 0 90)
			(layer "B.Fab")
			(hide yes)
			(effects
				(font
					(size 1.27 1.27)
					(thickness 0.15)
				)
				(justify mirror)
			)
		)
		(property "MPN" "GRM155R61H104KE14D"
			(at 0 0 90)
			(unlocked yes)
			(layer "B.Fab")
			(hide yes)
			(effects
				(font
					(size 1 1)
					(thickness 0.15)
				)
				(justify mirror)
			)
		)
		(property "Val" "100n"
			(at 0 0 90)
			(unlocked yes)
			(layer "B.Fab")
			(hide yes)
			(effects
				(font
					(size 1 1)
					(thickness 0.15)
				)
				(justify mirror)
			)
		)
		(property "Voltage" "50V"
			(at 0 0 90)
			(unlocked yes)
			(layer "B.Fab")
			(hide yes)
			(effects
				(font
					(size 1 1)
					(thickness 0.15)
				)
				(justify mirror)
			)
		)
		(property "Dielectric" "X5R"
			(at 0 0 90)
			(unlocked yes)
			(layer "B.Fab")
			(hide yes)
			(effects
				(font
					(size 1 1)
					(thickness 0.15)
				)
				(justify mirror)
			)
		)
		(property "Manufacturer" "Murata"
			(at 0 0 90)
			(unlocked yes)
			(layer "B.Fab")
			(hide yes)
			(effects
				(font
					(size 1 1)
					(thickness 0.15)
				)
				(justify mirror)
			)
		)
		(property "License" "Apache-2.0"
			(at 0 0 90)
			(unlocked yes)
			(layer "B.Fab")
			(hide yes)
			(effects
				(font
					(size 1 1)
					(thickness 0.15)
				)
				(justify mirror)
			)
		)
		(property "Author" "Antmicro"
			(at 0 0 90)
			(unlocked yes)
			(layer "B.Fab")
			(hide yes)
			(effects
				(font
					(size 1 1)
					(thickness 0.15)
				)
				(justify mirror)
			)
		)
		(sheetname "/Peripherals/")
		(sheetfile "peripherals.kicad_sch")
		(attr smd)
		(fp_poly
			(pts
				(xy -0.925 0.47) (xy 0.925 0.47) (xy 0.925 -0.47) (xy -0.925 -0.47)
			)
			(stroke
				(width 0.05)
				(type default)
			)
			(fill no)
			(layer "B.CrtYd")
		)
		(fp_line
			(start -0.494 0.25)
			(end 0.504 0.25)
			(stroke
				(width 0.15)
				(type solid)
			)
			(layer "B.Fab")
		)
		(fp_line
			(start 0.504 0.25)
			(end 0.504 -0.248)
			(stroke
				(width 0.15)
				(type solid)
			)
			(layer "B.Fab")
		)
		(fp_line
			(start -0.494 -0.248)
			(end -0.494 0.25)
			(stroke
				(width 0.15)
				(type solid)
			)
			(layer "B.Fab")
		)
		(fp_line
			(start 0.504 -0.248)
			(end -0.494 -0.248)
			(stroke
				(width 0.15)
				(type solid)
			)
			(layer "B.Fab")
		)
		(fp_text user "${REFERENCE}"
			(at -0.939 -4.599 90)
			(layer "B.Fab")
			(effects
				(font
					(size 0.7 0.7)
					(thickness 0.15)
				)
				(justify left bottom mirror)
			)
		)
		(fp_text user "License: Apache-2.0"
			(at -0.939 -5.799 90)
			(layer "B.Fab")
			(effects
				(font
					(size 0.7 0.7)
					(thickness 0.15)
				)
				(justify left bottom mirror)
			)
		)
		(fp_text user "Author: Antmicro"
			(at -0.939 -3.399 90)
			(layer "B.Fab")
			(effects
				(font
					(size 0.7 0.7)
					(thickness 0.15)
				)
				(justify left bottom mirror)
			)
		)
		(pad "1" smd roundrect
			(at -0.48 0 270)
			(size 0.59 0.64)
			(layers "B.Cu" "B.Mask" "B.Paste")
			(roundrect_rratio 0.25)
			(net 1 "GND")
			(pintype "passive")
		)
		(pad "2" smd roundrect
			(at 0.48 0 270)
			(size 0.59 0.64)
			(layers "B.Cu" "B.Mask" "B.Paste")
			(roundrect_rratio 0.25)
			(net 2 "+3V3")
			(pintype "passive")
		)
	)
	(footprint "antmicro-footprints:R_0402_1005Metric"
		(layer "B.Cu")
		(at 235.8 122 180)
		(descr "Resistor SMD 0402")
		(tags "resistor SMD 0402")
		(property "Reference" "R73"
			(at -3.149999 -0.422 0)
			(layer "B.SilkS")
			(effects
				(font
					(size 0.7 0.7)
					(thickness 0.15)
				)
				(justify left bottom mirror)
			)
		)
		(property "Value" "R_2k2_0402"
			(at -1.011843 -1.772046 0)
			(layer "B.Fab")
			(effects
				(font
					(size 0.7 0.7)
					(thickness 0.15)
				)
				(justify left bottom mirror)
			)
		)
		(property "Datasheet" "https://www.bourns.com/docs/product-datasheets/cr.pdf"
			(at 0 0 0)
			(layer "B.Fab")
			(hide yes)
			(effects
				(font
					(size 1.27 1.27)
					(thickness 0.15)
				)
				(justify mirror)
			)
		)
		(property "Description" "SMD Chip Resistor, 2.2 kohm, ± 1%, 62.5 mW, 0402 [1005 Metric], Thick Film, General Purpose"
			(at 0 0 0)
			(layer "B.Fab")
			(hide yes)
			(effects
				(font
					(size 1.27 1.27)
					(thickness 0.15)
				)
				(justify mirror)
			)
		)
		(property "Manufacturer" "Bourns"
			(at 0 0 0)
			(unlocked yes)
			(layer "B.Fab")
			(hide yes)
			(effects
				(font
					(size 1 1)
					(thickness 0.15)
				)
				(justify mirror)
			)
		)
		(property "MPN" "CR0402-FX-2201GLF"
			(at 0 0 0)
			(unlocked yes)
			(layer "B.Fab")
			(hide yes)
			(effects
				(font
					(size 1 1)
					(thickness 0.15)
				)
				(justify mirror)
			)
		)
		(property "Val" "2k2"
			(at 0 0 0)
			(unlocked yes)
			(layer "B.Fab")
			(hide yes)
			(effects
				(font
					(size 1 1)
					(thickness 0.15)
				)
				(justify mirror)
			)
		)
		(property "License" "Apache-2.0"
			(at 0 0 0)
			(unlocked yes)
			(layer "B.Fab")
			(hide yes)
			(effects
				(font
					(size 1 1)
					(thickness 0.15)
				)
				(justify mirror)
			)
		)
		(property "Author" "Antmicro"
			(at 0 0 0)
			(unlocked yes)
			(layer "B.Fab")
			(hide yes)
			(effects
				(font
					(size 1 1)
					(thickness 0.15)
				)
				(justify mirror)
			)
		)
		(property "Tolerance" "1%"
			(at 0 0 0)
			(unlocked yes)
			(layer "B.Fab")
			(hide yes)
			(effects
				(font
					(size 1 1)
					(thickness 0.15)
				)
				(justify mirror)
			)
		)
		(sheetname "/USB Hub/")
		(sheetfile "usb_hub.kicad_sch")
		(attr smd)
		(fp_poly
			(pts
				(xy -0.925 0.47) (xy -0.925 -0.47) (xy 0.925 -0.47) (xy 0.925 0.47)
			)
			(stroke
				(width 0.05)
				(type default)
			)
			(fill no)
			(layer "B.CrtYd")
		)
		(fp_poly
			(pts
				(xy -0.5 0.25) (xy -0.5 -0.25) (xy 0.5 -0.25) (xy 0.5 0.25)
			)
			(stroke
				(width 0.15)
				(type solid)
			)
			(fill no)
			(layer "B.Fab")
		)
		(fp_text user "Author: Antmicro"
			(at -0.95 -4.169 0)
			(layer "B.Fab")
			(effects
				(font
					(size 0.7 0.7)
					(thickness 0.15)
				)
				(justify left bottom mirror)
			)
		)
		(fp_text user "${REFERENCE}"
			(at -0.95 -3.168 0)
			(layer "B.Fab")
			(effects
				(font
					(size 0.7 0.7)
					(thickness 0.15)
				)
				(justify left bottom mirror)
			)
		)
		(fp_text user "License: Apache-2.0"
			(at -0.949999 -5.169 0)
			(layer "B.Fab")
			(effects
				(font
					(size 0.7 0.7)
					(thickness 0.15)
				)
				(justify left bottom mirror)
			)
		)
		(pad "1" smd roundrect
			(at -0.48 0 180)
			(size 0.59 0.64)
			(layers "B.Cu" "B.Mask" "B.Paste")
			(roundrect_rratio 0.25)
			(net 1 "GND")
			(pintype "passive")
		)
		(pad "2" smd roundrect
			(at 0.48 0 180)
			(size 0.59 0.64)
			(layers "B.Cu" "B.Mask" "B.Paste")
			(roundrect_rratio 0.25)
			(net 909 "/USB Hub/USBC3_ISET")
			(pintype "passive")
		)
	)
	(footprint "antmicro-footprints:C_0402_1005Metric"
		(layer "B.Cu")
		(at 235.8 123)
		(descr "Capacitor SMD 0402")
		(tags "capacitor SMD 0402")
		(property "Reference" "C77"
			(at 1.08 -0.308 0)
			(layer "B.SilkS")
			(effects
				(font
					(size 0.7 0.7)
					(thickness 0.15)
				)
				(justify right top mirror)
			)
		)
		(property "Value" "C_100n_0402"
			(at -1.022927 -2.155213 0)
			(layer "B.Fab")
			(effects
				(font
					(size 0.7 0.7)
					(thickness 0.15)
				)
				(justify right top mirror)
			)
		)
		(property "Datasheet" "https://www.murata.com/products/productdetail?partno=GRM155R61H104KE14%23"
			(at 0 0 0)
			(layer "B.Fab")
			(hide yes)
			(effects
				(font
					(size 1.27 1.27)
					(thickness 0.15)
				)
				(justify mirror)
			)
		)
		(property "Description" "SMD Multilayer Ceramic Capacitor, 0.1 µF, 50 V, 0402 [1005 Metric], ± 10%, X5R, GRM Series"
			(at 0 0 0)
			(layer "B.Fab")
			(hide yes)
			(effects
				(font
					(size 1.27 1.27)
					(thickness 0.15)
				)
				(justify mirror)
			)
		)
		(property "Manufacturer" "Murata"
			(at 0 0 180)
			(unlocked yes)
			(layer "B.Fab")
			(hide yes)
			(effects
				(font
					(size 1 1)
					(thickness 0.15)
				)
				(justify mirror)
			)
		)
		(property "MPN" "GRM155R61H104KE14D"
			(at 0 0 180)
			(unlocked yes)
			(layer "B.Fab")
			(hide yes)
			(effects
				(font
					(size 1 1)
					(thickness 0.15)
				)
				(justify mirror)
			)
		)
		(property "Val" "100n"
			(at 0 0 180)
			(unlocked yes)
			(layer "B.Fab")
			(hide yes)
			(effects
				(font
					(size 1 1)
					(thickness 0.15)
				)
				(justify mirror)
			)
		)
		(property "License" "Apache-2.0"
			(at 0 0 180)
			(unlocked yes)
			(layer "B.Fab")
			(hide yes)
			(effects
				(font
					(size 1 1)
					(thickness 0.15)
				)
				(justify mirror)
			)
		)
		(property "Author" "Antmicro"
			(at 0 0 180)
			(unlocked yes)
			(layer "B.Fab")
			(hide yes)
			(effects
				(font
					(size 1 1)
					(thickness 0.15)
				)
				(justify mirror)
			)
		)
		(property "Voltage" "50V"
			(at 0 0 180)
			(unlocked yes)
			(layer "B.Fab")
			(hide yes)
			(effects
				(font
					(size 1 1)
					(thickness 0.15)
				)
				(justify mirror)
			)
		)
		(property "Dielectric" "X5R"
			(at 0 0 180)
			(unlocked yes)
			(layer "B.Fab")
			(hide yes)
			(effects
				(font
					(size 1 1)
					(thickness 0.15)
				)
				(justify mirror)
			)
		)
		(sheetname "/USB Hub/")
		(sheetfile "usb_hub.kicad_sch")
		(attr smd)
		(fp_poly
			(pts
				(xy -0.925 0.47) (xy -0.925 -0.47) (xy 0.925 -0.47) (xy 0.925 0.47)
			)
			(stroke
				(width 0.05)
				(type default)
			)
			(fill no)
			(layer "B.CrtYd")
		)
		(fp_line
			(start -0.494 -0.248)
			(end -0.494 0.25)
			(stroke
				(width 0.15)
				(type solid)
			)
			(layer "B.Fab")
		)
		(fp_line
			(start -0.494 0.25)
			(end 0.504 0.25)
			(stroke
				(width 0.15)
				(type solid)
			)
			(layer "B.Fab")
		)
		(fp_line
			(start 0.504 -0.248)
			(end -0.494 -0.248)
			(stroke
				(width 0.15)
				(type solid)
			)
			(layer "B.Fab")
		)
		(fp_line
			(start 0.504 0.25)
			(end 0.504 -0.248)
			(stroke
				(width 0.15)
				(type solid)
			)
			(layer "B.Fab")
		)
		(fp_text user "${REFERENCE}"
			(at -0.939 -4.599 0)
			(layer "B.Fab")
			(effects
				(font
					(size 0.7 0.7)
					(thickness 0.15)
				)
				(justify right top mirror)
			)
		)
		(fp_text user "License: Apache-2.0"
			(at -0.939 -5.799 0)
			(layer "B.Fab")
			(effects
				(font
					(size 0.7 0.7)
					(thickness 0.15)
				)
				(justify right top mirror)
			)
		)
		(fp_text user "Author: Antmicro"
			(at -0.939 -3.399 0)
			(layer "B.Fab")
			(effects
				(font
					(size 0.7 0.7)
					(thickness 0.15)
				)
				(justify right top mirror)
			)
		)
		(pad "1" smd roundrect
			(at -0.48 0)
			(size 0.59 0.64)
			(layers "B.Cu" "B.Mask" "B.Paste")
			(roundrect_rratio 0.25)
			(net 5 "+5V")
			(pintype "passive")
		)
		(pad "2" smd roundrect
			(at 0.48 0)
			(size 0.59 0.64)
			(layers "B.Cu" "B.Mask" "B.Paste")
			(roundrect_rratio 0.25)
			(net 1 "GND")
			(pintype "passive")
		)
	)
	(footprint "antmicro-footprints:R_0402_1005Metric"
		(layer "B.Cu")
		(at 212.8 86.66)
		(descr "Resistor SMD 0402")
		(tags "resistor SMD 0402")
		(property "Reference" "R130"
			(at -3.9 -0.3 0)
			(layer "B.SilkS")
			(effects
				(font
					(size 0.7 0.7)
					(thickness 0.15)
				)
				(justify right top mirror)
			)
		)
		(property "Value" "R_1k_0402"
			(at -1.011843 -1.772046 0)
			(layer "B.Fab")
			(effects
				(font
					(size 0.7 0.7)
					(thickness 0.15)
				)
				(justify right top mirror)
			)
		)
		(property "Datasheet" "https://www.bourns.com/docs/product-datasheets/cr.pdf"
			(at 0 0 0)
			(layer "B.Fab")
			(hide yes)
			(effects
				(font
					(size 1.27 1.27)
					(thickness 0.15)
				)
				(justify mirror)
			)
		)
		(property "Description" "SMD Chip Resistor, 1 kohm, ± 1%, 63 mW, 0402 [1005 Metric], Thick Film, General Purpose"
			(at 0 0 0)
			(layer "B.Fab")
			(hide yes)
			(effects
				(font
					(size 1.27 1.27)
					(thickness 0.15)
				)
				(justify mirror)
			)
		)
		(property "Manufacturer" "Bourns"
			(at 0 0 180)
			(unlocked yes)
			(layer "B.Fab")
			(hide yes)
			(effects
				(font
					(size 1 1)
					(thickness 0.15)
				)
				(justify mirror)
			)
		)
		(property "MPN" "CR0402-FX-1001GLF"
			(at 0 0 180)
			(unlocked yes)
			(layer "B.Fab")
			(hide yes)
			(effects
				(font
					(size 1 1)
					(thickness 0.15)
				)
				(justify mirror)
			)
		)
		(property "Val" "1k"
			(at 0 0 180)
			(unlocked yes)
			(layer "B.Fab")
			(hide yes)
			(effects
				(font
					(size 1 1)
					(thickness 0.15)
				)
				(justify mirror)
			)
		)
		(property "License" "Apache-2.0"
			(at 0 0 180)
			(unlocked yes)
			(layer "B.Fab")
			(hide yes)
			(effects
				(font
					(size 1 1)
					(thickness 0.15)
				)
				(justify mirror)
			)
		)
		(property "Author" "Antmicro"
			(at 0 0 180)
			(unlocked yes)
			(layer "B.Fab")
			(hide yes)
			(effects
				(font
					(size 1 1)
					(thickness 0.15)
				)
				(justify mirror)
			)
		)
		(property "Tolerance" "1%"
			(at 0 0 180)
			(unlocked yes)
			(layer "B.Fab")
			(hide yes)
			(effects
				(font
					(size 1 1)
					(thickness 0.15)
				)
				(justify mirror)
			)
		)
		(sheetname "/USB DP Alt mode/")
		(sheetfile "usb_dp.kicad_sch")
		(attr smd exclude_from_pos_files exclude_from_bom dnp)
		(fp_poly
			(pts
				(xy -0.925 0.47) (xy 0.925 0.47) (xy 0.925 -0.47) (xy -0.925 -0.47)
			)
			(stroke
				(width 0.05)
				(type default)
			)
			(fill no)
			(layer "B.CrtYd")
		)
		(fp_poly
			(pts
				(xy -0.5 0.25) (xy 0.5 0.25) (xy 0.5 -0.25) (xy -0.5 -0.25)
			)
			(stroke
				(width 0.15)
				(type solid)
			)
			(fill no)
			(layer "B.Fab")
		)
		(fp_text user "Author: Antmicro"
			(at -0.95 -4.169 0)
			(layer "B.Fab")
			(effects
				(font
					(size 0.7 0.7)
					(thickness 0.15)
				)
				(justify right top mirror)
			)
		)
		(fp_text user "License: Apache-2.0"
			(at -0.949999 -5.169 0)
			(layer "B.Fab")
			(effects
				(font
					(size 0.7 0.7)
					(thickness 0.15)
				)
				(justify right top mirror)
			)
		)
		(fp_text user "${REFERENCE}"
			(at -0.95 -3.168 0)
			(layer "B.Fab")
			(effects
				(font
					(size 0.7 0.7)
					(thickness 0.15)
				)
				(justify right top mirror)
			)
		)
		(pad "1" smd roundrect
			(at -0.48 0)
			(size 0.59 0.64)
			(layers "B.Cu" "B.Mask" "B.Paste")
			(roundrect_rratio 0.25)
			(net 964 "/USB DP Alt mode/USBC1_SSEQ0")
			(pintype "passive")
		)
		(pad "2" smd roundrect
			(at 0.48 0)
			(size 0.59 0.64)
			(layers "B.Cu" "B.Mask" "B.Paste")
			(roundrect_rratio 0.25)
			(net 2 "+3V3")
			(pintype "passive")
		)
	)
	(footprint "antmicro-footprints:C_0402_1005Metric"
		(layer "B.Cu")
		(at 211 60)
		(descr "Capacitor SMD 0402")
		(tags "capacitor SMD 0402")
		(property "Reference" "C160"
			(at -3.82 -0.57 0)
			(layer "B.SilkS")
			(effects
				(font
					(size 0.7 0.7)
					(thickness 0.15)
				)
				(justify right top mirror)
			)
		)
		(property "Value" "C_1u_0402"
			(at -1.022927 -2.155213 0)
			(layer "B.Fab")
			(effects
				(font
					(size 0.7 0.7)
					(thickness 0.15)
				)
				(justify right top mirror)
			)
		)
		(property "Datasheet" "https://product.tdk.com/en/search/capacitor/ceramic/mlcc/info?part_no=C1005X6S1A105K050BC"
			(at 0 0 0)
			(layer "B.Fab")
			(hide yes)
			(effects
				(font
					(size 1.27 1.27)
					(thickness 0.15)
				)
				(justify mirror)
			)
		)
		(property "Description" "SMD Multilayer Ceramic Capacitor, 1 µF, 10 V, 0402 [1005 Metric], ± 10%, X6S, C"
			(at 0 0 0)
			(layer "B.Fab")
			(hide yes)
			(effects
				(font
					(size 1.27 1.27)
					(thickness 0.15)
				)
				(justify mirror)
			)
		)
		(property "Manufacturer" "TDK"
			(at 0 0 180)
			(unlocked yes)
			(layer "B.Fab")
			(hide yes)
			(effects
				(font
					(size 1 1)
					(thickness 0.15)
				)
				(justify mirror)
			)
		)
		(property "MPN" "C1005X6S1A105K050BC"
			(at 0 0 180)
			(unlocked yes)
			(layer "B.Fab")
			(hide yes)
			(effects
				(font
					(size 1 1)
					(thickness 0.15)
				)
				(justify mirror)
			)
		)
		(property "Val" "1u"
			(at 0 0 180)
			(unlocked yes)
			(layer "B.Fab")
			(hide yes)
			(effects
				(font
					(size 1 1)
					(thickness 0.15)
				)
				(justify mirror)
			)
		)
		(property "License" "Apache-2.0"
			(at 0 0 180)
			(unlocked yes)
			(layer "B.Fab")
			(hide yes)
			(effects
				(font
					(size 1 1)
					(thickness 0.15)
				)
				(justify mirror)
			)
		)
		(property "Author" "Antmicro"
			(at 0 0 180)
			(unlocked yes)
			(layer "B.Fab")
			(hide yes)
			(effects
				(font
					(size 1 1)
					(thickness 0.15)
				)
				(justify mirror)
			)
		)
		(property "Voltage" ""
			(at 0 0 180)
			(unlocked yes)
			(layer "B.Fab")
			(hide yes)
			(effects
				(font
					(size 1 1)
					(thickness 0.15)
				)
				(justify mirror)
			)
		)
		(property "Dielectric" ""
			(at 0 0 180)
			(unlocked yes)
			(layer "B.Fab")
			(hide yes)
			(effects
				(font
					(size 1 1)
					(thickness 0.15)
				)
				(justify mirror)
			)
		)
		(sheetname "/CSI/")
		(sheetfile "csi.kicad_sch")
		(attr smd)
		(fp_rect
			(start -0.925 0.47)
			(end 0.925 -0.47)
			(stroke
				(width 0.05)
				(type default)
			)
			(fill no)
			(layer "B.CrtYd")
		)
		(fp_line
			(start -0.494 -0.248)
			(end -0.494 0.25)
			(stroke
				(width 0.15)
				(type solid)
			)
			(layer "B.Fab")
		)
		(fp_line
			(start -0.494 0.25)
			(end 0.504 0.25)
			(stroke
				(width 0.15)
				(type solid)
			)
			(layer "B.Fab")
		)
		(fp_line
			(start 0.504 -0.248)
			(end -0.494 -0.248)
			(stroke
				(width 0.15)
				(type solid)
			)
			(layer "B.Fab")
		)
		(fp_line
			(start 0.504 0.25)
			(end 0.504 -0.248)
			(stroke
				(width 0.15)
				(type solid)
			)
			(layer "B.Fab")
		)
		(fp_text user "${REFERENCE}"
			(at -0.939 -4.599 0)
			(layer "B.Fab")
			(effects
				(font
					(size 0.7 0.7)
					(thickness 0.15)
				)
				(justify right top mirror)
			)
		)
		(fp_text user "Author: Antmicro"
			(at -0.939 -3.399 0)
			(layer "B.Fab")
			(effects
				(font
					(size 0.7 0.7)
					(thickness 0.15)
				)
				(justify right top mirror)
			)
		)
		(fp_text user "License: Apache-2.0"
			(at -0.939 -5.799 0)
			(layer "B.Fab")
			(effects
				(font
					(size 0.7 0.7)
					(thickness 0.15)
				)
				(justify right top mirror)
			)
		)
		(pad "1" smd roundrect
			(at -0.48 0)
			(size 0.59 0.64)
			(layers "B.Cu" "B.Mask" "B.Paste")
			(roundrect_rratio 0.25)
			(net 1 "GND")
			(pintype "passive")
		)
		(pad "2" smd roundrect
			(at 0.48 0)
			(size 0.59 0.64)
			(layers "B.Cu" "B.Mask" "B.Paste")
			(roundrect_rratio 0.25)
			(net 8 "/CSI/CSIB_3V3")
			(pintype "passive")
		)
	)
	(footprint "antmicro-footprints:C_0402_1005Metric"
		(layer "B.Cu")
		(at 94 121.775 180)
		(descr "Capacitor SMD 0402")
		(tags "capacitor SMD 0402")
		(property "Reference" "C212"
			(at -3.8 -0.625 0)
			(layer "B.SilkS")
			(effects
				(font
					(size 0.7 0.7)
					(thickness 0.15)
				)
				(justify left bottom mirror)
			)
		)
		(property "Value" "C_220n_0402"
			(at -1.022927 -2.155213 0)
			(layer "B.Fab")
			(effects
				(font
					(size 0.7 0.7)
					(thickness 0.15)
				)
				(justify left bottom mirror)
			)
		)
		(property "Datasheet" "https://www.yageo.com/en/Chart/Download/pdf/CC0402KRX5R6BB224"
			(at 0 0 0)
			(layer "B.Fab")
			(hide yes)
			(effects
				(font
					(size 1.27 1.27)
					(thickness 0.15)
				)
				(justify mirror)
			)
		)
		(property "Description" "SMD Multilayer Ceramic Capacitor, 0.22 µF, 10 V, 0402 [1005 Metric], ± 10%, X5R, CC Series"
			(at 0 0 0)
			(layer "B.Fab")
			(hide yes)
			(effects
				(font
					(size 1.27 1.27)
					(thickness 0.15)
				)
				(justify mirror)
			)
		)
		(property "MPN" "CC0402KRX5R6BB224"
			(at 0 0 180)
			(unlocked yes)
			(layer "B.Fab")
			(hide yes)
			(effects
				(font
					(size 1 1)
					(thickness 0.15)
				)
				(justify mirror)
			)
		)
		(property "Val" "220n"
			(at 0 0 180)
			(unlocked yes)
			(layer "B.Fab")
			(hide yes)
			(effects
				(font
					(size 1 1)
					(thickness 0.15)
				)
				(justify mirror)
			)
		)
		(property "Voltage" "25V"
			(at 0 0 180)
			(unlocked yes)
			(layer "B.Fab")
			(hide yes)
			(effects
				(font
					(size 1 1)
					(thickness 0.15)
				)
				(justify mirror)
			)
		)
		(property "Dielectric" "X7R"
			(at 0 0 180)
			(unlocked yes)
			(layer "B.Fab")
			(hide yes)
			(effects
				(font
					(size 1 1)
					(thickness 0.15)
				)
				(justify mirror)
			)
		)
		(property "Manufacturer" "YAGEO"
			(at 0 0 180)
			(unlocked yes)
			(layer "B.Fab")
			(hide yes)
			(effects
				(font
					(size 1 1)
					(thickness 0.15)
				)
				(justify mirror)
			)
		)
		(property "License" "Apache-2.0"
			(at 0 0 180)
			(unlocked yes)
			(layer "B.Fab")
			(hide yes)
			(effects
				(font
					(size 1 1)
					(thickness 0.15)
				)
				(justify mirror)
			)
		)
		(property "Author" "Antmicro"
			(at 0 0 180)
			(unlocked yes)
			(layer "B.Fab")
			(hide yes)
			(effects
				(font
					(size 1 1)
					(thickness 0.15)
				)
				(justify mirror)
			)
		)
		(property "Public" "False"
			(at 0 0 180)
			(unlocked yes)
			(layer "B.Fab")
			(hide yes)
			(effects
				(font
					(size 1 1)
					(thickness 0.15)
				)
				(justify mirror)
			)
		)
		(sheetname "/Expansion connector/")
		(sheetfile "expansion_connector.kicad_sch")
		(attr smd)
		(fp_poly
			(pts
				(xy -0.925 0.47) (xy 0.925 0.47) (xy 0.925 -0.47) (xy -0.925 -0.47)
			)
			(stroke
				(width 0.05)
				(type default)
			)
			(fill no)
			(layer "B.CrtYd")
		)
		(fp_line
			(start 0.504 0.25)
			(end 0.504 -0.248)
			(stroke
				(width 0.15)
				(type solid)
			)
			(layer "B.Fab")
		)
		(fp_line
			(start 0.504 -0.248)
			(end -0.494 -0.248)
			(stroke
				(width 0.15)
				(type solid)
			)
			(layer "B.Fab")
		)
		(fp_line
			(start -0.494 0.25)
			(end 0.504 0.25)
			(stroke
				(width 0.15)
				(type solid)
			)
			(layer "B.Fab")
		)
		(fp_line
			(start -0.494 -0.248)
			(end -0.494 0.25)
			(stroke
				(width 0.15)
				(type solid)
			)
			(layer "B.Fab")
		)
		(fp_text user "${REFERENCE}"
			(at -0.939 -4.599 0)
			(layer "B.Fab")
			(effects
				(font
					(size 0.7 0.7)
					(thickness 0.15)
				)
				(justify left bottom mirror)
			)
		)
		(fp_text user "License: Apache-2.0"
			(at -0.939 -5.799 0)
			(layer "B.Fab")
			(effects
				(font
					(size 0.7 0.7)
					(thickness 0.15)
				)
				(justify left bottom mirror)
			)
		)
		(fp_text user "Author: Antmicro"
			(at -0.939 -3.399 0)
			(layer "B.Fab")
			(effects
				(font
					(size 0.7 0.7)
					(thickness 0.15)
				)
				(justify left bottom mirror)
			)
		)
		(pad "1" smd roundrect
			(at -0.48 0 180)
			(size 0.59 0.64)
			(layers "B.Cu" "B.Mask" "B.Paste")
			(roundrect_rratio 0.25)
			(net 519 "/Expansion connector/PCIe_{C3x2}.TX1-")
			(pintype "passive")
		)
		(pad "2" smd roundrect
			(at 0.48 0 180)
			(size 0.59 0.64)
			(layers "B.Cu" "B.Mask" "B.Paste")
			(roundrect_rratio 0.25)
			(net 475 "/Expansion connector/PET1_C3_P")
			(pintype "passive")
		)
	)
	(footprint "antmicro-footprints:C_0402_1005Metric"
		(layer "B.Cu")
		(at 160.3 69.79 180)
		(descr "Capacitor SMD 0402")
		(tags "capacitor SMD 0402")
		(property "Reference" "C238"
			(at -1.26 -1.44 0)
			(layer "B.SilkS")
			(effects
				(font
					(size 0.7 0.7)
					(thickness 0.15)
				)
				(justify left bottom mirror)
			)
		)
		(property "Value" "C_100n_0402"
			(at -1.022927 -2.155213 0)
			(layer "B.Fab")
			(effects
				(font
					(size 0.7 0.7)
					(thickness 0.15)
				)
				(justify left bottom mirror)
			)
		)
		(property "Datasheet" "https://www.murata.com/products/productdetail?partno=GRM155R61H104KE14%23"
			(at 0 0 0)
			(layer "B.Fab")
			(hide yes)
			(effects
				(font
					(size 1.27 1.27)
					(thickness 0.15)
				)
				(justify mirror)
			)
		)
		(property "Description" "SMD Multilayer Ceramic Capacitor, 0.1 µF, 50 V, 0402 [1005 Metric], ± 10%, X5R, GRM Series"
			(at 0 0 0)
			(layer "B.Fab")
			(hide yes)
			(effects
				(font
					(size 1.27 1.27)
					(thickness 0.15)
				)
				(justify mirror)
			)
		)
		(property "MPN" "GRM155R61H104KE14D"
			(at 0 0 0)
			(unlocked yes)
			(layer "B.Fab")
			(hide yes)
			(effects
				(font
					(size 1 1)
					(thickness 0.15)
				)
				(justify mirror)
			)
		)
		(property "Val" "100n"
			(at 0 0 0)
			(unlocked yes)
			(layer "B.Fab")
			(hide yes)
			(effects
				(font
					(size 1 1)
					(thickness 0.15)
				)
				(justify mirror)
			)
		)
		(property "Voltage" "50V"
			(at 0 0 0)
			(unlocked yes)
			(layer "B.Fab")
			(hide yes)
			(effects
				(font
					(size 1 1)
					(thickness 0.15)
				)
				(justify mirror)
			)
		)
		(property "Dielectric" "X5R"
			(at 0 0 0)
			(unlocked yes)
			(layer "B.Fab")
			(hide yes)
			(effects
				(font
					(size 1 1)
					(thickness 0.15)
				)
				(justify mirror)
			)
		)
		(property "Manufacturer" "Murata"
			(at 0 0 0)
			(unlocked yes)
			(layer "B.Fab")
			(hide yes)
			(effects
				(font
					(size 1 1)
					(thickness 0.15)
				)
				(justify mirror)
			)
		)
		(property "License" "Apache-2.0"
			(at 0 0 0)
			(unlocked yes)
			(layer "B.Fab")
			(hide yes)
			(effects
				(font
					(size 1 1)
					(thickness 0.15)
				)
				(justify mirror)
			)
		)
		(property "Author" "Antmicro"
			(at 0 0 0)
			(unlocked yes)
			(layer "B.Fab")
			(hide yes)
			(effects
				(font
					(size 1 1)
					(thickness 0.15)
				)
				(justify mirror)
			)
		)
		(sheetname "/SoM_IO2/")
		(sheetfile "som_io2.kicad_sch")
		(attr smd exclude_from_pos_files exclude_from_bom dnp)
		(fp_rect
			(start -0.925 0.47)
			(end 0.925 -0.47)
			(stroke
				(width 0.05)
				(type default)
			)
			(fill no)
			(layer "B.CrtYd")
		)
		(fp_line
			(start 0.504 0.25)
			(end 0.504 -0.248)
			(stroke
				(width 0.15)
				(type solid)
			)
			(layer "B.Fab")
		)
		(fp_line
			(start 0.504 -0.248)
			(end -0.494 -0.248)
			(stroke
				(width 0.15)
				(type solid)
			)
			(layer "B.Fab")
		)
		(fp_line
			(start -0.494 0.25)
			(end 0.504 0.25)
			(stroke
				(width 0.15)
				(type solid)
			)
			(layer "B.Fab")
		)
		(fp_line
			(start -0.494 -0.248)
			(end -0.494 0.25)
			(stroke
				(width 0.15)
				(type solid)
			)
			(layer "B.Fab")
		)
		(fp_text user "License: Apache-2.0"
			(at -0.939 -5.799 0)
			(layer "B.Fab")
			(effects
				(font
					(size 0.7 0.7)
					(thickness 0.15)
				)
				(justify left bottom mirror)
			)
		)
		(fp_text user "${REFERENCE}"
			(at -0.939 -4.599 0)
			(layer "B.Fab")
			(effects
				(font
					(size 0.7 0.7)
					(thickness 0.15)
				)
				(justify left bottom mirror)
			)
		)
		(fp_text user "Author: Antmicro"
			(at -0.939 -3.399 0)
			(layer "B.Fab")
			(effects
				(font
					(size 0.7 0.7)
					(thickness 0.15)
				)
				(justify left bottom mirror)
			)
		)
		(pad "1" smd roundrect
			(at -0.48 0 180)
			(size 0.59 0.64)
			(layers "B.Cu" "B.Mask" "B.Paste")
			(roundrect_rratio 0.25)
			(net 1 "GND")
			(pintype "passive")
		)
		(pad "2" smd roundrect
			(at 0.48 0 180)
			(size 0.59 0.64)
			(layers "B.Cu" "B.Mask" "B.Paste")
			(roundrect_rratio 0.25)
			(net 11 "+1V8")
			(pintype "passive")
		)
	)
	(footprint "antmicro-footprints:R_0402_1005Metric"
		(layer "B.Cu")
		(at 124.6 109.8 180)
		(descr "Resistor SMD 0402")
		(tags "resistor SMD 0402")
		(property "Reference" "R208"
			(at -3.9 -0.36 0)
			(layer "B.SilkS")
			(effects
				(font
					(size 0.7 0.7)
					(thickness 0.15)
				)
				(justify left bottom mirror)
			)
		)
		(property "Value" "R_0R_0402"
			(at -1.011843 -1.772046 0)
			(layer "B.Fab")
			(effects
				(font
					(size 0.7 0.7)
					(thickness 0.15)
				)
				(justify left bottom mirror)
			)
		)
		(property "Datasheet" "https://industrial.panasonic.com/cdbs/www-data/pdf/RDA0000/AOA0000C301.pdf"
			(at 0 0 0)
			(layer "B.Fab")
			(hide yes)
			(effects
				(font
					(size 1.27 1.27)
					(thickness 0.15)
				)
				(justify mirror)
			)
		)
		(property "Description" "SMD Chip Resistor, Jumper, 0 ohm, 100 mW, 0402 [1005 Metric], Thick Film, General Purpose"
			(at 0 0 0)
			(layer "B.Fab")
			(hide yes)
			(effects
				(font
					(size 1.27 1.27)
					(thickness 0.15)
				)
				(justify mirror)
			)
		)
		(property "MPN" "ERJ2GE0R00X"
			(at 0 0 0)
			(unlocked yes)
			(layer "B.Fab")
			(hide yes)
			(effects
				(font
					(size 1 1)
					(thickness 0.15)
				)
				(justify mirror)
			)
		)
		(property "Manufacturer" "Panasonic"
			(at 0 0 0)
			(unlocked yes)
			(layer "B.Fab")
			(hide yes)
			(effects
				(font
					(size 1 1)
					(thickness 0.15)
				)
				(justify mirror)
			)
		)
		(property "License" "Apache-2.0"
			(at 0 0 0)
			(unlocked yes)
			(layer "B.Fab")
			(hide yes)
			(effects
				(font
					(size 1 1)
					(thickness 0.15)
				)
				(justify mirror)
			)
		)
		(property "Author" "Antmicro"
			(at 0 0 0)
			(unlocked yes)
			(layer "B.Fab")
			(hide yes)
			(effects
				(font
					(size 1 1)
					(thickness 0.15)
				)
				(justify mirror)
			)
		)
		(property "Val" "0R"
			(at 0 0 0)
			(unlocked yes)
			(layer "B.Fab")
			(hide yes)
			(effects
				(font
					(size 1 1)
					(thickness 0.15)
				)
				(justify mirror)
			)
		)
		(property "Tolerance" "~"
			(at 0 0 0)
			(unlocked yes)
			(layer "B.Fab")
			(hide yes)
			(effects
				(font
					(size 1 1)
					(thickness 0.15)
				)
				(justify mirror)
			)
		)
		(property "Current" "1A"
			(at 0 0 0)
			(unlocked yes)
			(layer "B.Fab")
			(hide yes)
			(effects
				(font
					(size 1 1)
					(thickness 0.15)
				)
				(justify mirror)
			)
		)
		(sheetname "/M.2/")
		(sheetfile "m2.kicad_sch")
		(attr smd)
		(fp_poly
			(pts
				(xy -0.925 0.47) (xy 0.925 0.47) (xy 0.925 -0.47) (xy -0.925 -0.47)
			)
			(stroke
				(width 0.05)
				(type default)
			)
			(fill no)
			(layer "B.CrtYd")
		)
		(fp_poly
			(pts
				(xy -0.5 0.25) (xy 0.5 0.25) (xy 0.5 -0.25) (xy -0.5 -0.25)
			)
			(stroke
				(width 0.15)
				(type solid)
			)
			(fill no)
			(layer "B.Fab")
		)
		(fp_text user "Author: Antmicro"
			(at -0.95 -4.169 0)
			(layer "B.Fab")
			(effects
				(font
					(size 0.7 0.7)
					(thickness 0.15)
				)
				(justify left bottom mirror)
			)
		)
		(fp_text user "${REFERENCE}"
			(at -0.95 -3.168 0)
			(layer "B.Fab")
			(effects
				(font
					(size 0.7 0.7)
					(thickness 0.15)
				)
				(justify left bottom mirror)
			)
		)
		(fp_text user "License: Apache-2.0"
			(at -0.949999 -5.169 0)
			(layer "B.Fab")
			(effects
				(font
					(size 0.7 0.7)
					(thickness 0.15)
				)
				(justify left bottom mirror)
			)
		)
		(pad "1" smd roundrect
			(at -0.48 0 180)
			(size 0.59 0.64)
			(layers "B.Cu" "B.Mask" "B.Paste")
			(roundrect_rratio 0.25)
			(net 104 "/M.2/~{PEWAKE}")
			(pintype "passive")
		)
		(pad "2" smd roundrect
			(at 0.48 0 180)
			(size 0.59 0.64)
			(layers "B.Cu" "B.Mask" "B.Paste")
			(roundrect_rratio 0.25)
			(net 826 "/M.2/~{PEWAKE_M}")
			(pintype "passive")
		)
	)
	(footprint "antmicro-footprints:TP_SMD_0.75mm"
		(layer "B.Cu")
		(at 185.48 76.67 180)
		(property "Reference" "TP124"
			(at -3.850001 -0.38 0)
			(layer "B.SilkS")
			(effects
				(font
					(size 0.7 0.7)
					(thickness 0.15)
				)
				(justify left bottom mirror)
			)
		)
		(property "Value" "TP_0.75mm_SMD"
			(at 0 -1.2 0)
			(layer "B.Fab")
			(effects
				(font
					(size 0.7 0.7)
					(thickness 0.15)
				)
				(justify left bottom mirror)
			)
		)
		(property "Description" "SMT test point"
			(at 0 0 0)
			(layer "B.Fab")
			(hide yes)
			(effects
				(font
					(size 1.27 1.27)
					(thickness 0.15)
				)
				(justify mirror)
			)
		)
		(property "MPN" ""
			(at 0 0 0)
			(unlocked yes)
			(layer "B.Fab")
			(hide yes)
			(effects
				(font
					(size 1 1)
					(thickness 0.15)
				)
				(justify mirror)
			)
		)
		(property "Manufacturer" ""
			(at 0 0 0)
			(unlocked yes)
			(layer "B.Fab")
			(hide yes)
			(effects
				(font
					(size 1 1)
					(thickness 0.15)
				)
				(justify mirror)
			)
		)
		(property "Author" "Antmicro"
			(at 0 0 0)
			(unlocked yes)
			(layer "B.Fab")
			(hide yes)
			(effects
				(font
					(size 1 1)
					(thickness 0.15)
				)
				(justify mirror)
			)
		)
		(property "License" "Apache-2.0"
			(at 0 0 0)
			(unlocked yes)
			(layer "B.Fab")
			(hide yes)
			(effects
				(font
					(size 1 1)
					(thickness 0.15)
				)
				(justify mirror)
			)
		)
		(sheetname "/Power/")
		(sheetfile "power.kicad_sch")
		(attr exclude_from_pos_files exclude_from_bom)
		(fp_circle
			(center 0 0)
			(end 0.475 0)
			(stroke
				(width 0.05)
				(type default)
			)
			(fill no)
			(layer "B.CrtYd")
		)
		(fp_text user "License: Apache-2.0"
			(at -0.4 -5.101 0)
			(layer "B.Fab")
			(effects
				(font
					(size 0.7 0.7)
					(thickness 0.15)
				)
				(justify left bottom mirror)
			)
		)
		(fp_text user "${REFERENCE}"
			(at -0.4 -2.7 0)
			(layer "B.Fab")
			(effects
				(font
					(size 0.7 0.7)
					(thickness 0.15)
				)
				(justify left bottom mirror)
			)
		)
		(fp_text user "Author: Antmicro"
			(at -0.4 -3.901 0)
			(layer "B.Fab")
			(effects
				(font
					(size 0.7 0.7)
					(thickness 0.15)
				)
				(justify left bottom mirror)
			)
		)
		(pad "1" smd circle
			(at 0 0 180)
			(size 0.75 0.75)
			(layers "B.Cu" "B.Mask")
			(net 525 "/Power/USBPD2_HV")
			(pinfunction "1")
			(pintype "passive")
		)
	)
	(footprint "antmicro-footprints:SOT-523"
		(layer "B.Cu")
		(at 213.8 75.702 -90)
		(property "Reference" "Q12"
			(at -1.102 -0.5 270)
			(layer "B.SilkS")
			(effects
				(font
					(size 0.7 0.7)
					(thickness 0.15)
				)
				(justify right top mirror)
			)
		)
		(property "Value" "DMG1012T-7"
			(at 0.1 -1.824 90)
			(layer "B.Fab")
			(effects
				(font
					(size 0.7 0.7)
					(thickness 0.15)
				)
				(justify left bottom mirror)
			)
		)
		(property "Datasheet" "https://www.diodes.com/assets/Datasheets/ds31783.pdf"
			(at 0 0 90)
			(layer "B.Fab")
			(hide yes)
			(effects
				(font
					(size 1.27 1.27)
					(thickness 0.15)
				)
				(justify mirror)
			)
		)
		(property "Description" "Power MOSFET, N Channel, 20 V, 630 mA, 0.3 ohm, SOT-523, Surface Mount"
			(at 0 0 90)
			(layer "B.Fab")
			(hide yes)
			(effects
				(font
					(size 1.27 1.27)
					(thickness 0.15)
				)
				(justify mirror)
			)
		)
		(property "MPN" "DMG1012T-7"
			(at 0 0 90)
			(unlocked yes)
			(layer "B.Fab")
			(hide yes)
			(effects
				(font
					(size 1 1)
					(thickness 0.15)
				)
				(justify mirror)
			)
		)
		(property "Manufacturer" "Diodes Incorporated"
			(at 0 0 90)
			(unlocked yes)
			(layer "B.Fab")
			(hide yes)
			(effects
				(font
					(size 1 1)
					(thickness 0.15)
				)
				(justify mirror)
			)
		)
		(property "Author" "Antmicro"
			(at 0 0 90)
			(unlocked yes)
			(layer "B.Fab")
			(hide yes)
			(effects
				(font
					(size 1 1)
					(thickness 0.15)
				)
				(justify mirror)
			)
		)
		(property "License" "Apache-2.0"
			(at 0 0 90)
			(unlocked yes)
			(layer "B.Fab")
			(hide yes)
			(effects
				(font
					(size 1 1)
					(thickness 0.15)
				)
				(justify mirror)
			)
		)
		(sheetname "/USB Debug, PD/")
		(sheetfile "usb_debug_pd.kicad_sch")
		(attr smd)
		(fp_line
			(start -0.725 0.551)
			(end -0.277 0.551)
			(stroke
				(width 0.15)
				(type solid)
			)
			(layer "B.SilkS")
		)
		(fp_line
			(start -0.277 0.551)
			(end -0.277 0.75)
			(stroke
				(width 0.15)
				(type solid)
			)
			(layer "B.SilkS")
		)
		(fp_line
			(start -0.927 0.351)
			(end -0.725 0.551)
			(stroke
				(width 0.15)
				(type solid)
			)
			(layer "B.SilkS")
		)
		(fp_line
			(start -0.927 0.051)
			(end -0.927 0.351)
			(stroke
				(width 0.15)
				(type solid)
			)
			(layer "B.SilkS")
		)
		(fp_circle
			(center -0.9652 -0.9652)
			(end -0.9152 -0.9652)
			(stroke
				(width 0.15)
				(type solid)
			)
			(fill yes)
			(layer "B.SilkS")
		)
		(fp_line
			(start -1.12 1.16)
			(end 1.1 1.16)
			(stroke
				(width 0.05)
				(type solid)
			)
			(layer "B.CrtYd")
		)
		(fp_line
			(start -1.12 1.16)
			(end -1.12 -1.15)
			(stroke
				(width 0.05)
				(type solid)
			)
			(layer "B.CrtYd")
		)
		(fp_line
			(start 1.1 1.16)
			(end 1.1 -1.15)
			(stroke
				(width 0.05)
				(type solid)
			)
			(layer "B.CrtYd")
		)
		(fp_line
			(start -1.12 -1.15)
			(end 1.1 -1.15)
			(stroke
				(width 0.05)
				(type solid)
			)
			(layer "B.CrtYd")
		)
		(fp_line
			(start -0.652 0.425)
			(end -0.802 0.276)
			(stroke
				(width 0.15)
				(type solid)
			)
			(layer "B.Fab")
		)
		(fp_line
			(start 0.8 0.425)
			(end -0.652 0.425)
			(stroke
				(width 0.15)
				(type solid)
			)
			(layer "B.Fab")
		)
		(fp_line
			(start 0.8 0.425)
			(end 0.8 -0.424)
			(stroke
				(width 0.15)
				(type solid)
			)
			(layer "B.Fab")
		)
		(fp_line
			(start -0.802 0.276)
			(end -0.802 -0.424)
			(stroke
				(width 0.15)
				(type solid)
			)
			(layer "B.Fab")
		)
		(fp_line
			(start 0.8 -0.424)
			(end -0.802 -0.424)
			(stroke
				(width 0.15)
				(type solid)
			)
			(layer "B.Fab")
		)
		(fp_circle
			(center -0.9652 -0.9652)
			(end -0.9144 -0.9652)
			(stroke
				(width 0.15)
				(type solid)
			)
			(fill no)
			(layer "B.Fab")
		)
		(fp_text user "Author: Antmicro"
			(at -1.12 -6.224 90)
			(layer "B.Fab")
			(effects
				(font
					(size 0.7 0.7)
					(thickness 0.15)
				)
				(justify left bottom mirror)
			)
		)
		(fp_text user "License: Apache-2.0"
			(at -1.12 -5.024 90)
			(layer "B.Fab")
			(effects
				(font
					(size 0.7 0.7)
					(thickness 0.15)
				)
				(justify left bottom mirror)
			)
		)
		(fp_text user "${REFERENCE}"
			(at -1.12 -3.824 90)
			(layer "B.Fab")
			(effects
				(font
					(size 0.7 0.7)
					(thickness 0.15)
				)
				(justify left bottom mirror)
			)
		)
		(pad "1" smd rect
			(at -0.5 -0.65 270)
			(size 0.4 0.51)
			(layers "B.Cu" "B.Mask" "B.Paste")
			(net 537 "/USB Debug, PD/FTDI_LED_RX")
			(pinfunction "G")
			(pintype "input")
		)
		(pad "2" smd rect
			(at 0.498 -0.65 270)
			(size 0.4 0.51)
			(layers "B.Cu" "B.Mask" "B.Paste")
			(net 1 "GND")
			(pinfunction "S")
			(pintype "passive")
		)
		(pad "3" smd rect
			(at 0 0.652 270)
			(size 0.4 0.51)
			(layers "B.Cu" "B.Mask" "B.Paste")
			(net 881 "/USB Debug, PD/FTDI_CBUS_EN")
			(pinfunction "D")
			(pintype "passive")
		)
	)
	(footprint "antmicro-footprints:R_0402_1005Metric"
		(layer "B.Cu")
		(at 175.25 57.5 -90)
		(descr "Resistor SMD 0402")
		(tags "resistor SMD 0402")
		(property "Reference" "R61"
			(at -3.58 -0.365532 90)
			(layer "B.SilkS")
			(effects
				(font
					(size 0.7 0.7)
					(thickness 0.15)
				)
				(justify left bottom mirror)
			)
		)
		(property "Value" "R_470R_0402"
			(at -1.011843 -1.772046 90)
			(layer "B.Fab")
			(effects
				(font
					(size 0.7 0.7)
					(thickness 0.15)
				)
				(justify left bottom mirror)
			)
		)
		(property "Datasheet" "https://www.bourns.com/docs/product-datasheets/cr.pdf"
			(at 0 0 90)
			(layer "B.Fab")
			(hide yes)
			(effects
				(font
					(size 1.27 1.27)
					(thickness 0.15)
				)
				(justify mirror)
			)
		)
		(property "Description" "SMD Chip Resistor, 470 ohm, ± 1%, 62.5 mW, 0402 [1005 Metric], Thick Film, General Purpose"
			(at 0 0 90)
			(layer "B.Fab")
			(hide yes)
			(effects
				(font
					(size 1.27 1.27)
					(thickness 0.15)
				)
				(justify mirror)
			)
		)
		(property "MPN" "CR0402-FX-4700GLF"
			(at 0 0 90)
			(unlocked yes)
			(layer "B.Fab")
			(hide yes)
			(effects
				(font
					(size 1 1)
					(thickness 0.15)
				)
				(justify mirror)
			)
		)
		(property "Manufacturer" "Bourns"
			(at 0 0 90)
			(unlocked yes)
			(layer "B.Fab")
			(hide yes)
			(effects
				(font
					(size 1 1)
					(thickness 0.15)
				)
				(justify mirror)
			)
		)
		(property "License" "Apache-2.0"
			(at 0 0 90)
			(unlocked yes)
			(layer "B.Fab")
			(hide yes)
			(effects
				(font
					(size 1 1)
					(thickness 0.15)
				)
				(justify mirror)
			)
		)
		(property "Author" "Antmicro"
			(at 0 0 90)
			(unlocked yes)
			(layer "B.Fab")
			(hide yes)
			(effects
				(font
					(size 1 1)
					(thickness 0.15)
				)
				(justify mirror)
			)
		)
		(property "Val" "470R"
			(at 0 0 90)
			(unlocked yes)
			(layer "B.Fab")
			(hide yes)
			(effects
				(font
					(size 1 1)
					(thickness 0.15)
				)
				(justify mirror)
			)
		)
		(property "Tolerance" "1%"
			(at 0 0 90)
			(unlocked yes)
			(layer "B.Fab")
			(hide yes)
			(effects
				(font
					(size 1 1)
					(thickness 0.15)
				)
				(justify mirror)
			)
		)
		(sheetname "/Power/")
		(sheetfile "power.kicad_sch")
		(attr smd)
		(fp_poly
			(pts
				(xy -0.925 0.47) (xy -0.925 -0.47) (xy 0.925 -0.47) (xy 0.925 0.47)
			)
			(stroke
				(width 0.05)
				(type default)
			)
			(fill no)
			(layer "B.CrtYd")
		)
		(fp_poly
			(pts
				(xy -0.5 0.25) (xy -0.5 -0.25) (xy 0.5 -0.25) (xy 0.5 0.25)
			)
			(stroke
				(width 0.15)
				(type solid)
			)
			(fill no)
			(layer "B.Fab")
		)
		(fp_text user "Author: Antmicro"
			(at -0.95 -4.169 90)
			(layer "B.Fab")
			(effects
				(font
					(size 0.7 0.7)
					(thickness 0.15)
				)
				(justify left bottom mirror)
			)
		)
		(fp_text user "${REFERENCE}"
			(at -0.95 -3.168 90)
			(layer "B.Fab")
			(effects
				(font
					(size 0.7 0.7)
					(thickness 0.15)
				)
				(justify left bottom mirror)
			)
		)
		(fp_text user "License: Apache-2.0"
			(at -0.949999 -5.169 90)
			(layer "B.Fab")
			(effects
				(font
					(size 0.7 0.7)
					(thickness 0.15)
				)
				(justify left bottom mirror)
			)
		)
		(pad "1" smd roundrect
			(at -0.48 0 270)
			(size 0.59 0.64)
			(layers "B.Cu" "B.Mask" "B.Paste")
			(roundrect_rratio 0.25)
			(net 1286 "Net-(D61-A)")
			(pintype "passive")
		)
		(pad "2" smd roundrect
			(at 0.48 0 270)
			(size 0.59 0.64)
			(layers "B.Cu" "B.Mask" "B.Paste")
			(roundrect_rratio 0.25)
			(net 213 "+5V_SOM")
			(pintype "passive")
		)
	)
	(footprint "antmicro-footprints:R_0402_1005Metric"
		(layer "B.Cu")
		(at 223.85 95.868)
		(descr "Resistor SMD 0402")
		(tags "resistor SMD 0402")
		(property "Reference" "R155"
			(at -1.45 1.555 0)
			(layer "B.SilkS")
			(effects
				(font
					(size 0.7 0.7)
					(thickness 0.15)
				)
				(justify right top mirror)
			)
		)
		(property "Value" "R_2M_0402"
			(at -1.011843 -1.772047 0)
			(layer "B.Fab")
			(effects
				(font
					(size 0.7 0.7)
					(thickness 0.15)
				)
				(justify right top mirror)
			)
		)
		(property "Datasheet" "https://www.mouser.com/datasheet/2/447/YAGEO_PYu_RC_Group_51_RoHS_L_12-3313492.pdf"
			(at 0 0 0)
			(layer "B.Fab")
			(hide yes)
			(effects
				(font
					(size 1.27 1.27)
					(thickness 0.15)
				)
				(justify mirror)
			)
		)
		(property "Description" "SMD Chip Resistor, 2 Mohm, ± 1%, 62.5 mW, 0402 [1005 Metric], Thick Film, General Purpose"
			(at 0 0 0)
			(layer "B.Fab")
			(hide yes)
			(effects
				(font
					(size 1.27 1.27)
					(thickness 0.15)
				)
				(justify mirror)
			)
		)
		(property "MPN" "RC0402FR-072ML"
			(at 0 0 180)
			(unlocked yes)
			(layer "B.Fab")
			(hide yes)
			(effects
				(font
					(size 1 1)
					(thickness 0.15)
				)
				(justify mirror)
			)
		)
		(property "Manufacturer" "YAGEO"
			(at 0 0 180)
			(unlocked yes)
			(layer "B.Fab")
			(hide yes)
			(effects
				(font
					(size 1 1)
					(thickness 0.15)
				)
				(justify mirror)
			)
		)
		(property "License" "Apache-2.0"
			(at 0 0 180)
			(unlocked yes)
			(layer "B.Fab")
			(hide yes)
			(effects
				(font
					(size 1 1)
					(thickness 0.15)
				)
				(justify mirror)
			)
		)
		(property "Author" "Antmicro"
			(at 0 0 180)
			(unlocked yes)
			(layer "B.Fab")
			(hide yes)
			(effects
				(font
					(size 1 1)
					(thickness 0.15)
				)
				(justify mirror)
			)
		)
		(property "Val" "2M"
			(at 0 0 180)
			(unlocked yes)
			(layer "B.Fab")
			(hide yes)
			(effects
				(font
					(size 1 1)
					(thickness 0.15)
				)
				(justify mirror)
			)
		)
		(property "Tolerance" "1%"
			(at 0 0 180)
			(unlocked yes)
			(layer "B.Fab")
			(hide yes)
			(effects
				(font
					(size 1 1)
					(thickness 0.15)
				)
				(justify mirror)
			)
		)
		(sheetname "/USB DP Alt mode/")
		(sheetfile "usb_dp.kicad_sch")
		(attr smd)
		(fp_rect
			(start -0.925 0.47)
			(end 0.925 -0.47)
			(stroke
				(width 0.05)
				(type default)
			)
			(fill no)
			(layer "B.CrtYd")
		)
		(fp_rect
			(start -0.5 0.25)
			(end 0.5 -0.25)
			(stroke
				(width 0.15)
				(type solid)
			)
			(fill no)
			(layer "B.Fab")
		)
		(fp_text user "Author: Antmicro"
			(at -0.95 -4.169 0)
			(layer "B.Fab")
			(effects
				(font
					(size 0.7 0.7)
					(thickness 0.15)
				)
				(justify right top mirror)
			)
		)
		(fp_text user "License: Apache-2.0"
			(at -0.95 -5.169 0)
			(layer "B.Fab")
			(effects
				(font
					(size 0.7 0.7)
					(thickness 0.15)
				)
				(justify right top mirror)
			)
		)
		(fp_text user "${REFERENCE}"
			(at -0.95 -3.168 0)
			(layer "B.Fab")
			(effects
				(font
					(size 0.7 0.7)
					(thickness 0.15)
				)
				(justify right top mirror)
			)
		)
		(pad "1" smd roundrect
			(at -0.48 0)
			(size 0.59 0.64)
			(layers "B.Cu" "B.Mask" "B.Paste")
			(roundrect_rratio 0.25)
			(net 815 "/USB DP Alt mode/USBC1_SBU_P")
			(pintype "passive")
		)
		(pad "2" smd roundrect
			(at 0.48 0)
			(size 0.59 0.64)
			(layers "B.Cu" "B.Mask" "B.Paste")
			(roundrect_rratio 0.25)
			(net 1 "GND")
			(pintype "passive")
		)
	)
	(footprint "antmicro-footprints:TP_SMD_0.75mm"
		(layer "B.Cu")
		(at 90.254 60.45 180)
		(property "Reference" "TP118"
			(at -0.346 -0.35 90)
			(layer "B.SilkS")
			(effects
				(font
					(size 0.7 0.7)
					(thickness 0.15)
				)
				(justify left bottom mirror)
			)
		)
		(property "Value" "TP_0.75mm_SMD"
			(at 0 -1.2 0)
			(layer "B.Fab")
			(effects
				(font
					(size 0.7 0.7)
					(thickness 0.15)
				)
				(justify left bottom mirror)
			)
		)
		(property "Description" "SMT test point"
			(at 0 0 0)
			(layer "B.Fab")
			(hide yes)
			(effects
				(font
					(size 1.27 1.27)
					(thickness 0.15)
				)
				(justify mirror)
			)
		)
		(property "MPN" ""
			(at 0 0 0)
			(unlocked yes)
			(layer "B.Fab")
			(hide yes)
			(effects
				(font
					(size 1 1)
					(thickness 0.15)
				)
				(justify mirror)
			)
		)
		(property "Manufacturer" ""
			(at 0 0 0)
			(unlocked yes)
			(layer "B.Fab")
			(hide yes)
			(effects
				(font
					(size 1 1)
					(thickness 0.15)
				)
				(justify mirror)
			)
		)
		(property "Author" "Antmicro"
			(at 0 0 0)
			(unlocked yes)
			(layer "B.Fab")
			(hide yes)
			(effects
				(font
					(size 1 1)
					(thickness 0.15)
				)
				(justify mirror)
			)
		)
		(property "License" "Apache-2.0"
			(at 0 0 0)
			(unlocked yes)
			(layer "B.Fab")
			(hide yes)
			(effects
				(font
					(size 1 1)
					(thickness 0.15)
				)
				(justify mirror)
			)
		)
		(sheetname "/SoM_Power/")
		(sheetfile "som_power.kicad_sch")
		(attr exclude_from_pos_files exclude_from_bom)
		(fp_circle
			(center 0 0)
			(end 0.475 0)
			(stroke
				(width 0.05)
				(type default)
			)
			(fill no)
			(layer "B.CrtYd")
		)
		(fp_text user "${REFERENCE}"
			(at -0.4 -2.7 0)
			(layer "B.Fab")
			(effects
				(font
					(size 0.7 0.7)
					(thickness 0.15)
				)
				(justify left bottom mirror)
			)
		)
		(fp_text user "Author: Antmicro"
			(at -0.4 -3.901 0)
			(layer "B.Fab")
			(effects
				(font
					(size 0.7 0.7)
					(thickness 0.15)
				)
				(justify left bottom mirror)
			)
		)
		(fp_text user "License: Apache-2.0"
			(at -0.4 -5.101 0)
			(layer "B.Fab")
			(effects
				(font
					(size 0.7 0.7)
					(thickness 0.15)
				)
				(justify left bottom mirror)
			)
		)
		(pad "1" smd circle
			(at 0 0 180)
			(size 0.75 0.75)
			(layers "B.Cu" "B.Mask")
			(net 1037 "Net-(U72-~{MR})")
			(pinfunction "1")
			(pintype "passive")
		)
	)
	(footprint "antmicro-footprints:R_0402_1005Metric"
		(layer "B.Cu")
		(at 66.4 65.7 -90)
		(descr "Resistor SMD 0402")
		(tags "resistor SMD 0402")
		(property "Reference" "R392"
			(at 0.9 -0.5 90)
			(layer "B.SilkS")
			(effects
				(font
					(size 0.7 0.7)
					(thickness 0.15)
				)
				(justify left bottom mirror)
			)
		)
		(property "Value" "R_2k2_0402"
			(at -1.011843 -1.772047 90)
			(layer "B.Fab")
			(effects
				(font
					(size 0.7 0.7)
					(thickness 0.15)
				)
				(justify left bottom mirror)
			)
		)
		(property "Datasheet" "https://www.bourns.com/docs/product-datasheets/cr.pdf"
			(at 0 0 90)
			(layer "B.Fab")
			(hide yes)
			(effects
				(font
					(size 1.27 1.27)
					(thickness 0.15)
				)
				(justify mirror)
			)
		)
		(property "Description" "SMD Chip Resistor, 2.2 kohm, ± 1%, 62.5 mW, 0402 [1005 Metric], Thick Film, General Purpose"
			(at 0 0 90)
			(layer "B.Fab")
			(hide yes)
			(effects
				(font
					(size 1.27 1.27)
					(thickness 0.15)
				)
				(justify mirror)
			)
		)
		(property "MPN" "CR0402-FX-2201GLF"
			(at 0 0 90)
			(unlocked yes)
			(layer "B.Fab")
			(hide yes)
			(effects
				(font
					(size 1 1)
					(thickness 0.15)
				)
				(justify mirror)
			)
		)
		(property "Manufacturer" "Bourns"
			(at 0 0 90)
			(unlocked yes)
			(layer "B.Fab")
			(hide yes)
			(effects
				(font
					(size 1 1)
					(thickness 0.15)
				)
				(justify mirror)
			)
		)
		(property "License" "Apache-2.0"
			(at 0 0 90)
			(unlocked yes)
			(layer "B.Fab")
			(hide yes)
			(effects
				(font
					(size 1 1)
					(thickness 0.15)
				)
				(justify mirror)
			)
		)
		(property "Author" "Antmicro"
			(at 0 0 90)
			(unlocked yes)
			(layer "B.Fab")
			(hide yes)
			(effects
				(font
					(size 1 1)
					(thickness 0.15)
				)
				(justify mirror)
			)
		)
		(property "Val" "2k2"
			(at 0 0 90)
			(unlocked yes)
			(layer "B.Fab")
			(hide yes)
			(effects
				(font
					(size 1 1)
					(thickness 0.15)
				)
				(justify mirror)
			)
		)
		(property "Tolerance" "1%"
			(at 0 0 90)
			(unlocked yes)
			(layer "B.Fab")
			(hide yes)
			(effects
				(font
					(size 1 1)
					(thickness 0.15)
				)
				(justify mirror)
			)
		)
		(sheetname "/CSI/")
		(sheetfile "csi.kicad_sch")
		(attr smd)
		(fp_rect
			(start -0.925 0.47)
			(end 0.925 -0.47)
			(stroke
				(width 0.05)
				(type default)
			)
			(fill no)
			(layer "B.CrtYd")
		)
		(fp_rect
			(start -0.5 0.25)
			(end 0.5 -0.25)
			(stroke
				(width 0.15)
				(type solid)
			)
			(fill no)
			(layer "B.Fab")
		)
		(fp_text user "Author: Antmicro"
			(at -0.95 -4.169 90)
			(layer "B.Fab")
			(effects
				(font
					(size 0.7 0.7)
					(thickness 0.15)
				)
				(justify left bottom mirror)
			)
		)
		(fp_text user "${REFERENCE}"
			(at -0.95 -3.168 90)
			(layer "B.Fab")
			(effects
				(font
					(size 0.7 0.7)
					(thickness 0.15)
				)
				(justify left bottom mirror)
			)
		)
		(fp_text user "License: Apache-2.0"
			(at -0.95 -5.169 90)
			(layer "B.Fab")
			(effects
				(font
					(size 0.7 0.7)
					(thickness 0.15)
				)
				(justify left bottom mirror)
			)
		)
		(pad "1" smd roundrect
			(at -0.48 0 270)
			(size 0.59 0.64)
			(layers "B.Cu" "B.Mask" "B.Paste")
			(roundrect_rratio 0.25)
			(net 990 "/CSI/CSIB_I2C_VCC")
			(pintype "passive")
		)
		(pad "2" smd roundrect
			(at 0.48 0 270)
			(size 0.59 0.64)
			(layers "B.Cu" "B.Mask" "B.Paste")
			(roundrect_rratio 0.25)
			(net 994 "/CSI/SCL_CAM2")
			(pintype "passive")
		)
	)
	(footprint "antmicro-footprints:R_0402_1005Metric"
		(layer "B.Cu")
		(at 238.895 61.495 90)
		(descr "Resistor SMD 0402")
		(tags "resistor SMD 0402")
		(property "Reference" "R412"
			(at 1.295 -0.395 90)
			(layer "B.SilkS")
			(effects
				(font
					(size 0.7 0.7)
					(thickness 0.15)
				)
				(justify right top mirror)
			)
		)
		(property "Value" "R_2k2_0402"
			(at -1.011843 -1.772046 90)
			(layer "B.Fab")
			(effects
				(font
					(size 0.7 0.7)
					(thickness 0.15)
				)
				(justify right top mirror)
			)
		)
		(property "Datasheet" "https://www.bourns.com/docs/product-datasheets/cr.pdf"
			(at 0 0 90)
			(layer "B.Fab")
			(hide yes)
			(effects
				(font
					(size 1.27 1.27)
					(thickness 0.15)
				)
				(justify mirror)
			)
		)
		(property "Description" "SMD Chip Resistor, 2.2 kohm, ± 1%, 62.5 mW, 0402 [1005 Metric], Thick Film, General Purpose"
			(at 0 0 90)
			(layer "B.Fab")
			(hide yes)
			(effects
				(font
					(size 1.27 1.27)
					(thickness 0.15)
				)
				(justify mirror)
			)
		)
		(property "MPN" "CR0402-FX-2201GLF"
			(at 0 0 270)
			(unlocked yes)
			(layer "B.Fab")
			(hide yes)
			(effects
				(font
					(size 1 1)
					(thickness 0.15)
				)
				(justify mirror)
			)
		)
		(property "Manufacturer" "Bourns"
			(at 0 0 270)
			(unlocked yes)
			(layer "B.Fab")
			(hide yes)
			(effects
				(font
					(size 1 1)
					(thickness 0.15)
				)
				(justify mirror)
			)
		)
		(property "License" "Apache-2.0"
			(at 0 0 270)
			(unlocked yes)
			(layer "B.Fab")
			(hide yes)
			(effects
				(font
					(size 1 1)
					(thickness 0.15)
				)
				(justify mirror)
			)
		)
		(property "Author" "Antmicro"
			(at 0 0 270)
			(unlocked yes)
			(layer "B.Fab")
			(hide yes)
			(effects
				(font
					(size 1 1)
					(thickness 0.15)
				)
				(justify mirror)
			)
		)
		(property "Val" "2k2"
			(at 0 0 270)
			(unlocked yes)
			(layer "B.Fab")
			(hide yes)
			(effects
				(font
					(size 1 1)
					(thickness 0.15)
				)
				(justify mirror)
			)
		)
		(property "Tolerance" "1%"
			(at 0 0 270)
			(unlocked yes)
			(layer "B.Fab")
			(hide yes)
			(effects
				(font
					(size 1 1)
					(thickness 0.15)
				)
				(justify mirror)
			)
		)
		(sheetname "/Power/")
		(sheetfile "power.kicad_sch")
		(attr smd)
		(fp_poly
			(pts
				(xy -0.925 0.47) (xy 0.925 0.47) (xy 0.925 -0.47) (xy -0.925 -0.47)
			)
			(stroke
				(width 0.05)
				(type default)
			)
			(fill no)
			(layer "B.CrtYd")
		)
		(fp_poly
			(pts
				(xy -0.5 0.25) (xy 0.5 0.25) (xy 0.5 -0.25) (xy -0.5 -0.25)
			)
			(stroke
				(width 0.15)
				(type solid)
			)
			(fill no)
			(layer "B.Fab")
		)
		(fp_text user "Author: Antmicro"
			(at -0.95 -4.169 90)
			(layer "B.Fab")
			(effects
				(font
					(size 0.7 0.7)
					(thickness 0.15)
				)
				(justify right top mirror)
			)
		)
		(fp_text user "License: Apache-2.0"
			(at -0.949999 -5.169 90)
			(layer "B.Fab")
			(effects
				(font
					(size 0.7 0.7)
					(thickness 0.15)
				)
				(justify right top mirror)
			)
		)
		(fp_text user "${REFERENCE}"
			(at -0.95 -3.168 90)
			(layer "B.Fab")
			(effects
				(font
					(size 0.7 0.7)
					(thickness 0.15)
				)
				(justify right top mirror)
			)
		)
		(pad "1" smd roundrect
			(at -0.48 0 90)
			(size 0.59 0.64)
			(layers "B.Cu" "B.Mask" "B.Paste")
			(roundrect_rratio 0.25)
			(net 1395 "Net-(D53-A)")
			(pintype "passive")
		)
		(pad "2" smd roundrect
			(at 0.48 0 90)
			(size 0.59 0.64)
			(layers "B.Cu" "B.Mask" "B.Paste")
			(roundrect_rratio 0.25)
			(net 13 "VCC")
			(pintype "passive")
		)
	)
	(footprint "antmicro-footprints:TP_SMD_0.75mm"
		(layer "B.Cu")
		(at 176.38 58 180)
		(property "Reference" "TP130"
			(at -0.44 4.04 270)
			(layer "B.SilkS")
			(effects
				(font
					(size 0.7 0.7)
					(thickness 0.15)
				)
				(justify left bottom mirror)
			)
		)
		(property "Value" "TP_0.75mm_SMD"
			(at 0 -1.2 0)
			(layer "B.Fab")
			(effects
				(font
					(size 0.7 0.7)
					(thickness 0.15)
				)
				(justify left bottom mirror)
			)
		)
		(property "Description" "SMT test point"
			(at 0 0 0)
			(layer "B.Fab")
			(hide yes)
			(effects
				(font
					(size 1.27 1.27)
					(thickness 0.15)
				)
				(justify mirror)
			)
		)
		(property "MPN" ""
			(at 0 0 0)
			(unlocked yes)
			(layer "B.Fab")
			(hide yes)
			(effects
				(font
					(size 1 1)
					(thickness 0.15)
				)
				(justify mirror)
			)
		)
		(property "Manufacturer" ""
			(at 0 0 0)
			(unlocked yes)
			(layer "B.Fab")
			(hide yes)
			(effects
				(font
					(size 1 1)
					(thickness 0.15)
				)
				(justify mirror)
			)
		)
		(property "Author" "Antmicro"
			(at 0 0 0)
			(unlocked yes)
			(layer "B.Fab")
			(hide yes)
			(effects
				(font
					(size 1 1)
					(thickness 0.15)
				)
				(justify mirror)
			)
		)
		(property "License" "Apache-2.0"
			(at 0 0 0)
			(unlocked yes)
			(layer "B.Fab")
			(hide yes)
			(effects
				(font
					(size 1 1)
					(thickness 0.15)
				)
				(justify mirror)
			)
		)
		(sheetname "/Power/")
		(sheetfile "power.kicad_sch")
		(attr exclude_from_pos_files exclude_from_bom)
		(fp_circle
			(center 0 0)
			(end 0.475 0)
			(stroke
				(width 0.05)
				(type default)
			)
			(fill no)
			(layer "B.CrtYd")
		)
		(fp_text user "Author: Antmicro"
			(at -0.4 -3.901 0)
			(layer "B.Fab")
			(effects
				(font
					(size 0.7 0.7)
					(thickness 0.15)
				)
				(justify left bottom mirror)
			)
		)
		(fp_text user "License: Apache-2.0"
			(at -0.4 -5.101 0)
			(layer "B.Fab")
			(effects
				(font
					(size 0.7 0.7)
					(thickness 0.15)
				)
				(justify left bottom mirror)
			)
		)
		(fp_text user "${REFERENCE}"
			(at -0.4 -2.7 0)
			(layer "B.Fab")
			(effects
				(font
					(size 0.7 0.7)
					(thickness 0.15)
				)
				(justify left bottom mirror)
			)
		)
		(pad "1" smd circle
			(at 0 0 180)
			(size 0.75 0.75)
			(layers "B.Cu" "B.Mask")
			(net 213 "+5V_SOM")
			(pinfunction "1")
			(pintype "passive")
		)
	)
	(footprint "antmicro-footprints:Spacer_Drill3.7mm_H8mm_9774080151R"
		(locked yes)
		(layer "B.Cu")
		(at 216.930532 63.71 -90)
		(descr "Spacer M=3 h=8mm fi=5.1mm")
		(property "Reference" "H3"
			(at 0 3.2 90)
			(layer "B.SilkS")
			(effects
				(font
					(size 0.7 0.7)
					(thickness 0.15)
				)
				(justify left bottom mirror)
			)
		)
		(property "Value" "Spacer_Drill3.7mm_H8mm_9774080151R"
			(at 0 -4 90)
			(layer "B.Fab")
			(effects
				(font
					(size 0.7 0.7)
					(thickness 0.15)
				)
				(justify left bottom mirror)
			)
		)
		(property "Datasheet" "https://www.we-online.com/components/products/datasheet/9774080151R.pdf"
			(at 0 0 90)
			(layer "B.Fab")
			(hide yes)
			(effects
				(font
					(size 1.27 1.27)
					(thickness 0.15)
				)
				(justify mirror)
			)
		)
		(property "Description" "Spacer, SMT, Non Stop, Steel, Swage Round, 5.1 mm x 8 mm, M2.5 Thread, WA-SMSI Series"
			(at 0 0 90)
			(layer "B.Fab")
			(hide yes)
			(effects
				(font
					(size 1.27 1.27)
					(thickness 0.15)
				)
				(justify mirror)
			)
		)
		(property "Manufacturer" "Würth Elektronik"
			(at 0 0 270)
			(unlocked yes)
			(layer "B.Fab")
			(hide yes)
			(effects
				(font
					(size 1 1)
					(thickness 0.15)
				)
				(justify mirror)
			)
		)
		(property "MPN" "9774080151R"
			(at 0 0 270)
			(unlocked yes)
			(layer "B.Fab")
			(hide yes)
			(effects
				(font
					(size 1 1)
					(thickness 0.15)
				)
				(justify mirror)
			)
		)
		(property "Author" "Antmicro"
			(at 0 0 270)
			(unlocked yes)
			(layer "B.Fab")
			(hide yes)
			(effects
				(font
					(size 1 1)
					(thickness 0.15)
				)
				(justify mirror)
			)
		)
		(property "License" "Apache-2.0"
			(at 0 0 270)
			(unlocked yes)
			(layer "B.Fab")
			(hide yes)
			(effects
				(font
					(size 1 1)
					(thickness 0.15)
				)
				(justify mirror)
			)
		)
		(sheetname "/")
		(sheetfile "jetson-agx-thor-baseboard.kicad_sch")
		(solder_paste_margin_ratio -1)
		(attr smd)
		(fp_circle
			(center 0 0)
			(end 3.05 0)
			(stroke
				(width 0.05)
				(type solid)
			)
			(fill no)
			(layer "B.CrtYd")
		)
		(fp_circle
			(center 0 0)
			(end 2.6 0)
			(stroke
				(width 0.15)
				(type solid)
			)
			(fill no)
			(layer "B.Fab")
		)
		(fp_text user "Author: Antmicro"
			(at -9.6 -7.7 90)
			(layer "B.Fab")
			(effects
				(font
					(size 0.7 0.7)
					(thickness 0.15)
				)
				(justify left bottom mirror)
			)
		)
		(fp_text user "License: Apache-2.0"
			(at -9.6 -8.9 90)
			(layer "B.Fab")
			(effects
				(font
					(size 0.7 0.7)
					(thickness 0.15)
				)
				(justify left bottom mirror)
			)
		)
		(fp_text user "${REFERENCE}"
			(at -9.6 -6.5 90)
			(layer "B.Fab")
			(effects
				(font
					(size 0.7 0.7)
					(thickness 0.15)
				)
				(justify left bottom mirror)
			)
		)
		(pad "" smd custom
			(at -1.7 -1.7 180)
			(size 0.62 0.62)
			(layers "B.Paste")
			(thermal_bridge_angle 90)
			(options
				(clearance outline)
				(anchor circle)
			)
			(primitives
				(gr_arc
					(start 1.266786 0.24747)
					(mid 0.285453 -0.29439)
					(end -0.250195 -1.279127)
					(width 0.2)
				)
				(gr_arc
					(start 1.259603 0.339191)
					(mid 0.218448 -0.232561)
					(end -0.34334 -1.279127)
					(width 0.2)
				)
				(gr_arc
					(start 1.255279 0.431435)
					(mid 0.152481 -0.169693)
					(end -0.436309 -1.279127)
					(width 0.2)
				)
				(gr_arc
					(start 1.253811 0.524161)
					(mid 0.087542 -0.105784)
					(end -0.529126 -1.279127)
					(width 0.2)
				)
				(gr_arc
					(start 1.275473 0.621136)
					(mid 0.0309 -0.033527)
					(end -0.621807 -1.279127)
					(width 0.2)
				)
				(gr_arc
					(start 1.263664 0.711602)
					(mid -0.037759 0.026651)
					(end -0.71437 -1.279127)
					(width 0.2)
				)
				(gr_arc
					(start 1.253435 0.802342)
					(mid -0.105837 0.087395)
					(end -0.806826 -1.279127)
					(width 0.2)
				)
				(gr_arc
					(start 1.267475 0.897258)
					(mid -0.165236 0.156885)
					(end -0.899187 -1.279127)
					(width 0.2)
				)
				(gr_arc
					(start 1.270645 0.990112)
					(mid -0.228522 0.222449)
					(end -0.991463 -1.279127)
					(width 0.2)
				)
				(gr_arc
					(start 1.266278 1.081674)
					(mid -0.294507 0.285313)
					(end -1.083663 -1.279127)
					(width 0.2)
				)
				(gr_line
					(start 1.279127 0.250195)
					(end 1.279127 1.083663)
					(width 0.2)
				)
				(gr_line
					(start -0.250195 -1.279127)
					(end -1.083663 -1.279127)
					(width 0.2)
				)
			)
		)
		(pad "" smd custom
			(at -1.7 1.7 270)
			(size 0.62 0.62)
			(layers "B.Paste")
			(thermal_bridge_angle 90)
			(options
				(clearance outline)
				(anchor circle)
			)
			(primitives
				(gr_arc
					(start 1.266786 0.24747)
					(mid 0.285453 -0.29439)
					(end -0.250195 -1.279127)
					(width 0.2)
				)
				(gr_arc
					(start 1.259603 0.339191)
					(mid 0.218448 -0.232561)
					(end -0.34334 -1.279127)
					(width 0.2)
				)
				(gr_arc
					(start 1.255279 0.431435)
					(mid 0.152481 -0.169693)
					(end -0.436309 -1.279127)
					(width 0.2)
				)
				(gr_arc
					(start 1.253811 0.524161)
					(mid 0.087542 -0.105784)
					(end -0.529126 -1.279127)
					(width 0.2)
				)
				(gr_arc
					(start 1.275473 0.621136)
					(mid 0.0309 -0.033527)
					(end -0.621807 -1.279127)
					(width 0.2)
				)
				(gr_arc
					(start 1.263664 0.711602)
					(mid -0.037759 0.026651)
					(end -0.71437 -1.279127)
					(width 0.2)
				)
				(gr_arc
					(start 1.253435 0.802342)
					(mid -0.105837 0.087395)
					(end -0.806826 -1.279127)
					(width 0.2)
				)
				(gr_arc
					(start 1.267475 0.897258)
					(mid -0.165236 0.156885)
					(end -0.899187 -1.279127)
					(width 0.2)
				)
				(gr_arc
					(start 1.270645 0.990112)
					(mid -0.228522 0.222449)
					(end -0.991463 -1.279127)
					(width 0.2)
				)
				(gr_arc
					(start 1.266278 1.081674)
					(mid -0.294507 0.285313)
					(end -1.083663 -1.279127)
					(width 0.2)
				)
				(gr_line
					(start 1.279127 0.250195)
					(end 1.279127 1.083663)
					(width 0.2)
				)
				(gr_line
					(start -0.250195 -1.279127)
					(end -1.083663 -1.279127)
					(width 0.2)
				)
			)
		)
		(pad "" smd custom
			(at 1.7 -1.7 90)
			(size 0.62 0.62)
			(layers "B.Paste")
			(thermal_bridge_angle 90)
			(options
				(clearance outline)
				(anchor circle)
			)
			(primitives
				(gr_arc
					(start 1.266786 0.24747)
					(mid 0.285453 -0.29439)
					(end -0.250195 -1.279127)
					(width 0.2)
				)
				(gr_arc
					(start 1.259603 0.339191)
					(mid 0.218448 -0.232561)
					(end -0.34334 -1.279127)
					(width 0.2)
				)
				(gr_arc
					(start 1.255279 0.431435)
					(mid 0.152481 -0.169693)
					(end -0.436309 -1.279127)
					(width 0.2)
				)
				(gr_arc
					(start 1.253811 0.524161)
					(mid 0.087542 -0.105784)
					(end -0.529126 -1.279127)
					(width 0.2)
				)
				(gr_arc
					(start 1.275473 0.621136)
					(mid 0.0309 -0.033527)
					(end -0.621807 -1.279127)
					(width 0.2)
				)
				(gr_arc
					(start 1.263664 0.711602)
					(mid -0.037759 0.026651)
					(end -0.71437 -1.279127)
					(width 0.2)
				)
				(gr_arc
					(start 1.253435 0.802342)
					(mid -0.105837 0.087395)
					(end -0.806826 -1.279127)
					(width 0.2)
				)
				(gr_arc
					(start 1.267475 0.897258)
					(mid -0.165236 0.156885)
					(end -0.899187 -1.279127)
					(width 0.2)
				)
				(gr_arc
					(start 1.270645 0.990112)
					(mid -0.228522 0.222449)
					(end -0.991463 -1.279127)
					(width 0.2)
				)
				(gr_arc
					(start 1.266278 1.081674)
					(mid -0.294507 0.285313)
					(end -1.083663 -1.279127)
					(width 0.2)
				)
				(gr_line
					(start 1.279127 0.250195)
					(end 1.279127 1.083663)
					(width 0.2)
				)
				(gr_line
					(start -0.250195 -1.279127)
					(end -1.083663 -1.279127)
					(width 0.2)
				)
			)
		)
		(pad "" smd custom
			(at 1.7 1.7)
			(size 0.62 0.62)
			(layers "B.Paste")
			(thermal_bridge_angle 90)
			(options
				(clearance outline)
				(anchor circle)
			)
			(primitives
				(gr_arc
					(start 1.266786 0.24747)
					(mid 0.285453 -0.29439)
					(end -0.250195 -1.279127)
					(width 0.2)
				)
				(gr_arc
					(start 1.259603 0.339191)
					(mid 0.218448 -0.232561)
					(end -0.34334 -1.279127)
					(width 0.2)
				)
				(gr_arc
					(start 1.255279 0.431435)
					(mid 0.152481 -0.169693)
					(end -0.436309 -1.279127)
					(width 0.2)
				)
				(gr_arc
					(start 1.253811 0.524161)
					(mid 0.087542 -0.105784)
					(end -0.529126 -1.279127)
					(width 0.2)
				)
				(gr_arc
					(start 1.275473 0.621136)
					(mid 0.0309 -0.033527)
					(end -0.621807 -1.279127)
					(width 0.2)
				)
				(gr_arc
					(start 1.263664 0.711602)
					(mid -0.037759 0.026651)
					(end -0.71437 -1.279127)
					(width 0.2)
				)
				(gr_arc
					(start 1.253435 0.802342)
					(mid -0.105837 0.087395)
					(end -0.806826 -1.279127)
					(width 0.2)
				)
				(gr_arc
					(start 1.267475 0.897258)
					(mid -0.165236 0.156885)
					(end -0.899187 -1.279127)
					(width 0.2)
				)
				(gr_arc
					(start 1.270645 0.990112)
					(mid -0.228522 0.222449)
					(end -0.991463 -1.279127)
					(width 0.2)
				)
				(gr_arc
					(start 1.266278 1.081674)
					(mid -0.294507 0.285313)
					(end -1.083663 -1.279127)
					(width 0.2)
				)
				(gr_line
					(start 1.279127 0.250195)
					(end 1.279127 1.083663)
					(width 0.2)
				)
				(gr_line
					(start -0.250195 -1.279127)
					(end -1.083663 -1.279127)
					(width 0.2)
				)
			)
		)
		(pad "1" thru_hole circle
			(at 0 0 270)
			(size 6 6)
			(drill 3.7)
			(layers "*.Cu" "*.Mask")
			(remove_unused_layers no)
			(net 1 "GND")
			(pintype "passive")
		)
	)
	(footprint "antmicro-footprints:R_0402_1005Metric"
		(layer "B.Cu")
		(at 203.4 103.8 180)
		(descr "Resistor SMD 0402")
		(tags "resistor SMD 0402")
		(property "Reference" "R278"
			(at -3.85 -0.5 0)
			(layer "B.SilkS")
			(effects
				(font
					(size 0.7 0.7)
					(thickness 0.15)
				)
				(justify left bottom mirror)
			)
		)
		(property "Value" "R_10k_0402"
			(at -1.011843 -1.772046 0)
			(layer "B.Fab")
			(effects
				(font
					(size 0.7 0.7)
					(thickness 0.15)
				)
				(justify left bottom mirror)
			)
		)
		(property "Datasheet" "https://www.bourns.com/docs/product-datasheets/cr.pdf"
			(at 0 0 0)
			(layer "B.Fab")
			(hide yes)
			(effects
				(font
					(size 1.27 1.27)
					(thickness 0.15)
				)
				(justify mirror)
			)
		)
		(property "Description" "SMD Chip Resistor, 10 kohm, ± 1%, 62.5 mW, 0402 [1005 Metric], Thick Film, General Purpose"
			(at 0 0 0)
			(layer "B.Fab")
			(hide yes)
			(effects
				(font
					(size 1.27 1.27)
					(thickness 0.15)
				)
				(justify mirror)
			)
		)
		(property "Manufacturer" "Bourns"
			(at 0 0 0)
			(unlocked yes)
			(layer "B.Fab")
			(hide yes)
			(effects
				(font
					(size 1 1)
					(thickness 0.15)
				)
				(justify mirror)
			)
		)
		(property "MPN" "CR0402-FX-1002GLF"
			(at 0 0 0)
			(unlocked yes)
			(layer "B.Fab")
			(hide yes)
			(effects
				(font
					(size 1 1)
					(thickness 0.15)
				)
				(justify mirror)
			)
		)
		(property "Val" "10k"
			(at 0 0 0)
			(unlocked yes)
			(layer "B.Fab")
			(hide yes)
			(effects
				(font
					(size 1 1)
					(thickness 0.15)
				)
				(justify mirror)
			)
		)
		(property "License" "Apache-2.0"
			(at 0 0 0)
			(unlocked yes)
			(layer "B.Fab")
			(hide yes)
			(effects
				(font
					(size 1 1)
					(thickness 0.15)
				)
				(justify mirror)
			)
		)
		(property "Author" "Antmicro"
			(at 0 0 0)
			(unlocked yes)
			(layer "B.Fab")
			(hide yes)
			(effects
				(font
					(size 1 1)
					(thickness 0.15)
				)
				(justify mirror)
			)
		)
		(property "Tolerance" "1%"
			(at 0 0 0)
			(unlocked yes)
			(layer "B.Fab")
			(hide yes)
			(effects
				(font
					(size 1 1)
					(thickness 0.15)
				)
				(justify mirror)
			)
		)
		(sheetname "/Recovery USB/")
		(sheetfile "recovery_usb.kicad_sch")
		(attr smd)
		(fp_poly
			(pts
				(xy -0.925 0.47) (xy 0.925 0.47) (xy 0.925 -0.47) (xy -0.925 -0.47)
			)
			(stroke
				(width 0.05)
				(type default)
			)
			(fill no)
			(layer "B.CrtYd")
		)
		(fp_poly
			(pts
				(xy -0.5 0.25) (xy 0.5 0.25) (xy 0.5 -0.25) (xy -0.5 -0.25)
			)
			(stroke
				(width 0.15)
				(type solid)
			)
			(fill no)
			(layer "B.Fab")
		)
		(fp_text user "Author: Antmicro"
			(at -0.95 -4.169 0)
			(layer "B.Fab")
			(effects
				(font
					(size 0.7 0.7)
					(thickness 0.15)
				)
				(justify left bottom mirror)
			)
		)
		(fp_text user "License: Apache-2.0"
			(at -0.949999 -5.169 0)
			(layer "B.Fab")
			(effects
				(font
					(size 0.7 0.7)
					(thickness 0.15)
				)
				(justify left bottom mirror)
			)
		)
		(fp_text user "${REFERENCE}"
			(at -0.95 -3.168 0)
			(layer "B.Fab")
			(effects
				(font
					(size 0.7 0.7)
					(thickness 0.15)
				)
				(justify left bottom mirror)
			)
		)
		(pad "1" smd roundrect
			(at -0.48 0 180)
			(size 0.59 0.64)
			(layers "B.Cu" "B.Mask" "B.Paste")
			(roundrect_rratio 0.25)
			(net 1023 "/Recovery USB/USBC2_I_MODE")
			(pintype "passive")
		)
		(pad "2" smd roundrect
			(at 0.48 0 180)
			(size 0.59 0.64)
			(layers "B.Cu" "B.Mask" "B.Paste")
			(roundrect_rratio 0.25)
			(net 5 "+5V")
			(pintype "passive")
		)
	)
	(footprint "antmicro-footprints:C_0402_1005Metric"
		(layer "B.Cu")
		(at 137.2 71.2 180)
		(descr "Capacitor SMD 0402")
		(tags "capacitor SMD 0402")
		(property "Reference" "C272"
			(at -1.42 0.68 0)
			(layer "B.SilkS")
			(effects
				(font
					(size 0.7 0.7)
					(thickness 0.15)
				)
				(justify left bottom mirror)
			)
		)
		(property "Value" "C_100n_0402"
			(at -1.022927 -2.155213 0)
			(layer "B.Fab")
			(effects
				(font
					(size 0.7 0.7)
					(thickness 0.15)
				)
				(justify left bottom mirror)
			)
		)
		(property "Datasheet" "https://www.murata.com/products/productdetail?partno=GRM155R61H104KE14%23"
			(at 0 0 0)
			(layer "B.Fab")
			(hide yes)
			(effects
				(font
					(size 1.27 1.27)
					(thickness 0.15)
				)
				(justify mirror)
			)
		)
		(property "Description" "SMD Multilayer Ceramic Capacitor, 0.1 µF, 50 V, 0402 [1005 Metric], ± 10%, X5R, GRM Series"
			(at 0 0 0)
			(layer "B.Fab")
			(hide yes)
			(effects
				(font
					(size 1.27 1.27)
					(thickness 0.15)
				)
				(justify mirror)
			)
		)
		(property "MPN" "GRM155R61H104KE14D"
			(at 0 0 0)
			(unlocked yes)
			(layer "B.Fab")
			(hide yes)
			(effects
				(font
					(size 1 1)
					(thickness 0.15)
				)
				(justify mirror)
			)
		)
		(property "Val" "100n"
			(at 0 0 0)
			(unlocked yes)
			(layer "B.Fab")
			(hide yes)
			(effects
				(font
					(size 1 1)
					(thickness 0.15)
				)
				(justify mirror)
			)
		)
		(property "Voltage" "50V"
			(at 0 0 0)
			(unlocked yes)
			(layer "B.Fab")
			(hide yes)
			(effects
				(font
					(size 1 1)
					(thickness 0.15)
				)
				(justify mirror)
			)
		)
		(property "Dielectric" "X5R"
			(at 0 0 0)
			(unlocked yes)
			(layer "B.Fab")
			(hide yes)
			(effects
				(font
					(size 1 1)
					(thickness 0.15)
				)
				(justify mirror)
			)
		)
		(property "Manufacturer" "Murata"
			(at 0 0 0)
			(unlocked yes)
			(layer "B.Fab")
			(hide yes)
			(effects
				(font
					(size 1 1)
					(thickness 0.15)
				)
				(justify mirror)
			)
		)
		(property "License" "Apache-2.0"
			(at 0 0 0)
			(unlocked yes)
			(layer "B.Fab")
			(hide yes)
			(effects
				(font
					(size 1 1)
					(thickness 0.15)
				)
				(justify mirror)
			)
		)
		(property "Author" "Antmicro"
			(at 0 0 0)
			(unlocked yes)
			(layer "B.Fab")
			(hide yes)
			(effects
				(font
					(size 1 1)
					(thickness 0.15)
				)
				(justify mirror)
			)
		)
		(sheetname "/SoM_Power/")
		(sheetfile "som_power.kicad_sch")
		(attr smd)
		(fp_poly
			(pts
				(xy -0.925 0.47) (xy -0.925 -0.47) (xy 0.925 -0.47) (xy 0.925 0.47)
			)
			(stroke
				(width 0.05)
				(type default)
			)
			(fill no)
			(layer "B.CrtYd")
		)
		(fp_line
			(start 0.504 0.25)
			(end 0.504 -0.248)
			(stroke
				(width 0.15)
				(type solid)
			)
			(layer "B.Fab")
		)
		(fp_line
			(start 0.504 -0.248)
			(end -0.494 -0.248)
			(stroke
				(width 0.15)
				(type solid)
			)
			(layer "B.Fab")
		)
		(fp_line
			(start -0.494 0.25)
			(end 0.504 0.25)
			(stroke
				(width 0.15)
				(type solid)
			)
			(layer "B.Fab")
		)
		(fp_line
			(start -0.494 -0.248)
			(end -0.494 0.25)
			(stroke
				(width 0.15)
				(type solid)
			)
			(layer "B.Fab")
		)
		(fp_text user "${REFERENCE}"
			(at -0.939 -4.599 0)
			(layer "B.Fab")
			(effects
				(font
					(size 0.7 0.7)
					(thickness 0.15)
				)
				(justify left bottom mirror)
			)
		)
		(fp_text user "Author: Antmicro"
			(at -0.939 -3.399 0)
			(layer "B.Fab")
			(effects
				(font
					(size 0.7 0.7)
					(thickness 0.15)
				)
				(justify left bottom mirror)
			)
		)
		(fp_text user "License: Apache-2.0"
			(at -0.939 -5.799 0)
			(layer "B.Fab")
			(effects
				(font
					(size 0.7 0.7)
					(thickness 0.15)
				)
				(justify left bottom mirror)
			)
		)
		(pad "1" smd roundrect
			(at -0.48 0 180)
			(size 0.59 0.64)
			(layers "B.Cu" "B.Mask" "B.Paste")
			(roundrect_rratio 0.25)
			(net 1 "GND")
			(pintype "passive")
		)
		(pad "2" smd roundrect
			(at 0.48 0 180)
			(size 0.59 0.64)
			(layers "B.Cu" "B.Mask" "B.Paste")
			(roundrect_rratio 0.25)
			(net 4 "+3V3_AON")
			(pintype "passive")
		)
	)
	(footprint "antmicro-footprints:TP_SMD_0.75mm"
		(layer "B.Cu")
		(at 91.4 83.4 -90)
		(property "Reference" "TP101"
			(at -2.595 -1.63 90)
			(layer "B.SilkS")
			(effects
				(font
					(size 0.7 0.7)
					(thickness 0.15)
				)
				(justify left bottom mirror)
			)
		)
		(property "Value" "TP_0.75mm_SMD"
			(at 0 -1.2 90)
			(layer "B.Fab")
			(effects
				(font
					(size 0.7 0.7)
					(thickness 0.15)
				)
				(justify left bottom mirror)
			)
		)
		(property "Description" "SMT test point"
			(at 0 0 90)
			(layer "B.Fab")
			(hide yes)
			(effects
				(font
					(size 1.27 1.27)
					(thickness 0.15)
				)
				(justify mirror)
			)
		)
		(property "MPN" ""
			(at 0 0 90)
			(unlocked yes)
			(layer "B.Fab")
			(hide yes)
			(effects
				(font
					(size 1 1)
					(thickness 0.15)
				)
				(justify mirror)
			)
		)
		(property "Manufacturer" ""
			(at 0 0 90)
			(unlocked yes)
			(layer "B.Fab")
			(hide yes)
			(effects
				(font
					(size 1 1)
					(thickness 0.15)
				)
				(justify mirror)
			)
		)
		(property "Author" "Antmicro"
			(at 0 0 90)
			(unlocked yes)
			(layer "B.Fab")
			(hide yes)
			(effects
				(font
					(size 1 1)
					(thickness 0.15)
				)
				(justify mirror)
			)
		)
		(property "License" "Apache-2.0"
			(at 0 0 90)
			(unlocked yes)
			(layer "B.Fab")
			(hide yes)
			(effects
				(font
					(size 1 1)
					(thickness 0.15)
				)
				(justify mirror)
			)
		)
		(sheetname "/SoM_IO/")
		(sheetfile "som_io.kicad_sch")
		(attr exclude_from_pos_files exclude_from_bom)
		(fp_circle
			(center 0 0)
			(end 0.475 0)
			(stroke
				(width 0.05)
				(type default)
			)
			(fill no)
			(layer "B.CrtYd")
		)
		(fp_text user "${REFERENCE}"
			(at -0.4 -2.7 90)
			(layer "B.Fab")
			(effects
				(font
					(size 0.7 0.7)
					(thickness 0.15)
				)
				(justify left bottom mirror)
			)
		)
		(fp_text user "License: Apache-2.0"
			(at -0.4 -5.101 90)
			(layer "B.Fab")
			(effects
				(font
					(size 0.7 0.7)
					(thickness 0.15)
				)
				(justify left bottom mirror)
			)
		)
		(fp_text user "Author: Antmicro"
			(at -0.4 -3.901 90)
			(layer "B.Fab")
			(effects
				(font
					(size 0.7 0.7)
					(thickness 0.15)
				)
				(justify left bottom mirror)
			)
		)
		(pad "1" smd circle
			(at 0 0 270)
			(size 0.75 0.75)
			(layers "B.Cu" "B.Mask")
			(net 72 "/SoM_IO/I2S_{M.2}.SDOUT")
			(pinfunction "1")
			(pintype "passive")
		)
	)
	(footprint "antmicro-footprints:R_0603_1608Metric"
		(layer "B.Cu")
		(at 124.6 95.5)
		(descr "Resistor SMD 0603")
		(tags "resistor SMD 0603")
		(property "Reference" "R213"
			(at 1.2 -0.3 0)
			(layer "B.SilkS")
			(effects
				(font
					(size 0.7 0.7)
					(thickness 0.15)
				)
				(justify right top mirror)
			)
		)
		(property "Value" "R_0R_22.4A_0603"
			(at 0 -1.6 0)
			(layer "B.Fab")
			(effects
				(font
					(size 0.7 0.7)
					(thickness 0.15)
				)
				(justify right top mirror)
			)
		)
		(property "Datasheet" "https://fscdn.rohm.com/en/products/databook/datasheet/passive/resistor/chip_resistor/pmr-jpw-e.pdf"
			(at 0 0 0)
			(layer "B.Fab")
			(hide yes)
			(effects
				(font
					(size 1.27 1.27)
					(thickness 0.15)
				)
				(justify mirror)
			)
		)
		(property "Description" "SMD Chip Resistor"
			(at 0 0 0)
			(layer "B.Fab")
			(hide yes)
			(effects
				(font
					(size 1.27 1.27)
					(thickness 0.15)
				)
				(justify mirror)
			)
		)
		(property "Manufacturer" "ROHM Semiconductor"
			(at 0 0 180)
			(unlocked yes)
			(layer "B.Fab")
			(hide yes)
			(effects
				(font
					(size 1 1)
					(thickness 0.15)
				)
				(justify mirror)
			)
		)
		(property "MPN" "PMR03EZPJ000"
			(at 0 0 180)
			(unlocked yes)
			(layer "B.Fab")
			(hide yes)
			(effects
				(font
					(size 1 1)
					(thickness 0.15)
				)
				(justify mirror)
			)
		)
		(property "Val" "0R"
			(at 0 0 180)
			(unlocked yes)
			(layer "B.Fab")
			(hide yes)
			(effects
				(font
					(size 1 1)
					(thickness 0.15)
				)
				(justify mirror)
			)
		)
		(property "Author" "Antmicro"
			(at 0 0 180)
			(unlocked yes)
			(layer "B.Fab")
			(hide yes)
			(effects
				(font
					(size 1 1)
					(thickness 0.15)
				)
				(justify mirror)
			)
		)
		(property "License" "Apache-2.0"
			(at 0 0 180)
			(unlocked yes)
			(layer "B.Fab")
			(hide yes)
			(effects
				(font
					(size 1 1)
					(thickness 0.15)
				)
				(justify mirror)
			)
		)
		(property "Max. Curr." "22.4A"
			(at 0 0 180)
			(unlocked yes)
			(layer "B.Fab")
			(hide yes)
			(effects
				(font
					(size 1 1)
					(thickness 0.15)
				)
				(justify mirror)
			)
		)
		(property "Tolerance" "template_tolerance"
			(at 0 0 180)
			(unlocked yes)
			(layer "B.Fab")
			(hide yes)
			(effects
				(font
					(size 1 1)
					(thickness 0.15)
				)
				(justify mirror)
			)
		)
		(sheetname "/M.2/")
		(sheetfile "m2.kicad_sch")
		(attr smd)
		(fp_line
			(start -0.15 -0.4)
			(end 0.15 -0.4)
			(stroke
				(width 0.15)
				(type solid)
			)
			(layer "B.SilkS")
		)
		(fp_line
			(start -0.15 0.4)
			(end 0.15 0.4)
			(stroke
				(width 0.15)
				(type solid)
			)
			(layer "B.SilkS")
		)
		(fp_poly
			(pts
				(xy -1.25 0.65) (xy 1.25 0.65) (xy 1.25 -0.65) (xy -1.25 -0.65)
			)
			(stroke
				(width 0.05)
				(type solid)
			)
			(fill no)
			(layer "B.CrtYd")
		)
		(fp_poly
			(pts
				(xy -0.8 0.4) (xy 0.8 0.4) (xy 0.8 -0.4) (xy -0.8 -0.4)
			)
			(stroke
				(width 0.15)
				(type solid)
			)
			(fill no)
			(layer "B.Fab")
		)
		(fp_text user "${REFERENCE}"
			(at -1.25 -3.898 0)
			(layer "B.Fab")
			(effects
				(font
					(size 0.7 0.7)
					(thickness 0.15)
				)
				(justify right top mirror)
			)
		)
		(fp_text user "Author: Antmicro"
			(at -1.25 -4.9 0)
			(layer "B.Fab")
			(effects
				(font
					(size 0.7 0.7)
					(thickness 0.15)
				)
				(justify right top mirror)
			)
		)
		(fp_text user "License: Apache-2.0"
			(at -1.249999 -5.9 0)
			(layer "B.Fab")
			(effects
				(font
					(size 0.7 0.7)
					(thickness 0.15)
				)
				(justify right top mirror)
			)
		)
		(pad "1" smd roundrect
			(at -0.7 0)
			(size 0.8 1)
			(layers "B.Cu" "B.Mask" "B.Paste")
			(roundrect_rratio 0.2)
			(net 14 "/M.2/3V3_M2")
			(pintype "passive")
		)
		(pad "2" smd roundrect
			(at 0.7 0)
			(size 0.8 1)
			(layers "B.Cu" "B.Mask" "B.Paste")
			(roundrect_rratio 0.2)
			(net 2 "+3V3")
			(pintype "passive")
		)
	)
	(footprint "antmicro-footprints:TP_SMD_0.75mm"
		(layer "B.Cu")
		(at 91.17 62.68 180)
		(property "Reference" "TP122"
			(at -0.45 3.82 90)
			(layer "B.SilkS")
			(effects
				(font
					(size 0.7 0.7)
					(thickness 0.15)
				)
				(justify left bottom mirror)
			)
		)
		(property "Value" "TP_0.75mm_SMD"
			(at 0 -1.2 0)
			(layer "B.Fab")
			(effects
				(font
					(size 0.7 0.7)
					(thickness 0.15)
				)
				(justify left bottom mirror)
			)
		)
		(property "Description" "SMT test point"
			(at 0 0 0)
			(layer "B.Fab")
			(hide yes)
			(effects
				(font
					(size 1.27 1.27)
					(thickness 0.15)
				)
				(justify mirror)
			)
		)
		(property "MPN" ""
			(at 0 0 0)
			(unlocked yes)
			(layer "B.Fab")
			(hide yes)
			(effects
				(font
					(size 1 1)
					(thickness 0.15)
				)
				(justify mirror)
			)
		)
		(property "Manufacturer" ""
			(at 0 0 0)
			(unlocked yes)
			(layer "B.Fab")
			(hide yes)
			(effects
				(font
					(size 1 1)
					(thickness 0.15)
				)
				(justify mirror)
			)
		)
		(property "Author" "Antmicro"
			(at 0 0 0)
			(unlocked yes)
			(layer "B.Fab")
			(hide yes)
			(effects
				(font
					(size 1 1)
					(thickness 0.15)
				)
				(justify mirror)
			)
		)
		(property "License" "Apache-2.0"
			(at 0 0 0)
			(unlocked yes)
			(layer "B.Fab")
			(hide yes)
			(effects
				(font
					(size 1 1)
					(thickness 0.15)
				)
				(justify mirror)
			)
		)
		(sheetname "/SoM_Power/")
		(sheetfile "som_power.kicad_sch")
		(attr exclude_from_pos_files exclude_from_bom)
		(fp_circle
			(center 0 0)
			(end 0.475 0)
			(stroke
				(width 0.05)
				(type default)
			)
			(fill no)
			(layer "B.CrtYd")
		)
		(fp_text user "${REFERENCE}"
			(at -0.4 -2.7 0)
			(layer "B.Fab")
			(effects
				(font
					(size 0.7 0.7)
					(thickness 0.15)
				)
				(justify left bottom mirror)
			)
		)
		(fp_text user "License: Apache-2.0"
			(at -0.4 -5.101 0)
			(layer "B.Fab")
			(effects
				(font
					(size 0.7 0.7)
					(thickness 0.15)
				)
				(justify left bottom mirror)
			)
		)
		(fp_text user "Author: Antmicro"
			(at -0.4 -3.901 0)
			(layer "B.Fab")
			(effects
				(font
					(size 0.7 0.7)
					(thickness 0.15)
				)
				(justify left bottom mirror)
			)
		)
		(pad "1" smd circle
			(at 0 0 180)
			(size 0.75 0.75)
			(layers "B.Cu" "B.Mask")
			(net 1032 "/SoM_Power/~{FORCE_SHDN}")
			(pinfunction "1")
			(pintype "passive")
		)
	)
	(footprint "antmicro-footprints:TP_SMD_0.75mm"
		(layer "B.Cu")
		(at 197 123 90)
		(property "Reference" "TP6"
			(at 0.6 -2.4 0)
			(layer "B.SilkS")
			(effects
				(font
					(size 0.7 0.7)
					(thickness 0.15)
				)
				(justify right top mirror)
			)
		)
		(property "Value" "TP_0.75mm_SMD"
			(at 0 -1.2 90)
			(layer "B.Fab")
			(effects
				(font
					(size 0.7 0.7)
					(thickness 0.15)
				)
				(justify right top mirror)
			)
		)
		(property "Description" "SMT test point"
			(at 0 0 90)
			(layer "B.Fab")
			(hide yes)
			(effects
				(font
					(size 1.27 1.27)
					(thickness 0.15)
				)
				(justify mirror)
			)
		)
		(property "MPN" ""
			(at 0 0 270)
			(unlocked yes)
			(layer "B.Fab")
			(hide yes)
			(effects
				(font
					(size 1 1)
					(thickness 0.15)
				)
				(justify mirror)
			)
		)
		(property "Manufacturer" ""
			(at 0 0 270)
			(unlocked yes)
			(layer "B.Fab")
			(hide yes)
			(effects
				(font
					(size 1 1)
					(thickness 0.15)
				)
				(justify mirror)
			)
		)
		(property "Author" "Antmicro"
			(at 0 0 270)
			(unlocked yes)
			(layer "B.Fab")
			(hide yes)
			(effects
				(font
					(size 1 1)
					(thickness 0.15)
				)
				(justify mirror)
			)
		)
		(property "License" "Apache-2.0"
			(at 0 0 270)
			(unlocked yes)
			(layer "B.Fab")
			(hide yes)
			(effects
				(font
					(size 1 1)
					(thickness 0.15)
				)
				(justify mirror)
			)
		)
		(sheetname "/USB Hub/")
		(sheetfile "usb_hub.kicad_sch")
		(attr exclude_from_pos_files exclude_from_bom)
		(fp_circle
			(center 0 0)
			(end 0.475 0)
			(stroke
				(width 0.05)
				(type default)
			)
			(fill no)
			(layer "B.CrtYd")
		)
		(fp_text user "Author: Antmicro"
			(at -0.4 -3.901 90)
			(layer "B.Fab")
			(effects
				(font
					(size 0.7 0.7)
					(thickness 0.15)
				)
				(justify right top mirror)
			)
		)
		(fp_text user "${REFERENCE}"
			(at -0.4 -2.7 90)
			(layer "B.Fab")
			(effects
				(font
					(size 0.7 0.7)
					(thickness 0.15)
				)
				(justify right top mirror)
			)
		)
		(fp_text user "License: Apache-2.0"
			(at -0.4 -5.101 90)
			(layer "B.Fab")
			(effects
				(font
					(size 0.7 0.7)
					(thickness 0.15)
				)
				(justify right top mirror)
			)
		)
		(pad "1" smd circle
			(at 0 0 90)
			(size 0.75 0.75)
			(layers "B.Cu" "B.Mask")
			(net 910 "/USB Hub/PRT_CTL3")
			(pinfunction "1")
			(pintype "passive")
		)
	)
	(footprint "antmicro-footprints:R_0402_1005Metric"
		(layer "B.Cu")
		(at 63.1 70.4 90)
		(descr "Resistor SMD 0402")
		(tags "resistor SMD 0402")
		(property "Reference" "R184"
			(at -2.2 3.7 90)
			(layer "B.SilkS")
			(effects
				(font
					(size 0.7 0.7)
					(thickness 0.15)
				)
				(justify right top mirror)
			)
		)
		(property "Value" "R_0R_0402"
			(at -1.011843 -1.772047 90)
			(layer "B.Fab")
			(effects
				(font
					(size 0.7 0.7)
					(thickness 0.15)
				)
				(justify right top mirror)
			)
		)
		(property "Datasheet" "https://industrial.panasonic.com/cdbs/www-data/pdf/RDA0000/AOA0000C301.pdf"
			(at 0 0 90)
			(layer "B.Fab")
			(hide yes)
			(effects
				(font
					(size 1.27 1.27)
					(thickness 0.15)
				)
				(justify mirror)
			)
		)
		(property "Description" "SMD Chip Resistor, Jumper, 0 ohm, 100 mW, 0402 [1005 Metric], Thick Film, General Purpose"
			(at 0 0 90)
			(layer "B.Fab")
			(hide yes)
			(effects
				(font
					(size 1.27 1.27)
					(thickness 0.15)
				)
				(justify mirror)
			)
		)
		(property "MPN" "ERJ2GE0R00X"
			(at 0 0 270)
			(unlocked yes)
			(layer "B.Fab")
			(hide yes)
			(effects
				(font
					(size 1 1)
					(thickness 0.15)
				)
				(justify mirror)
			)
		)
		(property "Manufacturer" "Panasonic"
			(at 0 0 270)
			(unlocked yes)
			(layer "B.Fab")
			(hide yes)
			(effects
				(font
					(size 1 1)
					(thickness 0.15)
				)
				(justify mirror)
			)
		)
		(property "License" "Apache-2.0"
			(at 0 0 270)
			(unlocked yes)
			(layer "B.Fab")
			(hide yes)
			(effects
				(font
					(size 1 1)
					(thickness 0.15)
				)
				(justify mirror)
			)
		)
		(property "Author" "Antmicro"
			(at 0 0 270)
			(unlocked yes)
			(layer "B.Fab")
			(hide yes)
			(effects
				(font
					(size 1 1)
					(thickness 0.15)
				)
				(justify mirror)
			)
		)
		(property "Val" "0R"
			(at 0 0 270)
			(unlocked yes)
			(layer "B.Fab")
			(hide yes)
			(effects
				(font
					(size 1 1)
					(thickness 0.15)
				)
				(justify mirror)
			)
		)
		(property "Tolerance" "~"
			(at 0 0 270)
			(unlocked yes)
			(layer "B.Fab")
			(hide yes)
			(effects
				(font
					(size 1 1)
					(thickness 0.15)
				)
				(justify mirror)
			)
		)
		(property "Current" "1A"
			(at 0 0 270)
			(unlocked yes)
			(layer "B.Fab")
			(hide yes)
			(effects
				(font
					(size 1 1)
					(thickness 0.15)
				)
				(justify mirror)
			)
		)
		(sheetname "/CSI/")
		(sheetfile "csi.kicad_sch")
		(attr smd)
		(fp_rect
			(start -0.925 0.47)
			(end 0.925 -0.47)
			(stroke
				(width 0.05)
				(type default)
			)
			(fill no)
			(layer "B.CrtYd")
		)
		(fp_rect
			(start -0.5 0.25)
			(end 0.5 -0.25)
			(stroke
				(width 0.15)
				(type solid)
			)
			(fill no)
			(layer "B.Fab")
		)
		(fp_text user "Author: Antmicro"
			(at -0.95 -4.169 90)
			(layer "B.Fab")
			(effects
				(font
					(size 0.7 0.7)
					(thickness 0.15)
				)
				(justify right top mirror)
			)
		)
		(fp_text user "${REFERENCE}"
			(at -0.95 -3.168 90)
			(layer "B.Fab")
			(effects
				(font
					(size 0.7 0.7)
					(thickness 0.15)
				)
				(justify right top mirror)
			)
		)
		(fp_text user "License: Apache-2.0"
			(at -0.95 -5.169 90)
			(layer "B.Fab")
			(effects
				(font
					(size 0.7 0.7)
					(thickness 0.15)
				)
				(justify right top mirror)
			)
		)
		(pad "1" smd roundrect
			(at -0.48 0 90)
			(size 0.59 0.64)
			(layers "B.Cu" "B.Mask" "B.Paste")
			(roundrect_rratio 0.25)
			(net 1377 "Net-(J11-Pad40)")
			(pintype "passive")
		)
		(pad "2" smd roundrect
			(at 0.48 0 90)
			(size 0.59 0.64)
			(layers "B.Cu" "B.Mask" "B.Paste")
			(roundrect_rratio 0.25)
			(net 985 "/CSI/SCL_CAM0")
			(pintype "passive")
		)
	)
	(footprint "antmicro-footprints:R_0402_1005Metric"
		(layer "B.Cu")
		(at 105.35 66.01 180)
		(descr "Resistor SMD 0402")
		(tags "resistor SMD 0402")
		(property "Reference" "R5"
			(at -0.78 -1.45 0)
			(layer "B.SilkS")
			(effects
				(font
					(size 0.7 0.7)
					(thickness 0.15)
				)
				(justify left bottom mirror)
			)
		)
		(property "Value" "R_49R9_0402"
			(at -1.011843 -1.772047 0)
			(layer "B.Fab")
			(effects
				(font
					(size 0.7 0.7)
					(thickness 0.15)
				)
				(justify left bottom mirror)
			)
		)
		(property "Datasheet" "https://www.bourns.com/docs/product-datasheets/cr.pdf"
			(at 0 0 0)
			(layer "B.Fab")
			(hide yes)
			(effects
				(font
					(size 1.27 1.27)
					(thickness 0.15)
				)
				(justify mirror)
			)
		)
		(property "Description" "SMD Chip Resistor, 49.9 ohm, ± 1%, 62.5 mW, 0402 [1005 Metric], Thick Film, General Purpose"
			(at 0 0 0)
			(layer "B.Fab")
			(hide yes)
			(effects
				(font
					(size 1.27 1.27)
					(thickness 0.15)
				)
				(justify mirror)
			)
		)
		(property "MPN" "CR0402-FX-49R9GLF"
			(at 0 0 0)
			(unlocked yes)
			(layer "B.Fab")
			(hide yes)
			(effects
				(font
					(size 1 1)
					(thickness 0.15)
				)
				(justify mirror)
			)
		)
		(property "Manufacturer" "Bourns"
			(at 0 0 0)
			(unlocked yes)
			(layer "B.Fab")
			(hide yes)
			(effects
				(font
					(size 1 1)
					(thickness 0.15)
				)
				(justify mirror)
			)
		)
		(property "License" "Apache-2.0"
			(at 0 0 0)
			(unlocked yes)
			(layer "B.Fab")
			(hide yes)
			(effects
				(font
					(size 1 1)
					(thickness 0.15)
				)
				(justify mirror)
			)
		)
		(property "Author" "Antmicro"
			(at 0 0 0)
			(unlocked yes)
			(layer "B.Fab")
			(hide yes)
			(effects
				(font
					(size 1 1)
					(thickness 0.15)
				)
				(justify mirror)
			)
		)
		(property "Val" "49R9"
			(at 0 0 0)
			(unlocked yes)
			(layer "B.Fab")
			(hide yes)
			(effects
				(font
					(size 1 1)
					(thickness 0.15)
				)
				(justify mirror)
			)
		)
		(property "Tolerance" "1%"
			(at 0 0 0)
			(unlocked yes)
			(layer "B.Fab")
			(hide yes)
			(effects
				(font
					(size 1 1)
					(thickness 0.15)
				)
				(justify mirror)
			)
		)
		(sheetname "/SoM_IO2/")
		(sheetfile "som_io2.kicad_sch")
		(attr smd)
		(fp_rect
			(start -0.925 0.47)
			(end 0.925 -0.47)
			(stroke
				(width 0.05)
				(type default)
			)
			(fill no)
			(layer "B.CrtYd")
		)
		(fp_rect
			(start -0.5 0.25)
			(end 0.5 -0.25)
			(stroke
				(width 0.15)
				(type solid)
			)
			(fill no)
			(layer "B.Fab")
		)
		(fp_text user "License: Apache-2.0"
			(at -0.95 -5.169 0)
			(layer "B.Fab")
			(effects
				(font
					(size 0.7 0.7)
					(thickness 0.15)
				)
				(justify left bottom mirror)
			)
		)
		(fp_text user "Author: Antmicro"
			(at -0.95 -4.169 0)
			(layer "B.Fab")
			(effects
				(font
					(size 0.7 0.7)
					(thickness 0.15)
				)
				(justify left bottom mirror)
			)
		)
		(fp_text user "${REFERENCE}"
			(at -0.95 -3.168 0)
			(layer "B.Fab")
			(effects
				(font
					(size 0.7 0.7)
					(thickness 0.15)
				)
				(justify left bottom mirror)
			)
		)
		(pad "1" smd roundrect
			(at -0.48 0 180)
			(size 0.59 0.64)
			(layers "B.Cu" "B.Mask" "B.Paste")
			(roundrect_rratio 0.25)
			(net 1 "GND")
			(pintype "passive")
		)
		(pad "2" smd roundrect
			(at 0.48 0 180)
			(size 0.59 0.64)
			(layers "B.Cu" "B.Mask" "B.Paste")
			(roundrect_rratio 0.25)
			(net 169 "/SoM_IO2/SFI_REFCLK+")
			(pintype "passive")
		)
	)
	(footprint "antmicro-footprints:R_0402_1005Metric"
		(layer "B.Cu")
		(at 124.6 110.8)
		(descr "Resistor SMD 0402")
		(tags "resistor SMD 0402")
		(property "Reference" "R212"
			(at 3.9 -0.47 0)
			(layer "B.SilkS")
			(effects
				(font
					(size 0.7 0.7)
					(thickness 0.15)
				)
				(justify left top mirror)
			)
		)
		(property "Value" "R_0R_0402"
			(at -1.011843 -1.772046 0)
			(layer "B.Fab")
			(effects
				(font
					(size 0.7 0.7)
					(thickness 0.15)
				)
				(justify right top mirror)
			)
		)
		(property "Datasheet" "https://industrial.panasonic.com/cdbs/www-data/pdf/RDA0000/AOA0000C301.pdf"
			(at 0 0 0)
			(layer "B.Fab")
			(hide yes)
			(effects
				(font
					(size 1.27 1.27)
					(thickness 0.15)
				)
				(justify mirror)
			)
		)
		(property "Description" "SMD Chip Resistor, Jumper, 0 ohm, 100 mW, 0402 [1005 Metric], Thick Film, General Purpose"
			(at 0 0 0)
			(layer "B.Fab")
			(hide yes)
			(effects
				(font
					(size 1.27 1.27)
					(thickness 0.15)
				)
				(justify mirror)
			)
		)
		(property "MPN" "ERJ2GE0R00X"
			(at 0 0 180)
			(unlocked yes)
			(layer "B.Fab")
			(hide yes)
			(effects
				(font
					(size 1 1)
					(thickness 0.15)
				)
				(justify mirror)
			)
		)
		(property "Manufacturer" "Panasonic"
			(at 0 0 180)
			(unlocked yes)
			(layer "B.Fab")
			(hide yes)
			(effects
				(font
					(size 1 1)
					(thickness 0.15)
				)
				(justify mirror)
			)
		)
		(property "License" "Apache-2.0"
			(at 0 0 180)
			(unlocked yes)
			(layer "B.Fab")
			(hide yes)
			(effects
				(font
					(size 1 1)
					(thickness 0.15)
				)
				(justify mirror)
			)
		)
		(property "Val" "0R"
			(at 0 0 180)
			(unlocked yes)
			(layer "B.Fab")
			(hide yes)
			(effects
				(font
					(size 1 1)
					(thickness 0.15)
				)
				(justify mirror)
			)
		)
		(property "Tolerance" "~"
			(at 0 0 180)
			(unlocked yes)
			(layer "B.Fab")
			(hide yes)
			(effects
				(font
					(size 1 1)
					(thickness 0.15)
				)
				(justify mirror)
			)
		)
		(property "Current" "1A"
			(at 0 0 180)
			(unlocked yes)
			(layer "B.Fab")
			(hide yes)
			(effects
				(font
					(size 1 1)
					(thickness 0.15)
				)
				(justify mirror)
			)
		)
		(property "Author" "Antmicro"
			(at 0 0 180)
			(unlocked yes)
			(layer "B.Fab")
			(hide yes)
			(effects
				(font
					(size 1 1)
					(thickness 0.15)
				)
				(justify mirror)
			)
		)
		(property "Public" "False"
			(at 0 0 180)
			(unlocked yes)
			(layer "B.Fab")
			(hide yes)
			(effects
				(font
					(size 1 1)
					(thickness 0.15)
				)
				(justify mirror)
			)
		)
		(sheetname "/M.2/")
		(sheetfile "m2.kicad_sch")
		(attr smd)
		(fp_poly
			(pts
				(xy -0.925 0.47) (xy 0.925 0.47) (xy 0.925 -0.47) (xy -0.925 -0.47)
			)
			(stroke
				(width 0.05)
				(type default)
			)
			(fill no)
			(layer "B.CrtYd")
		)
		(fp_poly
			(pts
				(xy -0.5 0.25) (xy 0.5 0.25) (xy 0.5 -0.25) (xy -0.5 -0.25)
			)
			(stroke
				(width 0.15)
				(type solid)
			)
			(fill no)
			(layer "B.Fab")
		)
		(fp_text user "Author: Antmicro"
			(at -0.95 -4.169 0)
			(layer "B.Fab")
			(effects
				(font
					(size 0.7 0.7)
					(thickness 0.15)
				)
				(justify right top mirror)
			)
		)
		(fp_text user "License: Apache-2.0"
			(at -0.949999 -5.169 0)
			(layer "B.Fab")
			(effects
				(font
					(size 0.7 0.7)
					(thickness 0.15)
				)
				(justify right top mirror)
			)
		)
		(fp_text user "${REFERENCE}"
			(at -0.95 -3.168 0)
			(layer "B.Fab")
			(effects
				(font
					(size 0.7 0.7)
					(thickness 0.15)
				)
				(justify right top mirror)
			)
		)
		(pad "1" smd roundrect
			(at -0.48 0)
			(size 0.59 0.64)
			(layers "B.Cu" "B.Mask" "B.Paste")
			(roundrect_rratio 0.25)
			(net 224 "/M.2/M2_M_SUSCLK")
			(pintype "passive")
		)
		(pad "2" smd roundrect
			(at 0.48 0)
			(size 0.59 0.64)
			(layers "B.Cu" "B.Mask" "B.Paste")
			(roundrect_rratio 0.25)
			(net 1005 "/M.2/SUSCLK")
			(pintype "passive")
		)
	)
	(footprint "antmicro-footprints:SOT-23-5"
		(layer "B.Cu")
		(at 212.12 70.66 90)
		(property "Reference" "U32"
			(at 1.96 1.08 180)
			(layer "B.SilkS")
			(effects
				(font
					(size 0.7 0.7)
					(thickness 0.15)
				)
				(justify left bottom mirror)
			)
		)
		(property "Value" "NCP718BSN330T1G"
			(at 0.002 -2.799 270)
			(layer "B.Fab")
			(effects
				(font
					(size 0.7 0.7)
					(thickness 0.15)
				)
				(justify left bottom mirror)
			)
		)
		(property "Datasheet" "https://www.mouser.com/datasheet/2/308/NCP718_D-1224359.pdf"
			(at 0 0 270)
			(layer "B.Fab")
			(hide yes)
			(effects
				(font
					(size 1.27 1.27)
					(thickness 0.15)
				)
				(justify mirror)
			)
		)
		(property "Description" "Linear Voltage Regulator IC Positive Fixed 1 Output 300mA TSOT-23-5"
			(at 0 0 270)
			(layer "B.Fab")
			(hide yes)
			(effects
				(font
					(size 1.27 1.27)
					(thickness 0.15)
				)
				(justify mirror)
			)
		)
		(property "MPN" "NCP718BSN330T1G"
			(at 0 0 90)
			(unlocked yes)
			(layer "B.Fab")
			(hide yes)
			(effects
				(font
					(size 1 1)
					(thickness 0.15)
				)
				(justify mirror)
			)
		)
		(property "Manufacturer" "ON Semiconductor"
			(at 0 0 90)
			(unlocked yes)
			(layer "B.Fab")
			(hide yes)
			(effects
				(font
					(size 1 1)
					(thickness 0.15)
				)
				(justify mirror)
			)
		)
		(property "Author" "Antmicro"
			(at 0 0 90)
			(unlocked yes)
			(layer "B.Fab")
			(hide yes)
			(effects
				(font
					(size 1 1)
					(thickness 0.15)
				)
				(justify mirror)
			)
		)
		(property "License" "Apache-2.0"
			(at 0 0 90)
			(unlocked yes)
			(layer "B.Fab")
			(hide yes)
			(effects
				(font
					(size 1 1)
					(thickness 0.15)
				)
				(justify mirror)
			)
		)
		(sheetname "/USB Debug, PD/")
		(sheetfile "usb_debug_pd.kicad_sch")
		(attr smd)
		(fp_line
			(start -0.55 -1.6)
			(end -0.85 -1.6)
			(stroke
				(width 0.15)
				(type solid)
			)
			(layer "B.SilkS")
		)
		(fp_line
			(start -0.85 -1.6)
			(end -0.85 -1.301)
			(stroke
				(width 0.15)
				(type solid)
			)
			(layer "B.SilkS")
		)
		(fp_line
			(start 0.8 -1.599)
			(end 0.549 -1.599)
			(stroke
				(width 0.15)
				(type solid)
			)
			(layer "B.SilkS")
		)
		(fp_line
			(start 0.8 -1.3)
			(end 0.8 -1.599)
			(stroke
				(width 0.15)
				(type solid)
			)
			(layer "B.SilkS")
		)
		(fp_line
			(start 0.8 -0.55)
			(end 0.8 0.55)
			(stroke
				(width 0.15)
				(type solid)
			)
			(layer "B.SilkS")
		)
		(fp_line
			(start 0.8 1.3)
			(end 0.8 1.6)
			(stroke
				(width 0.15)
				(type solid)
			)
			(layer "B.SilkS")
		)
		(fp_line
			(start 0.8 1.6)
			(end 0.5 1.6)
			(stroke
				(width 0.15)
				(type solid)
			)
			(layer "B.SilkS")
		)
		(fp_line
			(start -0.8 1.6)
			(end -0.8 1.3)
			(stroke
				(width 0.15)
				(type solid)
			)
			(layer "B.SilkS")
		)
		(fp_line
			(start -0.8 1.6)
			(end -0.5 1.6)
			(stroke
				(width 0.15)
				(type solid)
			)
			(layer "B.SilkS")
		)
		(fp_circle
			(center -1.25 1.5)
			(end -1.2 1.5)
			(stroke
				(width 0.15)
				(type solid)
			)
			(fill yes)
			(layer "B.SilkS")
		)
		(fp_rect
			(start 1.9 1.76)
			(end -1.9 -1.75)
			(stroke
				(width 0.05)
				(type solid)
			)
			(fill no)
			(layer "B.CrtYd")
		)
		(fp_line
			(start -0.398 1.526)
			(end -0.874 1.05)
			(stroke
				(width 0.15)
				(type solid)
			)
			(layer "B.Fab")
		)
		(fp_rect
			(start 0.874 -1.523)
			(end -0.873 1.525)
			(stroke
				(width 0.15)
				(type solid)
			)
			(fill no)
			(layer "B.Fab")
		)
		(fp_text user "Author: Antmicro"
			(at -1.898 -5.499 270)
			(layer "B.Fab")
			(effects
				(font
					(size 0.7 0.7)
					(thickness 0.15)
				)
				(justify left bottom mirror)
			)
		)
		(fp_text user "License: Apache-2.0"
			(at -1.898 -6.7 270)
			(layer "B.Fab")
			(effects
				(font
					(size 0.7 0.7)
					(thickness 0.15)
				)
				(justify left bottom mirror)
			)
		)
		(fp_text user "${REFERENCE}"
			(at -1.898 -4.299 270)
			(layer "B.Fab")
			(effects
				(font
					(size 0.7 0.7)
					(thickness 0.15)
				)
				(justify left bottom mirror)
			)
		)
		(pad "1" smd rect
			(at -1.351 0.951 180)
			(size 0.55 1)
			(layers "B.Cu" "B.Mask" "B.Paste")
			(net 176 "/USB Debug, PD/USBC0_VBUS")
			(pinfunction "VIN")
			(pintype "passive")
		)
		(pad "2" smd rect
			(at -1.351 0 180)
			(size 0.55 1)
			(layers "B.Cu" "B.Mask" "B.Paste")
			(net 1 "GND")
			(pinfunction "GND")
			(pintype "passive")
		)
		(pad "3" smd rect
			(at -1.351 -0.949 180)
			(size 0.55 1)
			(layers "B.Cu" "B.Mask" "B.Paste")
			(net 176 "/USB Debug, PD/USBC0_VBUS")
			(pinfunction "EN")
			(pintype "passive")
		)
		(pad "4" smd rect
			(at 1.35 -0.949 180)
			(size 0.55 1)
			(layers "B.Cu" "B.Mask" "B.Paste")
			(net 1323 "unconnected-(U32-NC-Pad4)")
			(pinfunction "NC")
			(pintype "no_connect")
		)
		(pad "5" smd rect
			(at 1.35 0.951 180)
			(size 0.55 1)
			(layers "B.Cu" "B.Mask" "B.Paste")
			(net 334 "/USB Debug, PD/FTDI_3V3")
			(pinfunction "VOUT")
			(pintype "passive")
		)
	)
	(footprint "antmicro-footprints:R_0402_1005Metric"
		(layer "B.Cu")
		(at 130.11 151.2 -90)
		(descr "Resistor SMD 0402")
		(tags "resistor SMD 0402")
		(property "Reference" "R232"
			(at -1.1 -6.29 90)
			(layer "B.SilkS")
			(effects
				(font
					(size 0.7 0.7)
					(thickness 0.15)
				)
				(justify left bottom mirror)
			)
		)
		(property "Value" "R_10k_0402"
			(at -1.011843 -1.772047 90)
			(layer "B.Fab")
			(effects
				(font
					(size 0.7 0.7)
					(thickness 0.15)
				)
				(justify left bottom mirror)
			)
		)
		(property "Datasheet" "https://www.bourns.com/docs/product-datasheets/cr.pdf"
			(at 0 0 90)
			(layer "B.Fab")
			(hide yes)
			(effects
				(font
					(size 1.27 1.27)
					(thickness 0.15)
				)
				(justify mirror)
			)
		)
		(property "Description" "SMD Chip Resistor, 10 kohm, ± 1%, 62.5 mW, 0402 [1005 Metric], Thick Film, General Purpose"
			(at 0 0 90)
			(layer "B.Fab")
			(hide yes)
			(effects
				(font
					(size 1.27 1.27)
					(thickness 0.15)
				)
				(justify mirror)
			)
		)
		(property "MPN" "CR0402-FX-1002GLF"
			(at 0 0 90)
			(unlocked yes)
			(layer "B.Fab")
			(hide yes)
			(effects
				(font
					(size 1 1)
					(thickness 0.15)
				)
				(justify mirror)
			)
		)
		(property "Manufacturer" "Bourns"
			(at 0 0 90)
			(unlocked yes)
			(layer "B.Fab")
			(hide yes)
			(effects
				(font
					(size 1 1)
					(thickness 0.15)
				)
				(justify mirror)
			)
		)
		(property "License" "Apache-2.0"
			(at 0 0 90)
			(unlocked yes)
			(layer "B.Fab")
			(hide yes)
			(effects
				(font
					(size 1 1)
					(thickness 0.15)
				)
				(justify mirror)
			)
		)
		(property "Author" "Antmicro"
			(at 0 0 90)
			(unlocked yes)
			(layer "B.Fab")
			(hide yes)
			(effects
				(font
					(size 1 1)
					(thickness 0.15)
				)
				(justify mirror)
			)
		)
		(property "Val" "10k"
			(at 0 0 90)
			(unlocked yes)
			(layer "B.Fab")
			(hide yes)
			(effects
				(font
					(size 1 1)
					(thickness 0.15)
				)
				(justify mirror)
			)
		)
		(property "Tolerance" "1%"
			(at 0 0 90)
			(unlocked yes)
			(layer "B.Fab")
			(hide yes)
			(effects
				(font
					(size 1 1)
					(thickness 0.15)
				)
				(justify mirror)
			)
		)
		(sheetname "/Peripherals/")
		(sheetfile "peripherals.kicad_sch")
		(attr smd)
		(fp_rect
			(start -0.925 0.47)
			(end 0.925 -0.47)
			(stroke
				(width 0.05)
				(type default)
			)
			(fill no)
			(layer "B.CrtYd")
		)
		(fp_rect
			(start -0.5 0.25)
			(end 0.5 -0.25)
			(stroke
				(width 0.15)
				(type solid)
			)
			(fill no)
			(layer "B.Fab")
		)
		(fp_text user "License: Apache-2.0"
			(at -0.95 -5.169 90)
			(layer "B.Fab")
			(effects
				(font
					(size 0.7 0.7)
					(thickness 0.15)
				)
				(justify left bottom mirror)
			)
		)
		(fp_text user "${REFERENCE}"
			(at -0.95 -3.168 90)
			(layer "B.Fab")
			(effects
				(font
					(size 0.7 0.7)
					(thickness 0.15)
				)
				(justify left bottom mirror)
			)
		)
		(fp_text user "Author: Antmicro"
			(at -0.95 -4.169 90)
			(layer "B.Fab")
			(effects
				(font
					(size 0.7 0.7)
					(thickness 0.15)
				)
				(justify left bottom mirror)
			)
		)
		(pad "1" smd roundrect
			(at -0.48 0 270)
			(size 0.59 0.64)
			(layers "B.Cu" "B.Mask" "B.Paste")
			(roundrect_rratio 0.25)
			(net 1089 "Net-(Q1-D)")
			(pintype "passive")
		)
		(pad "2" smd roundrect
			(at 0.48 0 270)
			(size 0.59 0.64)
			(layers "B.Cu" "B.Mask" "B.Paste")
			(roundrect_rratio 0.25)
			(net 2 "+3V3")
			(pintype "passive")
		)
	)
	(footprint "antmicro-footprints:C_0402_1005Metric"
		(layer "B.Cu")
		(at 225.521 77.41 90)
		(descr "Capacitor SMD 0402")
		(tags "capacitor SMD 0402")
		(property "Reference" "C150"
			(at 1.01 -0.321 90)
			(layer "B.SilkS")
			(effects
				(font
					(size 0.7 0.7)
					(thickness 0.15)
				)
				(justify right top mirror)
			)
		)
		(property "Value" "C_47p_0402"
			(at -1.022927 -2.155213 90)
			(layer "B.Fab")
			(effects
				(font
					(size 0.7 0.7)
					(thickness 0.15)
				)
				(justify right top mirror)
			)
		)
		(property "Datasheet" "https://www.kemet.com/en/us/capacitors/product/C0402C470J5GACTU.html"
			(at 0 0 90)
			(layer "B.Fab")
			(hide yes)
			(effects
				(font
					(size 1.27 1.27)
					(thickness 0.15)
				)
				(justify mirror)
			)
		)
		(property "Description" "SMD Multilayer Ceramic Capacitor, 47 pF, 50 V, 0402 [1005 Metric], ± 5%, C0G / NP0, C Series KEMET"
			(at 0 0 90)
			(layer "B.Fab")
			(hide yes)
			(effects
				(font
					(size 1.27 1.27)
					(thickness 0.15)
				)
				(justify mirror)
			)
		)
		(property "MPN" "C0402C470J5GACTU"
			(at 0 0 270)
			(unlocked yes)
			(layer "B.Fab")
			(hide yes)
			(effects
				(font
					(size 1 1)
					(thickness 0.15)
				)
				(justify mirror)
			)
		)
		(property "Manufacturer" "KEMET"
			(at 0 0 270)
			(unlocked yes)
			(layer "B.Fab")
			(hide yes)
			(effects
				(font
					(size 1 1)
					(thickness 0.15)
				)
				(justify mirror)
			)
		)
		(property "License" "Apache-2.0"
			(at 0 0 270)
			(unlocked yes)
			(layer "B.Fab")
			(hide yes)
			(effects
				(font
					(size 1 1)
					(thickness 0.15)
				)
				(justify mirror)
			)
		)
		(property "Author" "Antmicro"
			(at 0 0 270)
			(unlocked yes)
			(layer "B.Fab")
			(hide yes)
			(effects
				(font
					(size 1 1)
					(thickness 0.15)
				)
				(justify mirror)
			)
		)
		(property "Val" "47p"
			(at 0 0 270)
			(unlocked yes)
			(layer "B.Fab")
			(hide yes)
			(effects
				(font
					(size 1 1)
					(thickness 0.15)
				)
				(justify mirror)
			)
		)
		(property "Voltage" ""
			(at 0 0 270)
			(unlocked yes)
			(layer "B.Fab")
			(hide yes)
			(effects
				(font
					(size 1 1)
					(thickness 0.15)
				)
				(justify mirror)
			)
		)
		(property "Dielectric" "C0G"
			(at 0 0 270)
			(unlocked yes)
			(layer "B.Fab")
			(hide yes)
			(effects
				(font
					(size 1 1)
					(thickness 0.15)
				)
				(justify mirror)
			)
		)
		(sheetname "/USB Debug, PD/")
		(sheetfile "usb_debug_pd.kicad_sch")
		(attr smd)
		(fp_rect
			(start -0.925 0.47)
			(end 0.925 -0.47)
			(stroke
				(width 0.05)
				(type default)
			)
			(fill no)
			(layer "B.CrtYd")
		)
		(fp_line
			(start 0.504 -0.248)
			(end -0.494 -0.248)
			(stroke
				(width 0.15)
				(type solid)
			)
			(layer "B.Fab")
		)
		(fp_line
			(start -0.494 -0.248)
			(end -0.494 0.25)
			(stroke
				(width 0.15)
				(type solid)
			)
			(layer "B.Fab")
		)
		(fp_line
			(start 0.504 0.25)
			(end 0.504 -0.248)
			(stroke
				(width 0.15)
				(type solid)
			)
			(layer "B.Fab")
		)
		(fp_line
			(start -0.494 0.25)
			(end 0.504 0.25)
			(stroke
				(width 0.15)
				(type solid)
			)
			(layer "B.Fab")
		)
		(fp_text user "${REFERENCE}"
			(at -0.939 -4.599 90)
			(layer "B.Fab")
			(effects
				(font
					(size 0.7 0.7)
					(thickness 0.15)
				)
				(justify right top mirror)
			)
		)
		(fp_text user "License: Apache-2.0"
			(at -0.939 -5.799 90)
			(layer "B.Fab")
			(effects
				(font
					(size 0.7 0.7)
					(thickness 0.15)
				)
				(justify right top mirror)
			)
		)
		(fp_text user "Author: Antmicro"
			(at -0.939 -3.399 90)
			(layer "B.Fab")
			(effects
				(font
					(size 0.7 0.7)
					(thickness 0.15)
				)
				(justify right top mirror)
			)
		)
		(pad "1" smd roundrect
			(at -0.48 0 90)
			(size 0.59 0.64)
			(layers "B.Cu" "B.Mask" "B.Paste")
			(roundrect_rratio 0.25)
			(net 489 "/USB Debug, PD/USBC0_D_P")
			(pintype "passive")
		)
		(pad "2" smd roundrect
			(at 0.48 0 90)
			(size 0.59 0.64)
			(layers "B.Cu" "B.Mask" "B.Paste")
			(roundrect_rratio 0.25)
			(net 1 "GND")
			(pintype "passive")
		)
	)
	(footprint "antmicro-footprints:TP_SMD_0.75mm"
		(layer "B.Cu")
		(at 138.85 63.85 -90)
		(property "Reference" "TP93"
			(at 0.45 -0.45 90)
			(layer "B.SilkS")
			(effects
				(font
					(size 0.7 0.7)
					(thickness 0.15)
				)
				(justify left bottom mirror)
			)
		)
		(property "Value" "TP_0.75mm_SMD"
			(at 0 -1.2 90)
			(layer "B.Fab")
			(effects
				(font
					(size 0.7 0.7)
					(thickness 0.15)
				)
				(justify left bottom mirror)
			)
		)
		(property "Description" "SMT test point"
			(at 0 0 90)
			(layer "B.Fab")
			(hide yes)
			(effects
				(font
					(size 1.27 1.27)
					(thickness 0.15)
				)
				(justify mirror)
			)
		)
		(property "MPN" ""
			(at 0 0 90)
			(unlocked yes)
			(layer "B.Fab")
			(hide yes)
			(effects
				(font
					(size 1 1)
					(thickness 0.15)
				)
				(justify mirror)
			)
		)
		(property "Manufacturer" ""
			(at 0 0 90)
			(unlocked yes)
			(layer "B.Fab")
			(hide yes)
			(effects
				(font
					(size 1 1)
					(thickness 0.15)
				)
				(justify mirror)
			)
		)
		(property "Author" "Antmicro"
			(at 0 0 90)
			(unlocked yes)
			(layer "B.Fab")
			(hide yes)
			(effects
				(font
					(size 1 1)
					(thickness 0.15)
				)
				(justify mirror)
			)
		)
		(property "License" "Apache-2.0"
			(at 0 0 90)
			(unlocked yes)
			(layer "B.Fab")
			(hide yes)
			(effects
				(font
					(size 1 1)
					(thickness 0.15)
				)
				(justify mirror)
			)
		)
		(sheetname "/Peripherals/")
		(sheetfile "peripherals.kicad_sch")
		(attr exclude_from_pos_files exclude_from_bom)
		(fp_circle
			(center 0 0)
			(end 0.475 0)
			(stroke
				(width 0.05)
				(type default)
			)
			(fill no)
			(layer "B.CrtYd")
		)
		(fp_text user "${REFERENCE}"
			(at -0.4 -2.7 90)
			(layer "B.Fab")
			(effects
				(font
					(size 0.7 0.7)
					(thickness 0.15)
				)
				(justify left bottom mirror)
			)
		)
		(fp_text user "License: Apache-2.0"
			(at -0.4 -5.101 90)
			(layer "B.Fab")
			(effects
				(font
					(size 0.7 0.7)
					(thickness 0.15)
				)
				(justify left bottom mirror)
			)
		)
		(fp_text user "Author: Antmicro"
			(at -0.4 -3.901 90)
			(layer "B.Fab")
			(effects
				(font
					(size 0.7 0.7)
					(thickness 0.15)
				)
				(justify left bottom mirror)
			)
		)
		(pad "1" smd circle
			(at 0 0 270)
			(size 0.75 0.75)
			(layers "B.Cu" "B.Mask")
			(net 838 "/Peripherals/I2C_CONN1_3V3")
			(pinfunction "1")
			(pintype "passive")
		)
	)
	(footprint "antmicro-footprints:R_0402_1005Metric"
		(layer "B.Cu")
		(at 217.452132 95.392)
		(descr "Resistor SMD 0402")
		(tags "resistor SMD 0402")
		(property "Reference" "R274"
			(at -1.052132 -1.492 0)
			(layer "B.SilkS")
			(effects
				(font
					(size 0.7 0.7)
					(thickness 0.15)
				)
				(justify right top mirror)
			)
		)
		(property "Value" "R_10k_0402"
			(at -1.011843 -1.772047 0)
			(layer "B.Fab")
			(effects
				(font
					(size 0.7 0.7)
					(thickness 0.15)
				)
				(justify right top mirror)
			)
		)
		(property "Datasheet" "https://www.bourns.com/docs/product-datasheets/cr.pdf"
			(at 0 0 0)
			(layer "B.Fab")
			(hide yes)
			(effects
				(font
					(size 1.27 1.27)
					(thickness 0.15)
				)
				(justify mirror)
			)
		)
		(property "Description" "SMD Chip Resistor, 10 kohm, ± 1%, 62.5 mW, 0402 [1005 Metric], Thick Film, General Purpose"
			(at 0 0 0)
			(layer "B.Fab")
			(hide yes)
			(effects
				(font
					(size 1.27 1.27)
					(thickness 0.15)
				)
				(justify mirror)
			)
		)
		(property "MPN" "CR0402-FX-1002GLF"
			(at 0 0 180)
			(unlocked yes)
			(layer "B.Fab")
			(hide yes)
			(effects
				(font
					(size 1 1)
					(thickness 0.15)
				)
				(justify mirror)
			)
		)
		(property "Manufacturer" "Bourns"
			(at 0 0 180)
			(unlocked yes)
			(layer "B.Fab")
			(hide yes)
			(effects
				(font
					(size 1 1)
					(thickness 0.15)
				)
				(justify mirror)
			)
		)
		(property "License" "Apache-2.0"
			(at 0 0 180)
			(unlocked yes)
			(layer "B.Fab")
			(hide yes)
			(effects
				(font
					(size 1 1)
					(thickness 0.15)
				)
				(justify mirror)
			)
		)
		(property "Author" "Antmicro"
			(at 0 0 180)
			(unlocked yes)
			(layer "B.Fab")
			(hide yes)
			(effects
				(font
					(size 1 1)
					(thickness 0.15)
				)
				(justify mirror)
			)
		)
		(property "Val" "10k"
			(at 0 0 180)
			(unlocked yes)
			(layer "B.Fab")
			(hide yes)
			(effects
				(font
					(size 1 1)
					(thickness 0.15)
				)
				(justify mirror)
			)
		)
		(property "Tolerance" "1%"
			(at 0 0 180)
			(unlocked yes)
			(layer "B.Fab")
			(hide yes)
			(effects
				(font
					(size 1 1)
					(thickness 0.15)
				)
				(justify mirror)
			)
		)
		(sheetname "/USB DP Alt mode/")
		(sheetfile "usb_dp.kicad_sch")
		(attr smd)
		(fp_rect
			(start -0.925 0.47)
			(end 0.925 -0.47)
			(stroke
				(width 0.05)
				(type default)
			)
			(fill no)
			(layer "B.CrtYd")
		)
		(fp_rect
			(start -0.5 0.25)
			(end 0.5 -0.25)
			(stroke
				(width 0.15)
				(type solid)
			)
			(fill no)
			(layer "B.Fab")
		)
		(fp_text user "${REFERENCE}"
			(at -0.95 -3.168 0)
			(layer "B.Fab")
			(effects
				(font
					(size 0.7 0.7)
					(thickness 0.15)
				)
				(justify right top mirror)
			)
		)
		(fp_text user "License: Apache-2.0"
			(at -0.95 -5.169 0)
			(layer "B.Fab")
			(effects
				(font
					(size 0.7 0.7)
					(thickness 0.15)
				)
				(justify right top mirror)
			)
		)
		(fp_text user "Author: Antmicro"
			(at -0.95 -4.169 0)
			(layer "B.Fab")
			(effects
				(font
					(size 0.7 0.7)
					(thickness 0.15)
				)
				(justify right top mirror)
			)
		)
		(pad "1" smd roundrect
			(at -0.48 0)
			(size 0.59 0.64)
			(layers "B.Cu" "B.Mask" "B.Paste")
			(roundrect_rratio 0.25)
			(net 1301 "Net-(Q35-D)")
			(pintype "passive")
		)
		(pad "2" smd roundrect
			(at 0.48 0)
			(size 0.59 0.64)
			(layers "B.Cu" "B.Mask" "B.Paste")
			(roundrect_rratio 0.25)
			(net 11 "+1V8")
			(pintype "passive")
		)
	)
	(footprint "antmicro-footprints:R_0603_1608Metric"
		(layer "B.Cu")
		(at 100.1 129.2 180)
		(descr "Resistor SMD 0603")
		(tags "resistor SMD 0603")
		(property "Reference" "R249"
			(at -4.23 -0.33 0)
			(layer "B.SilkS")
			(effects
				(font
					(size 0.7 0.7)
					(thickness 0.15)
				)
				(justify left bottom mirror)
			)
		)
		(property "Value" "R_0R_22.4A_0603"
			(at 0 -1.6 0)
			(layer "B.Fab")
			(effects
				(font
					(size 0.7 0.7)
					(thickness 0.15)
				)
				(justify left bottom mirror)
			)
		)
		(property "Datasheet" "https://fscdn.rohm.com/en/products/databook/datasheet/passive/resistor/chip_resistor/pmr-jpw-e.pdf"
			(at 0 0 0)
			(layer "B.Fab")
			(hide yes)
			(effects
				(font
					(size 1.27 1.27)
					(thickness 0.15)
				)
				(justify mirror)
			)
		)
		(property "Description" "SMD Chip Resistor"
			(at 0 0 0)
			(layer "B.Fab")
			(hide yes)
			(effects
				(font
					(size 1.27 1.27)
					(thickness 0.15)
				)
				(justify mirror)
			)
		)
		(property "MPN" "PMR03EZPJ000"
			(at 0 0 0)
			(unlocked yes)
			(layer "B.Fab")
			(hide yes)
			(effects
				(font
					(size 1 1)
					(thickness 0.15)
				)
				(justify mirror)
			)
		)
		(property "Manufacturer" "ROHM Semiconductor"
			(at 0 0 0)
			(unlocked yes)
			(layer "B.Fab")
			(hide yes)
			(effects
				(font
					(size 1 1)
					(thickness 0.15)
				)
				(justify mirror)
			)
		)
		(property "Val" "0R"
			(at 0 0 0)
			(unlocked yes)
			(layer "B.Fab")
			(hide yes)
			(effects
				(font
					(size 1 1)
					(thickness 0.15)
				)
				(justify mirror)
			)
		)
		(property "Max. Curr." "22.4A"
			(at 0 0 0)
			(unlocked yes)
			(layer "B.Fab")
			(hide yes)
			(effects
				(font
					(size 1 1)
					(thickness 0.15)
				)
				(justify mirror)
			)
		)
		(property "Author" "Antmicro"
			(at 0 0 0)
			(unlocked yes)
			(layer "B.Fab")
			(hide yes)
			(effects
				(font
					(size 1 1)
					(thickness 0.15)
				)
				(justify mirror)
			)
		)
		(property "License" "Apache-2.0"
			(at 0 0 0)
			(unlocked yes)
			(layer "B.Fab")
			(hide yes)
			(effects
				(font
					(size 1 1)
					(thickness 0.15)
				)
				(justify mirror)
			)
		)
		(property "Tolerance" "template_tolerance"
			(at 0 0 0)
			(unlocked yes)
			(layer "B.Fab")
			(hide yes)
			(effects
				(font
					(size 1 1)
					(thickness 0.15)
				)
				(justify mirror)
			)
		)
		(sheetname "/Expansion connector/")
		(sheetfile "expansion_connector.kicad_sch")
		(attr smd exclude_from_pos_files exclude_from_bom dnp)
		(fp_line
			(start -0.15 0.4)
			(end 0.15 0.4)
			(stroke
				(width 0.15)
				(type solid)
			)
			(layer "B.SilkS")
		)
		(fp_line
			(start -0.15 -0.4)
			(end 0.15 -0.4)
			(stroke
				(width 0.15)
				(type solid)
			)
			(layer "B.SilkS")
		)
		(fp_rect
			(start -1.25 0.65)
			(end 1.25 -0.65)
			(stroke
				(width 0.05)
				(type solid)
			)
			(fill no)
			(layer "B.CrtYd")
		)
		(fp_rect
			(start -0.8 0.4)
			(end 0.8 -0.4)
			(stroke
				(width 0.15)
				(type solid)
			)
			(fill no)
			(layer "B.Fab")
		)
		(fp_text user "${REFERENCE}"
			(at -1.25 -3.898 0)
			(layer "B.Fab")
			(effects
				(font
					(size 0.7 0.7)
					(thickness 0.15)
				)
				(justify left bottom mirror)
			)
		)
		(fp_text user "License: Apache-2.0"
			(at -1.25 -5.9 0)
			(layer "B.Fab")
			(effects
				(font
					(size 0.7 0.7)
					(thickness 0.15)
				)
				(justify left bottom mirror)
			)
		)
		(fp_text user "Author: Antmicro"
			(at -1.25 -4.9 0)
			(layer "B.Fab")
			(effects
				(font
					(size 0.7 0.7)
					(thickness 0.15)
				)
				(justify left bottom mirror)
			)
		)
		(pad "1" smd roundrect
			(at -0.7 0 180)
			(size 0.8 1)
			(layers "B.Cu" "B.Mask" "B.Paste")
			(roundrect_rratio 0.2)
			(net 2 "+3V3")
			(pintype "passive")
		)
		(pad "2" smd roundrect
			(at 0.7 0 180)
			(size 0.8 1)
			(layers "B.Cu" "B.Mask" "B.Paste")
			(roundrect_rratio 0.2)
			(net 297 "/Expansion connector/+3V3_FMC")
			(pintype "passive")
		)
	)
	(footprint "antmicro-footprints:R_0402_1005Metric"
		(layer "B.Cu")
		(at 124.6 130.8)
		(descr "Resistor SMD 0402")
		(tags "resistor SMD 0402")
		(property "Reference" "R223"
			(at -1.19 -5.32 0)
			(layer "B.SilkS")
			(effects
				(font
					(size 0.7 0.7)
					(thickness 0.15)
				)
				(justify right top mirror)
			)
		)
		(property "Value" "R_0R_0402"
			(at -1.011843 -1.772046 0)
			(layer "B.Fab")
			(effects
				(font
					(size 0.7 0.7)
					(thickness 0.15)
				)
				(justify right top mirror)
			)
		)
		(property "Datasheet" "https://industrial.panasonic.com/cdbs/www-data/pdf/RDA0000/AOA0000C301.pdf"
			(at 0 0 0)
			(layer "B.Fab")
			(hide yes)
			(effects
				(font
					(size 1.27 1.27)
					(thickness 0.15)
				)
				(justify mirror)
			)
		)
		(property "Description" "SMD Chip Resistor, Jumper, 0 ohm, 100 mW, 0402 [1005 Metric], Thick Film, General Purpose"
			(at 0 0 0)
			(layer "B.Fab")
			(hide yes)
			(effects
				(font
					(size 1.27 1.27)
					(thickness 0.15)
				)
				(justify mirror)
			)
		)
		(property "MPN" "ERJ2GE0R00X"
			(at 0 0 180)
			(unlocked yes)
			(layer "B.Fab")
			(hide yes)
			(effects
				(font
					(size 1 1)
					(thickness 0.15)
				)
				(justify mirror)
			)
		)
		(property "Manufacturer" "Panasonic"
			(at 0 0 180)
			(unlocked yes)
			(layer "B.Fab")
			(hide yes)
			(effects
				(font
					(size 1 1)
					(thickness 0.15)
				)
				(justify mirror)
			)
		)
		(property "License" "Apache-2.0"
			(at 0 0 180)
			(unlocked yes)
			(layer "B.Fab")
			(hide yes)
			(effects
				(font
					(size 1 1)
					(thickness 0.15)
				)
				(justify mirror)
			)
		)
		(property "Val" "0R"
			(at 0 0 180)
			(unlocked yes)
			(layer "B.Fab")
			(hide yes)
			(effects
				(font
					(size 1 1)
					(thickness 0.15)
				)
				(justify mirror)
			)
		)
		(property "Tolerance" "~"
			(at 0 0 180)
			(unlocked yes)
			(layer "B.Fab")
			(hide yes)
			(effects
				(font
					(size 1 1)
					(thickness 0.15)
				)
				(justify mirror)
			)
		)
		(property "Current" "1A"
			(at 0 0 180)
			(unlocked yes)
			(layer "B.Fab")
			(hide yes)
			(effects
				(font
					(size 1 1)
					(thickness 0.15)
				)
				(justify mirror)
			)
		)
		(property "Author" "Antmicro"
			(at 0 0 180)
			(unlocked yes)
			(layer "B.Fab")
			(hide yes)
			(effects
				(font
					(size 1 1)
					(thickness 0.15)
				)
				(justify mirror)
			)
		)
		(property "Public" "False"
			(at 0 0 180)
			(unlocked yes)
			(layer "B.Fab")
			(hide yes)
			(effects
				(font
					(size 1 1)
					(thickness 0.15)
				)
				(justify mirror)
			)
		)
		(sheetname "/M.2/")
		(sheetfile "m2.kicad_sch")
		(attr smd)
		(fp_poly
			(pts
				(xy -0.925 0.47) (xy 0.925 0.47) (xy 0.925 -0.47) (xy -0.925 -0.47)
			)
			(stroke
				(width 0.05)
				(type default)
			)
			(fill no)
			(layer "B.CrtYd")
		)
		(fp_poly
			(pts
				(xy -0.5 0.25) (xy 0.5 0.25) (xy 0.5 -0.25) (xy -0.5 -0.25)
			)
			(stroke
				(width 0.15)
				(type solid)
			)
			(fill no)
			(layer "B.Fab")
		)
		(fp_text user "Author: Antmicro"
			(at -0.95 -4.169 0)
			(layer "B.Fab")
			(effects
				(font
					(size 0.7 0.7)
					(thickness 0.15)
				)
				(justify right top mirror)
			)
		)
		(fp_text user "${REFERENCE}"
			(at -0.95 -3.168 0)
			(layer "B.Fab")
			(effects
				(font
					(size 0.7 0.7)
					(thickness 0.15)
				)
				(justify right top mirror)
			)
		)
		(fp_text user "License: Apache-2.0"
			(at -0.949999 -5.169 0)
			(layer "B.Fab")
			(effects
				(font
					(size 0.7 0.7)
					(thickness 0.15)
				)
				(justify right top mirror)
			)
		)
		(pad "1" smd roundrect
			(at -0.48 0)
			(size 0.59 0.64)
			(layers "B.Cu" "B.Mask" "B.Paste")
			(roundrect_rratio 0.25)
			(net 832 "/M.2/M2_E_SUSCLK")
			(pintype "passive")
		)
		(pad "2" smd roundrect
			(at 0.48 0)
			(size 0.59 0.64)
			(layers "B.Cu" "B.Mask" "B.Paste")
			(roundrect_rratio 0.25)
			(net 1005 "/M.2/SUSCLK")
			(pintype "passive")
		)
	)
	(footprint "antmicro-footprints:SOD-523"
		(layer "B.Cu")
		(at 208.9 83.9 90)
		(property "Reference" "D17"
			(at -1.2 -1.5 90)
			(layer "B.SilkS")
			(effects
				(font
					(size 0.7 0.7)
					(thickness 0.15)
				)
				(justify right top mirror)
			)
		)
		(property "Value" "RB521S30T1G"
			(at 0 -1.499 90)
			(layer "B.Fab")
			(effects
				(font
					(size 0.7 0.7)
					(thickness 0.15)
				)
				(justify right top mirror)
			)
		)
		(property "Datasheet" "https://www.onsemi.com/pdf/datasheet/rb521s30t1-d.pdf"
			(at 0 0 90)
			(layer "B.Fab")
			(hide yes)
			(effects
				(font
					(size 1.27 1.27)
					(thickness 0.15)
				)
				(justify mirror)
			)
		)
		(property "Description" "Small Signal Schottky Diode, Single, 30 V, 200 mA, 500 mV, 1 A, 125 °C"
			(at 0 0 90)
			(layer "B.Fab")
			(hide yes)
			(effects
				(font
					(size 1.27 1.27)
					(thickness 0.15)
				)
				(justify mirror)
			)
		)
		(property "MPN" "RB521S30T1G"
			(at 0 0 270)
			(unlocked yes)
			(layer "B.Fab")
			(hide yes)
			(effects
				(font
					(size 1 1)
					(thickness 0.15)
				)
				(justify mirror)
			)
		)
		(property "Manufacturer" "ON Semiconductor"
			(at 0 0 270)
			(unlocked yes)
			(layer "B.Fab")
			(hide yes)
			(effects
				(font
					(size 1 1)
					(thickness 0.15)
				)
				(justify mirror)
			)
		)
		(property "Author" "Antmicro"
			(at 0 0 270)
			(unlocked yes)
			(layer "B.Fab")
			(hide yes)
			(effects
				(font
					(size 1 1)
					(thickness 0.15)
				)
				(justify mirror)
			)
		)
		(property "License" "Apache-2.0"
			(at 0 0 270)
			(unlocked yes)
			(layer "B.Fab")
			(hide yes)
			(effects
				(font
					(size 1 1)
					(thickness 0.15)
				)
				(justify mirror)
			)
		)
		(sheetname "/USB Debug, PD/")
		(sheetfile "usb_debug_pd.kicad_sch")
		(attr smd)
		(fp_line
			(start -0.35 0.5)
			(end -0.35 -0.5)
			(stroke
				(width 0.15)
				(type solid)
			)
			(layer "B.SilkS")
		)
		(fp_poly
			(pts
				(xy -1 0.6) (xy -1 -0.6) (xy 1 -0.6) (xy 1 0.6)
			)
			(stroke
				(width 0.05)
				(type solid)
			)
			(fill no)
			(layer "B.CrtYd")
		)
		(fp_line
			(start -0.652 -0.423)
			(end 0.65 -0.423)
			(stroke
				(width 0.15)
				(type solid)
			)
			(layer "B.Fab")
		)
		(fp_line
			(start -0.652 -0.423)
			(end -0.652 0.425)
			(stroke
				(width 0.15)
				(type solid)
			)
			(layer "B.Fab")
		)
		(fp_line
			(start -0.35 0.4)
			(end -0.35 -0.4)
			(stroke
				(width 0.15)
				(type solid)
			)
			(layer "B.Fab")
		)
		(fp_line
			(start 0.65 0.425)
			(end 0.65 -0.423)
			(stroke
				(width 0.15)
				(type solid)
			)
			(layer "B.Fab")
		)
		(fp_line
			(start -0.652 0.425)
			(end 0.65 0.425)
			(stroke
				(width 0.15)
				(type solid)
			)
			(layer "B.Fab")
		)
		(fp_text user "License: Apache-2.0"
			(at -1.276 -5.9 90)
			(layer "B.Fab")
			(effects
				(font
					(size 0.7 0.7)
					(thickness 0.15)
				)
				(justify right top mirror)
			)
		)
		(fp_text user "Author: Antmicro"
			(at -1.276 -4.7 90)
			(layer "B.Fab")
			(effects
				(font
					(size 0.7 0.7)
					(thickness 0.15)
				)
				(justify right top mirror)
			)
		)
		(fp_text user "${REFERENCE}"
			(at -1.276 -3.499 90)
			(layer "B.Fab")
			(effects
				(font
					(size 0.7 0.7)
					(thickness 0.15)
				)
				(justify right top mirror)
			)
		)
		(pad "1" smd roundrect
			(at -0.701 0 90)
			(size 0.5 0.6)
			(layers "B.Cu" "B.Mask" "B.Paste")
			(roundrect_rratio 0.25)
			(net 271 "FLASH_PWR")
			(pinfunction "C")
			(pintype "passive")
		)
		(pad "2" smd roundrect
			(at 0.699001 0 90)
			(size 0.5 0.6)
			(layers "B.Cu" "B.Mask" "B.Paste")
			(roundrect_rratio 0.25)
			(net 294 "/USB Debug, PD/PDC_LDO_3V3")
			(pinfunction "A")
			(pintype "passive")
		)
	)
	(footprint "antmicro-footprints:R_0402_1005Metric"
		(layer "B.Cu")
		(at 217.55 114.03)
		(descr "Resistor SMD 0402")
		(tags "resistor SMD 0402")
		(property "Reference" "R331"
			(at -1.76 1.79 0)
			(layer "B.SilkS")
			(effects
				(font
					(size 0.7 0.7)
					(thickness 0.15)
				)
				(justify right top mirror)
			)
		)
		(property "Value" "R_2R2_0402"
			(at -1.011843 -1.772047 0)
			(layer "B.Fab")
			(effects
				(font
					(size 0.7 0.7)
					(thickness 0.15)
				)
				(justify right top mirror)
			)
		)
		(property "Datasheet" "https://www.bourns.com/docs/product-datasheets/cr.pdf"
			(at 0 0 0)
			(layer "B.Fab")
			(hide yes)
			(effects
				(font
					(size 1.27 1.27)
					(thickness 0.15)
				)
				(justify mirror)
			)
		)
		(property "Description" "SMD Chip Resistor, 2.2 ohm, ± 1%, 62.5 mW, 0402 [1005 Metric], Thick Film, General Purpose"
			(at 0 0 0)
			(layer "B.Fab")
			(hide yes)
			(effects
				(font
					(size 1.27 1.27)
					(thickness 0.15)
				)
				(justify mirror)
			)
		)
		(property "MPN" "CR0402-FX-2R20GLF"
			(at 0 0 180)
			(unlocked yes)
			(layer "B.Fab")
			(hide yes)
			(effects
				(font
					(size 1 1)
					(thickness 0.15)
				)
				(justify mirror)
			)
		)
		(property "Manufacturer" "Bourns"
			(at 0 0 180)
			(unlocked yes)
			(layer "B.Fab")
			(hide yes)
			(effects
				(font
					(size 1 1)
					(thickness 0.15)
				)
				(justify mirror)
			)
		)
		(property "License" "Apache-2.0"
			(at 0 0 180)
			(unlocked yes)
			(layer "B.Fab")
			(hide yes)
			(effects
				(font
					(size 1 1)
					(thickness 0.15)
				)
				(justify mirror)
			)
		)
		(property "Author" "Antmicro"
			(at 0 0 180)
			(unlocked yes)
			(layer "B.Fab")
			(hide yes)
			(effects
				(font
					(size 1 1)
					(thickness 0.15)
				)
				(justify mirror)
			)
		)
		(property "Val" "2R2"
			(at 0 0 180)
			(unlocked yes)
			(layer "B.Fab")
			(hide yes)
			(effects
				(font
					(size 1 1)
					(thickness 0.15)
				)
				(justify mirror)
			)
		)
		(property "Tolerance" "1%"
			(at 0 0 180)
			(unlocked yes)
			(layer "B.Fab")
			(hide yes)
			(effects
				(font
					(size 1 1)
					(thickness 0.15)
				)
				(justify mirror)
			)
		)
		(sheetname "/USB Hub/")
		(sheetfile "usb_hub.kicad_sch")
		(attr smd)
		(fp_rect
			(start -0.925 0.47)
			(end 0.925 -0.47)
			(stroke
				(width 0.05)
				(type default)
			)
			(fill no)
			(layer "B.CrtYd")
		)
		(fp_rect
			(start -0.5 0.25)
			(end 0.5 -0.25)
			(stroke
				(width 0.15)
				(type solid)
			)
			(fill no)
			(layer "B.Fab")
		)
		(fp_text user "License: Apache-2.0"
			(at -0.95 -5.169 0)
			(layer "B.Fab")
			(effects
				(font
					(size 0.7 0.7)
					(thickness 0.15)
				)
				(justify right top mirror)
			)
		)
		(fp_text user "Author: Antmicro"
			(at -0.95 -4.169 0)
			(layer "B.Fab")
			(effects
				(font
					(size 0.7 0.7)
					(thickness 0.15)
				)
				(justify right top mirror)
			)
		)
		(fp_text user "${REFERENCE}"
			(at -0.95 -3.168 0)
			(layer "B.Fab")
			(effects
				(font
					(size 0.7 0.7)
					(thickness 0.15)
				)
				(justify right top mirror)
			)
		)
		(pad "1" smd roundrect
			(at -0.48 0)
			(size 0.59 0.64)
			(layers "B.Cu" "B.Mask" "B.Paste")
			(roundrect_rratio 0.25)
			(net 1237 "Net-(D58-C)")
			(pintype "passive")
		)
		(pad "2" smd roundrect
			(at 0.48 0)
			(size 0.59 0.64)
			(layers "B.Cu" "B.Mask" "B.Paste")
			(roundrect_rratio 0.25)
			(net 509 "/USB Hub/USBC3_CC_{2}")
			(pintype "passive")
		)
	)
	(footprint "antmicro-footprints:C_0603_1608Metric_EIA"
		(layer "B.Cu")
		(at 118.130532 69.46)
		(descr "Capacitor SMD 0603, IPC-7351 Density Level A")
		(tags "Capacitor 0603")
		(property "Reference" "C21"
			(at 0.969468 -0.86 180)
			(layer "B.SilkS")
			(effects
				(font
					(size 0.7 0.7)
					(thickness 0.15)
				)
				(justify left bottom mirror)
			)
		)
		(property "Value" "C_22u_16V_0603"
			(at -1.42757 -1.770288 180)
			(layer "B.Fab")
			(effects
				(font
					(size 0.7 0.7)
					(thickness 0.15)
				)
				(justify left bottom mirror)
			)
		)
		(property "Datasheet" "https://product.samsungsem.com/mlcc/CL10A226MO7JZN.do"
			(at 0 0 180)
			(layer "B.Fab")
			(hide yes)
			(effects
				(font
					(size 1.27 1.27)
					(thickness 0.15)
				)
				(justify mirror)
			)
		)
		(property "Description" "SMD Multilayer Ceramic Capacitor"
			(at 0 0 180)
			(layer "B.Fab")
			(hide yes)
			(effects
				(font
					(size 1.27 1.27)
					(thickness 0.15)
				)
				(justify mirror)
			)
		)
		(property "MPN" "CL10A226MO7JZNC"
			(at 0 0 0)
			(unlocked yes)
			(layer "B.Fab")
			(hide yes)
			(effects
				(font
					(size 1 1)
					(thickness 0.15)
				)
				(justify mirror)
			)
		)
		(property "Manufacturer" "Samsung Electro-Mechanics"
			(at 0 0 0)
			(unlocked yes)
			(layer "B.Fab")
			(hide yes)
			(effects
				(font
					(size 1 1)
					(thickness 0.15)
				)
				(justify mirror)
			)
		)
		(property "License" "Apache-2.0"
			(at 0 0 0)
			(unlocked yes)
			(layer "B.Fab")
			(hide yes)
			(effects
				(font
					(size 1 1)
					(thickness 0.15)
				)
				(justify mirror)
			)
		)
		(property "Author" "Antmicro"
			(at 0 0 0)
			(unlocked yes)
			(layer "B.Fab")
			(hide yes)
			(effects
				(font
					(size 1 1)
					(thickness 0.15)
				)
				(justify mirror)
			)
		)
		(property "Val" "22u"
			(at 0 0 0)
			(unlocked yes)
			(layer "B.Fab")
			(hide yes)
			(effects
				(font
					(size 1 1)
					(thickness 0.15)
				)
				(justify mirror)
			)
		)
		(property "Voltage" "16V"
			(at 0 0 0)
			(unlocked yes)
			(layer "B.Fab")
			(hide yes)
			(effects
				(font
					(size 1 1)
					(thickness 0.15)
				)
				(justify mirror)
			)
		)
		(property "Dielectric" "X7R"
			(at 0 0 0)
			(unlocked yes)
			(layer "B.Fab")
			(hide yes)
			(effects
				(font
					(size 1 1)
					(thickness 0.15)
				)
				(justify mirror)
			)
		)
		(property "Public" "False"
			(at 0 0 0)
			(unlocked yes)
			(layer "B.Fab")
			(hide yes)
			(effects
				(font
					(size 1 1)
					(thickness 0.15)
				)
				(justify mirror)
			)
		)
		(sheetname "/SoM_Power/")
		(sheetfile "som_power.kicad_sch")
		(attr smd)
		(fp_line
			(start -0.15 -0.55)
			(end 0.15 -0.55)
			(stroke
				(width 0.15)
				(type solid)
			)
			(layer "B.SilkS")
		)
		(fp_line
			(start -0.15 0.55)
			(end 0.15 0.55)
			(stroke
				(width 0.15)
				(type solid)
			)
			(layer "B.SilkS")
		)
		(fp_rect
			(start -1.25 0.65)
			(end 1.25 -0.65)
			(stroke
				(width 0.05)
				(type solid)
			)
			(fill no)
			(layer "B.CrtYd")
		)
		(fp_rect
			(start -0.8 0.45)
			(end 0.8 -0.45)
			(stroke
				(width 0.15)
				(type solid)
			)
			(fill no)
			(layer "B.Fab")
		)
		(fp_text user "${REFERENCE}"
			(at -1.682 -3.895 180)
			(layer "B.Fab")
			(effects
				(font
					(size 0.7 0.7)
					(thickness 0.15)
				)
				(justify left bottom mirror)
			)
		)
		(fp_text user "Author: Antmicro"
			(at -1.682 -4.894 180)
			(layer "B.Fab")
			(effects
				(font
					(size 0.7 0.7)
					(thickness 0.15)
				)
				(justify left bottom mirror)
			)
		)
		(fp_text user "License: Apache-2.0"
			(at -1.682 -5.895 180)
			(layer "B.Fab")
			(effects
				(font
					(size 0.7 0.7)
					(thickness 0.15)
				)
				(justify left bottom mirror)
			)
		)
		(pad "1" smd roundrect
			(at -0.7 0)
			(size 0.8 1.1)
			(layers "B.Cu" "B.Mask" "B.Paste")
			(roundrect_rratio 0.2)
			(net 1 "GND")
			(pintype "passive")
		)
		(pad "2" smd roundrect
			(at 0.7 0)
			(size 0.8 1.1)
			(layers "B.Cu" "B.Mask" "B.Paste")
			(roundrect_rratio 0.2)
			(net 213 "+5V_SOM")
			(pintype "passive")
		)
	)
	(footprint "antmicro-footprints:SOT-563"
		(layer "B.Cu")
		(at 220.18 111.27 90)
		(property "Reference" "Q21"
			(at -1.33 1.32 90)
			(layer "B.SilkS")
			(effects
				(font
					(size 0.7 0.7)
					(thickness 0.15)
				)
				(justify right top mirror)
			)
		)
		(property "Value" "DMC2400UV-7"
			(at 0 -2 90)
			(layer "B.Fab")
			(effects
				(font
					(size 0.7 0.7)
					(thickness 0.15)
				)
				(justify right top mirror)
			)
		)
		(property "Datasheet" "https://www.mouser.com/datasheet/2/115/DIOD_S_A0010038249_1-2543538.pdf"
			(at 0 0 90)
			(layer "B.Fab")
			(hide yes)
			(effects
				(font
					(size 1.27 1.27)
					(thickness 0.15)
				)
				(justify mirror)
			)
		)
		(property "Description" "Dual MOSFET, Complementary N and P Channel, 20 V, 20 V, 1.03 A, 1.03 A, 0.3 ohm"
			(at 0 0 90)
			(layer "B.Fab")
			(hide yes)
			(effects
				(font
					(size 1.27 1.27)
					(thickness 0.15)
				)
				(justify mirror)
			)
		)
		(property "MPN" "DMC2400UV-7"
			(at 0 0 270)
			(unlocked yes)
			(layer "B.Fab")
			(hide yes)
			(effects
				(font
					(size 1 1)
					(thickness 0.15)
				)
				(justify mirror)
			)
		)
		(property "Manufacturer" "Diodes Incorporated"
			(at 0 0 270)
			(unlocked yes)
			(layer "B.Fab")
			(hide yes)
			(effects
				(font
					(size 1 1)
					(thickness 0.15)
				)
				(justify mirror)
			)
		)
		(property "Author" "Antmicro"
			(at 0 0 270)
			(unlocked yes)
			(layer "B.Fab")
			(hide yes)
			(effects
				(font
					(size 1 1)
					(thickness 0.15)
				)
				(justify mirror)
			)
		)
		(property "License" "Apache-2.0"
			(at 0 0 270)
			(unlocked yes)
			(layer "B.Fab")
			(hide yes)
			(effects
				(font
					(size 1 1)
					(thickness 0.15)
				)
				(justify mirror)
			)
		)
		(sheetname "/USB Hub/")
		(sheetfile "usb_hub.kicad_sch")
		(attr smd)
		(fp_line
			(start 0.776 -0.972)
			(end 0.526 -0.972)
			(stroke
				(width 0.15)
				(type solid)
			)
			(layer "B.SilkS")
		)
		(fp_line
			(start -0.778 -0.949)
			(end -0.424 -0.949)
			(stroke
				(width 0.15)
				(type solid)
			)
			(layer "B.SilkS")
		)
		(fp_line
			(start 0.776 -0.776)
			(end 0.776 -0.972)
			(stroke
				(width 0.15)
				(type solid)
			)
			(layer "B.SilkS")
		)
		(fp_line
			(start -0.778 -0.776)
			(end -0.778 -0.949)
			(stroke
				(width 0.15)
				(type solid)
			)
			(layer "B.SilkS")
		)
		(fp_line
			(start 0.776 0.974)
			(end 0.776 0.778)
			(stroke
				(width 0.15)
				(type solid)
			)
			(layer "B.SilkS")
		)
		(fp_line
			(start 0.776 0.974)
			(end 0.526 0.974)
			(stroke
				(width 0.15)
				(type solid)
			)
			(layer "B.SilkS")
		)
		(fp_line
			(start -0.499 0.974)
			(end -0.724 0.778)
			(stroke
				(width 0.15)
				(type solid)
			)
			(layer "B.SilkS")
		)
		(fp_circle
			(center -0.903 0.999)
			(end -0.952 0.95)
			(stroke
				(width 0.15)
				(type solid)
			)
			(fill yes)
			(layer "B.SilkS")
		)
		(fp_rect
			(start 1.19 1.12)
			(end -1.2 -1.1)
			(stroke
				(width 0.05)
				(type solid)
			)
			(fill no)
			(layer "B.CrtYd")
		)
		(fp_line
			(start 0.651 -0.847)
			(end -0.653 -0.847)
			(stroke
				(width 0.15)
				(type solid)
			)
			(layer "B.Fab")
		)
		(fp_line
			(start -0.653 0.678)
			(end -0.653 -0.847)
			(stroke
				(width 0.15)
				(type solid)
			)
			(layer "B.Fab")
		)
		(fp_line
			(start 0.651 0.849)
			(end 0.651 -0.847)
			(stroke
				(width 0.15)
				(type solid)
			)
			(layer "B.Fab")
		)
		(fp_line
			(start -0.453 0.849)
			(end -0.653 0.678)
			(stroke
				(width 0.15)
				(type solid)
			)
			(layer "B.Fab")
		)
		(fp_line
			(start -0.453 0.849)
			(end 0.651 0.849)
			(stroke
				(width 0.15)
				(type solid)
			)
			(layer "B.Fab")
		)
		(fp_text user "${REFERENCE}"
			(at -1.299 -7.323 90)
			(layer "B.Fab")
			(effects
				(font
					(size 0.7 0.7)
					(thickness 0.15)
				)
				(justify right top mirror)
			)
		)
		(fp_text user "Author: Antmicro"
			(at -1.299 -6.124 90)
			(layer "B.Fab")
			(effects
				(font
					(size 0.7 0.7)
					(thickness 0.15)
				)
				(justify right top mirror)
			)
		)
		(fp_text user "License: Apache-2.0"
			(at -1.299 -4.924 90)
			(layer "B.Fab")
			(effects
				(font
					(size 0.7 0.7)
					(thickness 0.15)
				)
				(justify right top mirror)
			)
		)
		(pad "1" smd roundrect
			(at -0.749 0.499 180)
			(size 0.3 0.6)
			(layers "B.Cu" "B.Mask" "B.Paste")
			(roundrect_rratio 0.25)
			(net 1 "GND")
			(pinfunction "S1")
			(pintype "passive")
		)
		(pad "2" smd roundrect
			(at -0.749 -0.001 180)
			(size 0.3 0.6)
			(layers "B.Cu" "B.Mask" "B.Paste")
			(roundrect_rratio 0.25)
			(net 1099 "/USB Hub/DP2_VCONN1")
			(pinfunction "G1")
			(pintype "input")
		)
		(pad "3" smd roundrect
			(at -0.749 -0.497 180)
			(size 0.3 0.6)
			(layers "B.Cu" "B.Mask" "B.Paste")
			(roundrect_rratio 0.25)
			(net 1019 "Net-(D57-A)")
			(pinfunction "D2")
			(pintype "passive")
		)
		(pad "4" smd roundrect
			(at 0.747 -0.497 180)
			(size 0.3 0.6)
			(layers "B.Cu" "B.Mask" "B.Paste")
			(roundrect_rratio 0.25)
			(net 5 "+5V")
			(pinfunction "S2")
			(pintype "passive")
		)
		(pad "5" smd roundrect
			(at 0.747 -0.001 180)
			(size 0.3 0.6)
			(layers "B.Cu" "B.Mask" "B.Paste")
			(roundrect_rratio 0.25)
			(net 1330 "Net-(Q21-D1)")
			(pinfunction "G2")
			(pintype "input")
		)
		(pad "6" smd roundrect
			(at 0.747 0.499 180)
			(size 0.3 0.6)
			(layers "B.Cu" "B.Mask" "B.Paste")
			(roundrect_rratio 0.25)
			(net 1330 "Net-(Q21-D1)")
			(pinfunction "D1")
			(pintype "passive")
		)
	)
	(footprint "antmicro-footprints:R_0402_1005Metric"
		(layer "B.Cu")
		(at 216 90.22 180)
		(descr "Resistor SMD 0402")
		(tags "resistor SMD 0402")
		(property "Reference" "R140"
			(at -7.6 -2.28 0)
			(layer "B.SilkS")
			(effects
				(font
					(size 0.7 0.7)
					(thickness 0.15)
				)
				(justify left bottom mirror)
			)
		)
		(property "Value" "R_1k_0402"
			(at -1.011843 -1.772047 0)
			(layer "B.Fab")
			(effects
				(font
					(size 0.7 0.7)
					(thickness 0.15)
				)
				(justify left bottom mirror)
			)
		)
		(property "Datasheet" "https://www.bourns.com/docs/product-datasheets/cr.pdf"
			(at 0 0 0)
			(layer "B.Fab")
			(hide yes)
			(effects
				(font
					(size 1.27 1.27)
					(thickness 0.15)
				)
				(justify mirror)
			)
		)
		(property "Description" "SMD Chip Resistor, 1 kohm, ± 1%, 63 mW, 0402 [1005 Metric], Thick Film, General Purpose"
			(at 0 0 0)
			(layer "B.Fab")
			(hide yes)
			(effects
				(font
					(size 1.27 1.27)
					(thickness 0.15)
				)
				(justify mirror)
			)
		)
		(property "Manufacturer" "Bourns"
			(at 0 0 0)
			(unlocked yes)
			(layer "B.Fab")
			(hide yes)
			(effects
				(font
					(size 1 1)
					(thickness 0.15)
				)
				(justify mirror)
			)
		)
		(property "MPN" "CR0402-FX-1001GLF"
			(at 0 0 0)
			(unlocked yes)
			(layer "B.Fab")
			(hide yes)
			(effects
				(font
					(size 1 1)
					(thickness 0.15)
				)
				(justify mirror)
			)
		)
		(property "Val" "1k"
			(at 0 0 0)
			(unlocked yes)
			(layer "B.Fab")
			(hide yes)
			(effects
				(font
					(size 1 1)
					(thickness 0.15)
				)
				(justify mirror)
			)
		)
		(property "License" "Apache-2.0"
			(at 0 0 0)
			(unlocked yes)
			(layer "B.Fab")
			(hide yes)
			(effects
				(font
					(size 1 1)
					(thickness 0.15)
				)
				(justify mirror)
			)
		)
		(property "Author" "Antmicro"
			(at 0 0 0)
			(unlocked yes)
			(layer "B.Fab")
			(hide yes)
			(effects
				(font
					(size 1 1)
					(thickness 0.15)
				)
				(justify mirror)
			)
		)
		(property "Tolerance" "1%"
			(at 0 0 0)
			(unlocked yes)
			(layer "B.Fab")
			(hide yes)
			(effects
				(font
					(size 1 1)
					(thickness 0.15)
				)
				(justify mirror)
			)
		)
		(sheetname "/USB DP Alt mode/")
		(sheetfile "usb_dp.kicad_sch")
		(attr smd exclude_from_pos_files exclude_from_bom dnp)
		(fp_rect
			(start -0.925 0.47)
			(end 0.925 -0.47)
			(stroke
				(width 0.05)
				(type default)
			)
			(fill no)
			(layer "B.CrtYd")
		)
		(fp_rect
			(start -0.5 0.25)
			(end 0.5 -0.25)
			(stroke
				(width 0.15)
				(type solid)
			)
			(fill no)
			(layer "B.Fab")
		)
		(fp_text user "License: Apache-2.0"
			(at -0.95 -5.169 0)
			(layer "B.Fab")
			(effects
				(font
					(size 0.7 0.7)
					(thickness 0.15)
				)
				(justify left bottom mirror)
			)
		)
		(fp_text user "Author: Antmicro"
			(at -0.95 -4.169 0)
			(layer "B.Fab")
			(effects
				(font
					(size 0.7 0.7)
					(thickness 0.15)
				)
				(justify left bottom mirror)
			)
		)
		(fp_text user "${REFERENCE}"
			(at -0.95 -3.168 0)
			(layer "B.Fab")
			(effects
				(font
					(size 0.7 0.7)
					(thickness 0.15)
				)
				(justify left bottom mirror)
			)
		)
		(pad "1" smd roundrect
			(at -0.48 0 180)
			(size 0.59 0.64)
			(layers "B.Cu" "B.Mask" "B.Paste")
			(roundrect_rratio 0.25)
			(net 969 "/USB DP Alt mode/USBC1_EQ1")
			(pintype "passive")
		)
		(pad "2" smd roundrect
			(at 0.48 0 180)
			(size 0.59 0.64)
			(layers "B.Cu" "B.Mask" "B.Paste")
			(roundrect_rratio 0.25)
			(net 2 "+3V3")
			(pintype "passive")
		)
	)
	(footprint "antmicro-footprints:R_0402_1005Metric"
		(layer "B.Cu")
		(at 63.2 66.5 -90)
		(descr "Resistor SMD 0402")
		(tags "resistor SMD 0402")
		(property "Reference" "R164"
			(at -9.7 0 90)
			(layer "B.SilkS")
			(effects
				(font
					(size 0.7 0.7)
					(thickness 0.15)
				)
				(justify left bottom mirror)
			)
		)
		(property "Value" "R_2k2_0402"
			(at -1.011843 -1.772047 90)
			(layer "B.Fab")
			(effects
				(font
					(size 0.7 0.7)
					(thickness 0.15)
				)
				(justify left bottom mirror)
			)
		)
		(property "Datasheet" "https://www.bourns.com/docs/product-datasheets/cr.pdf"
			(at 0 0 90)
			(layer "B.Fab")
			(hide yes)
			(effects
				(font
					(size 1.27 1.27)
					(thickness 0.15)
				)
				(justify mirror)
			)
		)
		(property "Description" "SMD Chip Resistor, 2.2 kohm, ± 1%, 62.5 mW, 0402 [1005 Metric], Thick Film, General Purpose"
			(at 0 0 90)
			(layer "B.Fab")
			(hide yes)
			(effects
				(font
					(size 1.27 1.27)
					(thickness 0.15)
				)
				(justify mirror)
			)
		)
		(property "MPN" "CR0402-FX-2201GLF"
			(at 0 0 90)
			(unlocked yes)
			(layer "B.Fab")
			(hide yes)
			(effects
				(font
					(size 1 1)
					(thickness 0.15)
				)
				(justify mirror)
			)
		)
		(property "Manufacturer" "Bourns"
			(at 0 0 90)
			(unlocked yes)
			(layer "B.Fab")
			(hide yes)
			(effects
				(font
					(size 1 1)
					(thickness 0.15)
				)
				(justify mirror)
			)
		)
		(property "License" "Apache-2.0"
			(at 0 0 90)
			(unlocked yes)
			(layer "B.Fab")
			(hide yes)
			(effects
				(font
					(size 1 1)
					(thickness 0.15)
				)
				(justify mirror)
			)
		)
		(property "Author" "Antmicro"
			(at 0 0 90)
			(unlocked yes)
			(layer "B.Fab")
			(hide yes)
			(effects
				(font
					(size 1 1)
					(thickness 0.15)
				)
				(justify mirror)
			)
		)
		(property "Val" "2k2"
			(at 0 0 90)
			(unlocked yes)
			(layer "B.Fab")
			(hide yes)
			(effects
				(font
					(size 1 1)
					(thickness 0.15)
				)
				(justify mirror)
			)
		)
		(property "Tolerance" "1%"
			(at 0 0 90)
			(unlocked yes)
			(layer "B.Fab")
			(hide yes)
			(effects
				(font
					(size 1 1)
					(thickness 0.15)
				)
				(justify mirror)
			)
		)
		(sheetname "/CSI/")
		(sheetfile "csi.kicad_sch")
		(attr smd)
		(fp_rect
			(start -0.925 0.47)
			(end 0.925 -0.47)
			(stroke
				(width 0.05)
				(type default)
			)
			(fill no)
			(layer "B.CrtYd")
		)
		(fp_rect
			(start -0.5 0.25)
			(end 0.5 -0.25)
			(stroke
				(width 0.15)
				(type solid)
			)
			(fill no)
			(layer "B.Fab")
		)
		(fp_text user "Author: Antmicro"
			(at -0.95 -4.169 90)
			(layer "B.Fab")
			(effects
				(font
					(size 0.7 0.7)
					(thickness 0.15)
				)
				(justify left bottom mirror)
			)
		)
		(fp_text user "${REFERENCE}"
			(at -0.95 -3.168 90)
			(layer "B.Fab")
			(effects
				(font
					(size 0.7 0.7)
					(thickness 0.15)
				)
				(justify left bottom mirror)
			)
		)
		(fp_text user "License: Apache-2.0"
			(at -0.95 -5.169 90)
			(layer "B.Fab")
			(effects
				(font
					(size 0.7 0.7)
					(thickness 0.15)
				)
				(justify left bottom mirror)
			)
		)
		(pad "1" smd roundrect
			(at -0.48 0 270)
			(size 0.59 0.64)
			(layers "B.Cu" "B.Mask" "B.Paste")
			(roundrect_rratio 0.25)
			(net 979 "/CSI/CSIA_I2C_VCC")
			(pintype "passive")
		)
		(pad "2" smd roundrect
			(at 0.48 0 270)
			(size 0.59 0.64)
			(layers "B.Cu" "B.Mask" "B.Paste")
			(roundrect_rratio 0.25)
			(net 986 "/CSI/SDA_CAM1")
			(pintype "passive")
		)
	)
	(footprint "antmicro-footprints:TP_SMD_0.75mm"
		(layer "B.Cu")
		(at 197.5 73.62 180)
		(property "Reference" "TP91"
			(at 0 0.6 0)
			(layer "B.SilkS")
			(effects
				(font
					(size 0.7 0.7)
					(thickness 0.15)
				)
				(justify left bottom mirror)
			)
		)
		(property "Value" "TP_0.75mm_SMD"
			(at 0 -1.2 0)
			(layer "B.Fab")
			(effects
				(font
					(size 0.7 0.7)
					(thickness 0.15)
				)
				(justify left bottom mirror)
			)
		)
		(property "Description" "SMT test point"
			(at 0 0 0)
			(layer "B.Fab")
			(hide yes)
			(effects
				(font
					(size 1.27 1.27)
					(thickness 0.15)
				)
				(justify mirror)
			)
		)
		(property "MPN" ""
			(at 0 0 0)
			(unlocked yes)
			(layer "B.Fab")
			(hide yes)
			(effects
				(font
					(size 1 1)
					(thickness 0.15)
				)
				(justify mirror)
			)
		)
		(property "Manufacturer" ""
			(at 0 0 0)
			(unlocked yes)
			(layer "B.Fab")
			(hide yes)
			(effects
				(font
					(size 1 1)
					(thickness 0.15)
				)
				(justify mirror)
			)
		)
		(property "Author" "Antmicro"
			(at 0 0 0)
			(unlocked yes)
			(layer "B.Fab")
			(hide yes)
			(effects
				(font
					(size 1 1)
					(thickness 0.15)
				)
				(justify mirror)
			)
		)
		(property "License" "Apache-2.0"
			(at 0 0 0)
			(unlocked yes)
			(layer "B.Fab")
			(hide yes)
			(effects
				(font
					(size 1 1)
					(thickness 0.15)
				)
				(justify mirror)
			)
		)
		(sheetname "/USB Debug, PD/")
		(sheetfile "usb_debug_pd.kicad_sch")
		(attr exclude_from_pos_files exclude_from_bom)
		(fp_circle
			(center 0 0)
			(end 0.475 0)
			(stroke
				(width 0.05)
				(type default)
			)
			(fill no)
			(layer "B.CrtYd")
		)
		(fp_text user "Author: Antmicro"
			(at -0.4 -3.901 0)
			(layer "B.Fab")
			(effects
				(font
					(size 0.7 0.7)
					(thickness 0.15)
				)
				(justify left bottom mirror)
			)
		)
		(fp_text user "License: Apache-2.0"
			(at -0.4 -5.101 0)
			(layer "B.Fab")
			(effects
				(font
					(size 0.7 0.7)
					(thickness 0.15)
				)
				(justify left bottom mirror)
			)
		)
		(fp_text user "${REFERENCE}"
			(at -0.4 -2.7 0)
			(layer "B.Fab")
			(effects
				(font
					(size 0.7 0.7)
					(thickness 0.15)
				)
				(justify left bottom mirror)
			)
		)
		(pad "1" smd circle
			(at 0 0 180)
			(size 0.75 0.75)
			(layers "B.Cu" "B.Mask")
			(net 946 "/USB Debug, PD/DEBUG_SDA")
			(pinfunction "1")
			(pintype "passive")
		)
	)
	(footprint "antmicro-footprints:TP_SMD_0.75mm"
		(layer "B.Cu")
		(at 234 71.5 90)
		(property "Reference" "TP83"
			(at -1.1 -1.6 90)
			(layer "B.SilkS")
			(effects
				(font
					(size 0.7 0.7)
					(thickness 0.15)
				)
				(justify right top mirror)
			)
		)
		(property "Value" "TP_0.75mm_SMD"
			(at 0 -1.2 90)
			(layer "B.Fab")
			(effects
				(font
					(size 0.7 0.7)
					(thickness 0.15)
				)
				(justify right top mirror)
			)
		)
		(property "Description" "SMT test point"
			(at 0 0 90)
			(layer "B.Fab")
			(hide yes)
			(effects
				(font
					(size 1.27 1.27)
					(thickness 0.15)
				)
				(justify mirror)
			)
		)
		(property "MPN" ""
			(at 0 0 270)
			(unlocked yes)
			(layer "B.Fab")
			(hide yes)
			(effects
				(font
					(size 1 1)
					(thickness 0.15)
				)
				(justify mirror)
			)
		)
		(property "Manufacturer" ""
			(at 0 0 270)
			(unlocked yes)
			(layer "B.Fab")
			(hide yes)
			(effects
				(font
					(size 1 1)
					(thickness 0.15)
				)
				(justify mirror)
			)
		)
		(property "Author" "Antmicro"
			(at 0 0 270)
			(unlocked yes)
			(layer "B.Fab")
			(hide yes)
			(effects
				(font
					(size 1 1)
					(thickness 0.15)
				)
				(justify mirror)
			)
		)
		(property "License" "Apache-2.0"
			(at 0 0 270)
			(unlocked yes)
			(layer "B.Fab")
			(hide yes)
			(effects
				(font
					(size 1 1)
					(thickness 0.15)
				)
				(justify mirror)
			)
		)
		(sheetname "/SoM_Power/")
		(sheetfile "som_power.kicad_sch")
		(attr exclude_from_pos_files exclude_from_bom)
		(fp_circle
			(center 0 0)
			(end 0.475 0)
			(stroke
				(width 0.05)
				(type default)
			)
			(fill no)
			(layer "B.CrtYd")
		)
		(fp_text user "License: Apache-2.0"
			(at -0.4 -5.101 90)
			(layer "B.Fab")
			(effects
				(font
					(size 0.7 0.7)
					(thickness 0.15)
				)
				(justify right top mirror)
			)
		)
		(fp_text user "${REFERENCE}"
			(at -0.4 -2.7 90)
			(layer "B.Fab")
			(effects
				(font
					(size 0.7 0.7)
					(thickness 0.15)
				)
				(justify right top mirror)
			)
		)
		(fp_text user "Author: Antmicro"
			(at -0.4 -3.901 90)
			(layer "B.Fab")
			(effects
				(font
					(size 0.7 0.7)
					(thickness 0.15)
				)
				(justify right top mirror)
			)
		)
		(pad "1" smd circle
			(at 0 0 90)
			(size 0.75 0.75)
			(layers "B.Cu" "B.Mask")
			(net 702 "/SoM_Power/~{SYS_RESET}")
			(pinfunction "1")
			(pintype "passive")
		)
	)
	(footprint "antmicro-footprints:TP_SMD_0.75mm"
		(layer "B.Cu")
		(at 140.330532 71.31 90)
		(property "Reference" "TP48"
			(at -3.26 0.069468 90)
			(layer "B.SilkS")
			(effects
				(font
					(size 0.7 0.7)
					(thickness 0.15)
				)
				(justify right top mirror)
			)
		)
		(property "Value" "TP_0.75mm_SMD"
			(at 0 -1.2 90)
			(layer "B.Fab")
			(effects
				(font
					(size 0.7 0.7)
					(thickness 0.15)
				)
				(justify right top mirror)
			)
		)
		(property "Description" "SMT test point"
			(at 0 0 90)
			(layer "B.Fab")
			(hide yes)
			(effects
				(font
					(size 1.27 1.27)
					(thickness 0.15)
				)
				(justify mirror)
			)
		)
		(property "MPN" ""
			(at 0 0 270)
			(unlocked yes)
			(layer "B.Fab")
			(hide yes)
			(effects
				(font
					(size 1 1)
					(thickness 0.15)
				)
				(justify mirror)
			)
		)
		(property "Manufacturer" ""
			(at 0 0 270)
			(unlocked yes)
			(layer "B.Fab")
			(hide yes)
			(effects
				(font
					(size 1 1)
					(thickness 0.15)
				)
				(justify mirror)
			)
		)
		(property "Author" "Antmicro"
			(at 0 0 270)
			(unlocked yes)
			(layer "B.Fab")
			(hide yes)
			(effects
				(font
					(size 1 1)
					(thickness 0.15)
				)
				(justify mirror)
			)
		)
		(property "License" "Apache-2.0"
			(at 0 0 270)
			(unlocked yes)
			(layer "B.Fab")
			(hide yes)
			(effects
				(font
					(size 1 1)
					(thickness 0.15)
				)
				(justify mirror)
			)
		)
		(sheetname "/SoM_Power/")
		(sheetfile "som_power.kicad_sch")
		(attr exclude_from_pos_files exclude_from_bom)
		(fp_circle
			(center 0 0)
			(end 0.475 0)
			(stroke
				(width 0.05)
				(type default)
			)
			(fill no)
			(layer "B.CrtYd")
		)
		(fp_text user "License: Apache-2.0"
			(at -0.4 -5.101 90)
			(layer "B.Fab")
			(effects
				(font
					(size 0.7 0.7)
					(thickness 0.15)
				)
				(justify right top mirror)
			)
		)
		(fp_text user "${REFERENCE}"
			(at -0.4 -2.7 90)
			(layer "B.Fab")
			(effects
				(font
					(size 0.7 0.7)
					(thickness 0.15)
				)
				(justify right top mirror)
			)
		)
		(fp_text user "Author: Antmicro"
			(at -0.4 -3.901 90)
			(layer "B.Fab")
			(effects
				(font
					(size 0.7 0.7)
					(thickness 0.15)
				)
				(justify right top mirror)
			)
		)
		(pad "1" smd circle
			(at 0 0 90)
			(size 0.75 0.75)
			(layers "B.Cu" "B.Mask")
			(net 741 "Net-(J1A-PERIPHERAL_RESET_N)")
			(pinfunction "1")
			(pintype "passive")
		)
	)
	(footprint "antmicro-footprints:TP_SMD_0.75mm"
		(layer "B.Cu")
		(at 139.030532 71.31 90)
		(property "Reference" "TP50"
			(at -3.26 0.458936 90)
			(layer "B.SilkS")
			(effects
				(font
					(size 0.7 0.7)
					(thickness 0.15)
				)
				(justify right top mirror)
			)
		)
		(property "Value" "TP_0.75mm_SMD"
			(at 0 -1.2 90)
			(layer "B.Fab")
			(effects
				(font
					(size 0.7 0.7)
					(thickness 0.15)
				)
				(justify right top mirror)
			)
		)
		(property "Description" "SMT test point"
			(at 0 0 90)
			(layer "B.Fab")
			(hide yes)
			(effects
				(font
					(size 1.27 1.27)
					(thickness 0.15)
				)
				(justify mirror)
			)
		)
		(property "MPN" ""
			(at 0 0 270)
			(unlocked yes)
			(layer "B.Fab")
			(hide yes)
			(effects
				(font
					(size 1 1)
					(thickness 0.15)
				)
				(justify mirror)
			)
		)
		(property "Manufacturer" ""
			(at 0 0 270)
			(unlocked yes)
			(layer "B.Fab")
			(hide yes)
			(effects
				(font
					(size 1 1)
					(thickness 0.15)
				)
				(justify mirror)
			)
		)
		(property "Author" "Antmicro"
			(at 0 0 270)
			(unlocked yes)
			(layer "B.Fab")
			(hide yes)
			(effects
				(font
					(size 1 1)
					(thickness 0.15)
				)
				(justify mirror)
			)
		)
		(property "License" "Apache-2.0"
			(at 0 0 270)
			(unlocked yes)
			(layer "B.Fab")
			(hide yes)
			(effects
				(font
					(size 1 1)
					(thickness 0.15)
				)
				(justify mirror)
			)
		)
		(sheetname "/SoM_Power/")
		(sheetfile "som_power.kicad_sch")
		(attr exclude_from_pos_files exclude_from_bom)
		(fp_circle
			(center 0 0)
			(end 0.475 0)
			(stroke
				(width 0.05)
				(type default)
			)
			(fill no)
			(layer "B.CrtYd")
		)
		(fp_text user "${REFERENCE}"
			(at -0.4 -2.7 90)
			(layer "B.Fab")
			(effects
				(font
					(size 0.7 0.7)
					(thickness 0.15)
				)
				(justify right top mirror)
			)
		)
		(fp_text user "Author: Antmicro"
			(at -0.4 -3.901 90)
			(layer "B.Fab")
			(effects
				(font
					(size 0.7 0.7)
					(thickness 0.15)
				)
				(justify right top mirror)
			)
		)
		(fp_text user "License: Apache-2.0"
			(at -0.4 -5.101 90)
			(layer "B.Fab")
			(effects
				(font
					(size 0.7 0.7)
					(thickness 0.15)
				)
				(justify right top mirror)
			)
		)
		(pad "1" smd circle
			(at 0 0 90)
			(size 0.75 0.75)
			(layers "B.Cu" "B.Mask")
			(net 621 "Net-(J1A-THERM_ALERT_N)")
			(pinfunction "1")
			(pintype "passive")
		)
	)
	(footprint "antmicro-footprints:SOD-523"
		(layer "B.Cu")
		(at 218.84 123.931698 90)
		(property "Reference" "D60"
			(at -1.068302 -1.54 90)
			(layer "B.SilkS")
			(effects
				(font
					(size 0.7 0.7)
					(thickness 0.15)
				)
				(justify right top mirror)
			)
		)
		(property "Value" "RB521S30T1G"
			(at 0 -1.499 90)
			(layer "B.Fab")
			(effects
				(font
					(size 0.7 0.7)
					(thickness 0.15)
				)
				(justify right top mirror)
			)
		)
		(property "Datasheet" "https://www.onsemi.com/pdf/datasheet/rb521s30t1-d.pdf"
			(at 0 0 90)
			(layer "B.Fab")
			(hide yes)
			(effects
				(font
					(size 1.27 1.27)
					(thickness 0.15)
				)
				(justify mirror)
			)
		)
		(property "Description" "Small Signal Schottky Diode, Single, 30 V, 200 mA, 500 mV, 1 A, 125 °C"
			(at 0 0 90)
			(layer "B.Fab")
			(hide yes)
			(effects
				(font
					(size 1.27 1.27)
					(thickness 0.15)
				)
				(justify mirror)
			)
		)
		(property "MPN" "RB521S30T1G"
			(at 0 0 270)
			(unlocked yes)
			(layer "B.Fab")
			(hide yes)
			(effects
				(font
					(size 1 1)
					(thickness 0.15)
				)
				(justify mirror)
			)
		)
		(property "Manufacturer" "ON Semiconductor"
			(at 0 0 270)
			(unlocked yes)
			(layer "B.Fab")
			(hide yes)
			(effects
				(font
					(size 1 1)
					(thickness 0.15)
				)
				(justify mirror)
			)
		)
		(property "Author" "Antmicro"
			(at 0 0 270)
			(unlocked yes)
			(layer "B.Fab")
			(hide yes)
			(effects
				(font
					(size 1 1)
					(thickness 0.15)
				)
				(justify mirror)
			)
		)
		(property "License" "Apache-2.0"
			(at 0 0 270)
			(unlocked yes)
			(layer "B.Fab")
			(hide yes)
			(effects
				(font
					(size 1 1)
					(thickness 0.15)
				)
				(justify mirror)
			)
		)
		(sheetname "/USB Hub/")
		(sheetfile "usb_hub.kicad_sch")
		(attr smd)
		(fp_line
			(start -0.35 0.5)
			(end -0.35 -0.5)
			(stroke
				(width 0.15)
				(type solid)
			)
			(layer "B.SilkS")
		)
		(fp_rect
			(start -1 0.6)
			(end 1 -0.6)
			(stroke
				(width 0.05)
				(type solid)
			)
			(fill no)
			(layer "B.CrtYd")
		)
		(fp_line
			(start -0.652 -0.423)
			(end 0.65 -0.423)
			(stroke
				(width 0.15)
				(type solid)
			)
			(layer "B.Fab")
		)
		(fp_line
			(start -0.652 -0.423)
			(end -0.652 0.425)
			(stroke
				(width 0.15)
				(type solid)
			)
			(layer "B.Fab")
		)
		(fp_line
			(start -0.35 0.4)
			(end -0.35 -0.4)
			(stroke
				(width 0.15)
				(type solid)
			)
			(layer "B.Fab")
		)
		(fp_line
			(start 0.65 0.425)
			(end 0.65 -0.423)
			(stroke
				(width 0.15)
				(type solid)
			)
			(layer "B.Fab")
		)
		(fp_line
			(start -0.652 0.425)
			(end 0.65 0.425)
			(stroke
				(width 0.15)
				(type solid)
			)
			(layer "B.Fab")
		)
		(fp_text user "License: Apache-2.0"
			(at -1.276 -5.9 90)
			(layer "B.Fab")
			(effects
				(font
					(size 0.7 0.7)
					(thickness 0.15)
				)
				(justify right top mirror)
			)
		)
		(fp_text user "Author: Antmicro"
			(at -1.276 -4.7 90)
			(layer "B.Fab")
			(effects
				(font
					(size 0.7 0.7)
					(thickness 0.15)
				)
				(justify right top mirror)
			)
		)
		(fp_text user "${REFERENCE}"
			(at -1.276 -3.499 90)
			(layer "B.Fab")
			(effects
				(font
					(size 0.7 0.7)
					(thickness 0.15)
				)
				(justify right top mirror)
			)
		)
		(pad "1" smd roundrect
			(at -0.701 0 90)
			(size 0.5 0.6)
			(layers "B.Cu" "B.Mask" "B.Paste")
			(roundrect_rratio 0.25)
			(net 1241 "Net-(D60-C)")
			(pinfunction "C")
			(pintype "passive")
		)
		(pad "2" smd roundrect
			(at 0.699 0 90)
			(size 0.5 0.6)
			(layers "B.Cu" "B.Mask" "B.Paste")
			(roundrect_rratio 0.25)
			(net 1240 "Net-(D60-A)")
			(pinfunction "A")
			(pintype "passive")
		)
	)
	(footprint "antmicro-footprints:R_1206_3216Metric"
		(layer "B.Cu")
		(at 92 66.1)
		(property "Reference" "R102"
			(at 1.9 2.2 180)
			(layer "B.SilkS")
			(effects
				(font
					(size 0.7 0.7)
					(thickness 0.15)
				)
				(justify left bottom mirror)
			)
		)
		(property "Value" "R_220R_1206"
			(at -2.422356 -2.103591 180)
			(layer "B.Fab")
			(effects
				(font
					(size 0.7 0.7)
					(thickness 0.15)
				)
				(justify left bottom mirror)
			)
		)
		(property "Datasheet" "https://www.bourns.com/docs/product-datasheets/cr.pdf"
			(at 0 0 180)
			(layer "B.Fab")
			(hide yes)
			(effects
				(font
					(size 1.27 1.27)
					(thickness 0.15)
				)
				(justify mirror)
			)
		)
		(property "Description" "SMT Chip Resistor, 220 ohm, ± 1%, 250 mW, 1206 [3216 Metric]"
			(at 0 0 180)
			(layer "B.Fab")
			(hide yes)
			(effects
				(font
					(size 1.27 1.27)
					(thickness 0.15)
				)
				(justify mirror)
			)
		)
		(property "MPN" "CR1206-FX-2200ELF"
			(at 0 0 180)
			(unlocked yes)
			(layer "B.Fab")
			(hide yes)
			(effects
				(font
					(size 1 1)
					(thickness 0.15)
				)
				(justify mirror)
			)
		)
		(property "Manufacturer" "Bourns"
			(at 0 0 180)
			(unlocked yes)
			(layer "B.Fab")
			(hide yes)
			(effects
				(font
					(size 1 1)
					(thickness 0.15)
				)
				(justify mirror)
			)
		)
		(property "License" "Apache-2.0"
			(at 0 0 180)
			(unlocked yes)
			(layer "B.Fab")
			(hide yes)
			(effects
				(font
					(size 1 1)
					(thickness 0.15)
				)
				(justify mirror)
			)
		)
		(property "Author" "Antmicro"
			(at 0 0 180)
			(unlocked yes)
			(layer "B.Fab")
			(hide yes)
			(effects
				(font
					(size 1 1)
					(thickness 0.15)
				)
				(justify mirror)
			)
		)
		(property "Val" "220R"
			(at 0 0 180)
			(unlocked yes)
			(layer "B.Fab")
			(hide yes)
			(effects
				(font
					(size 1 1)
					(thickness 0.15)
				)
				(justify mirror)
			)
		)
		(property "Tolerance" "1%"
			(at 0 0 180)
			(unlocked yes)
			(layer "B.Fab")
			(hide yes)
			(effects
				(font
					(size 1 1)
					(thickness 0.15)
				)
				(justify mirror)
			)
		)
		(sheetname "/SoM_Power/")
		(sheetfile "som_power.kicad_sch")
		(attr smd)
		(fp_line
			(start 0.8 -0.901)
			(end -0.8 -0.901)
			(stroke
				(width 0.15)
				(type solid)
			)
			(layer "B.SilkS")
		)
		(fp_line
			(start 0.8 0.899)
			(end -0.8 0.899)
			(stroke
				(width 0.15)
				(type solid)
			)
			(layer "B.SilkS")
		)
		(fp_rect
			(start -2.325 1.15)
			(end 2.325 -1.15)
			(stroke
				(width 0.05)
				(type default)
			)
			(fill no)
			(layer "B.CrtYd")
		)
		(fp_line
			(start -1.601 -0.8)
			(end 1.6 -0.8)
			(stroke
				(width 0.15)
				(type solid)
			)
			(layer "B.Fab")
		)
		(fp_line
			(start -1.601 0.802)
			(end -1.601 -0.8)
			(stroke
				(width 0.15)
				(type solid)
			)
			(layer "B.Fab")
		)
		(fp_line
			(start -1.601 0.802)
			(end 1.6 0.802)
			(stroke
				(width 0.15)
				(type solid)
			)
			(layer "B.Fab")
		)
		(fp_line
			(start 1.6 0.802)
			(end 1.6 -0.8)
			(stroke
				(width 0.15)
				(type solid)
			)
			(layer "B.Fab")
		)
		(fp_text user "Author: Antmicro"
			(at -2.401 -4.899 180)
			(layer "B.Fab")
			(effects
				(font
					(size 0.7 0.7)
					(thickness 0.15)
				)
				(justify left bottom mirror)
			)
		)
		(fp_text user "${REFERENCE}"
			(at -2.401 -3.5 180)
			(layer "B.Fab")
			(effects
				(font
					(size 0.7 0.7)
					(thickness 0.15)
				)
				(justify left bottom mirror)
			)
		)
		(fp_text user "License: Apache-2.0"
			(at -2.401 -6.3 180)
			(layer "B.Fab")
			(effects
				(font
					(size 0.7 0.7)
					(thickness 0.15)
				)
				(justify left bottom mirror)
			)
		)
		(pad "1" smd roundrect
			(at -1.5 -0.001)
			(size 1.15 1.8)
			(layers "B.Cu" "B.Mask" "B.Paste")
			(roundrect_rratio 0.25)
			(net 884 "Net-(Q8-D)")
			(pintype "passive")
		)
		(pad "2" smd roundrect
			(at 1.5 -0.001)
			(size 1.15 1.8)
			(layers "B.Cu" "B.Mask" "B.Paste")
			(roundrect_rratio 0.25)
			(net 12 "SYS_VIN_HV")
			(pintype "passive")
		)
	)
	(footprint "antmicro-footprints:TP_SMD_0.75mm"
		(layer "B.Cu")
		(at 174.14 58 180)
		(property "Reference" "TP131"
			(at -0.43 4.04 270)
			(layer "B.SilkS")
			(effects
				(font
					(size 0.7 0.7)
					(thickness 0.15)
				)
				(justify left bottom mirror)
			)
		)
		(property "Value" "TP_0.75mm_SMD"
			(at 0 -1.2 0)
			(layer "B.Fab")
			(effects
				(font
					(size 0.7 0.7)
					(thickness 0.15)
				)
				(justify left bottom mirror)
			)
		)
		(property "Description" "SMT test point"
			(at 0 0 0)
			(layer "B.Fab")
			(hide yes)
			(effects
				(font
					(size 1.27 1.27)
					(thickness 0.15)
				)
				(justify mirror)
			)
		)
		(property "MPN" ""
			(at 0 0 0)
			(unlocked yes)
			(layer "B.Fab")
			(hide yes)
			(effects
				(font
					(size 1 1)
					(thickness 0.15)
				)
				(justify mirror)
			)
		)
		(property "Manufacturer" ""
			(at 0 0 0)
			(unlocked yes)
			(layer "B.Fab")
			(hide yes)
			(effects
				(font
					(size 1 1)
					(thickness 0.15)
				)
				(justify mirror)
			)
		)
		(property "Author" "Antmicro"
			(at 0 0 0)
			(unlocked yes)
			(layer "B.Fab")
			(hide yes)
			(effects
				(font
					(size 1 1)
					(thickness 0.15)
				)
				(justify mirror)
			)
		)
		(property "License" "Apache-2.0"
			(at 0 0 0)
			(unlocked yes)
			(layer "B.Fab")
			(hide yes)
			(effects
				(font
					(size 1 1)
					(thickness 0.15)
				)
				(justify mirror)
			)
		)
		(sheetname "/Power/")
		(sheetfile "power.kicad_sch")
		(attr exclude_from_pos_files exclude_from_bom)
		(fp_circle
			(center 0 0)
			(end 0.475 0)
			(stroke
				(width 0.05)
				(type default)
			)
			(fill no)
			(layer "B.CrtYd")
		)
		(fp_text user "License: Apache-2.0"
			(at -0.4 -5.101 0)
			(layer "B.Fab")
			(effects
				(font
					(size 0.7 0.7)
					(thickness 0.15)
				)
				(justify left bottom mirror)
			)
		)
		(fp_text user "${REFERENCE}"
			(at -0.4 -2.7 0)
			(layer "B.Fab")
			(effects
				(font
					(size 0.7 0.7)
					(thickness 0.15)
				)
				(justify left bottom mirror)
			)
		)
		(fp_text user "Author: Antmicro"
			(at -0.4 -3.901 0)
			(layer "B.Fab")
			(effects
				(font
					(size 0.7 0.7)
					(thickness 0.15)
				)
				(justify left bottom mirror)
			)
		)
		(pad "1" smd circle
			(at 0 0 180)
			(size 0.75 0.75)
			(layers "B.Cu" "B.Mask")
			(net 491 "+5V_AON")
			(pinfunction "1")
			(pintype "passive")
		)
	)
	(footprint "antmicro-footprints:R_0402_1005Metric"
		(layer "B.Cu")
		(at 124.6 108.8 180)
		(descr "Resistor SMD 0402")
		(tags "resistor SMD 0402")
		(property "Reference" "R210"
			(at -3.9 -0.4 0)
			(layer "B.SilkS")
			(effects
				(font
					(size 0.7 0.7)
					(thickness 0.15)
				)
				(justify left bottom mirror)
			)
		)
		(property "Value" "R_47k_0402"
			(at -1.011843 -1.772046 0)
			(layer "B.Fab")
			(effects
				(font
					(size 0.7 0.7)
					(thickness 0.15)
				)
				(justify left bottom mirror)
			)
		)
		(property "Datasheet" "https://www.bourns.com/docs/product-datasheets/cr.pdf"
			(at 0 0 0)
			(layer "B.Fab")
			(hide yes)
			(effects
				(font
					(size 1.27 1.27)
					(thickness 0.15)
				)
				(justify mirror)
			)
		)
		(property "Description" "SMD Chip Resistor, 47 kohm, ± 1%, 62.5 mW, 0402 [1005 Metric], Thick Film, General Purpose"
			(at 0 0 0)
			(layer "B.Fab")
			(hide yes)
			(effects
				(font
					(size 1.27 1.27)
					(thickness 0.15)
				)
				(justify mirror)
			)
		)
		(property "Manufacturer" "Bourns"
			(at 0 0 0)
			(unlocked yes)
			(layer "B.Fab")
			(hide yes)
			(effects
				(font
					(size 1 1)
					(thickness 0.15)
				)
				(justify mirror)
			)
		)
		(property "MPN" "CR0402-FX-4702GLF"
			(at 0 0 0)
			(unlocked yes)
			(layer "B.Fab")
			(hide yes)
			(effects
				(font
					(size 1 1)
					(thickness 0.15)
				)
				(justify mirror)
			)
		)
		(property "Val" "47k"
			(at 0 0 0)
			(unlocked yes)
			(layer "B.Fab")
			(hide yes)
			(effects
				(font
					(size 1 1)
					(thickness 0.15)
				)
				(justify mirror)
			)
		)
		(property "License" "Apache-2.0"
			(at 0 0 0)
			(unlocked yes)
			(layer "B.Fab")
			(hide yes)
			(effects
				(font
					(size 1 1)
					(thickness 0.15)
				)
				(justify mirror)
			)
		)
		(property "Author" "Antmicro"
			(at 0 0 0)
			(unlocked yes)
			(layer "B.Fab")
			(hide yes)
			(effects
				(font
					(size 1 1)
					(thickness 0.15)
				)
				(justify mirror)
			)
		)
		(property "Tolerance" "1%"
			(at 0 0 0)
			(unlocked yes)
			(layer "B.Fab")
			(hide yes)
			(effects
				(font
					(size 1 1)
					(thickness 0.15)
				)
				(justify mirror)
			)
		)
		(sheetname "/M.2/")
		(sheetfile "m2.kicad_sch")
		(attr smd exclude_from_pos_files exclude_from_bom dnp)
		(fp_poly
			(pts
				(xy -0.925 0.47) (xy 0.925 0.47) (xy 0.925 -0.47) (xy -0.925 -0.47)
			)
			(stroke
				(width 0.05)
				(type default)
			)
			(fill no)
			(layer "B.CrtYd")
		)
		(fp_poly
			(pts
				(xy -0.5 0.25) (xy 0.5 0.25) (xy 0.5 -0.25) (xy -0.5 -0.25)
			)
			(stroke
				(width 0.15)
				(type solid)
			)
			(fill no)
			(layer "B.Fab")
		)
		(fp_text user "Author: Antmicro"
			(at -0.95 -4.169 0)
			(layer "B.Fab")
			(effects
				(font
					(size 0.7 0.7)
					(thickness 0.15)
				)
				(justify left bottom mirror)
			)
		)
		(fp_text user "${REFERENCE}"
			(at -0.95 -3.168 0)
			(layer "B.Fab")
			(effects
				(font
					(size 0.7 0.7)
					(thickness 0.15)
				)
				(justify left bottom mirror)
			)
		)
		(fp_text user "License: Apache-2.0"
			(at -0.949999 -5.169 0)
			(layer "B.Fab")
			(effects
				(font
					(size 0.7 0.7)
					(thickness 0.15)
				)
				(justify left bottom mirror)
			)
		)
		(pad "1" smd roundrect
			(at -0.48 0 180)
			(size 0.59 0.64)
			(layers "B.Cu" "B.Mask" "B.Paste")
			(roundrect_rratio 0.25)
			(net 2 "+3V3")
			(pintype "passive")
		)
		(pad "2" smd roundrect
			(at 0.48 0 180)
			(size 0.59 0.64)
			(layers "B.Cu" "B.Mask" "B.Paste")
			(roundrect_rratio 0.25)
			(net 825 "/M.2/~{CLKREQ_M}")
			(pintype "passive")
		)
	)
	(footprint "antmicro-footprints:R_0402_1005Metric"
		(layer "B.Cu")
		(at 142.8 71.7 -90)
		(descr "Resistor SMD 0402")
		(tags "resistor SMD 0402")
		(property "Reference" "R290"
			(at -1 -2.5 90)
			(layer "B.SilkS")
			(effects
				(font
					(size 0.7 0.7)
					(thickness 0.15)
				)
				(justify left bottom mirror)
			)
		)
		(property "Value" "R_0R_0402"
			(at -1.011843 -1.772047 90)
			(layer "B.Fab")
			(effects
				(font
					(size 0.7 0.7)
					(thickness 0.15)
				)
				(justify left bottom mirror)
			)
		)
		(property "Datasheet" "https://industrial.panasonic.com/cdbs/www-data/pdf/RDA0000/AOA0000C301.pdf"
			(at 0 0 90)
			(layer "B.Fab")
			(hide yes)
			(effects
				(font
					(size 1.27 1.27)
					(thickness 0.15)
				)
				(justify mirror)
			)
		)
		(property "Description" "SMD Chip Resistor, Jumper, 0 ohm, 100 mW, 0402 [1005 Metric], Thick Film, General Purpose"
			(at 0 0 90)
			(layer "B.Fab")
			(hide yes)
			(effects
				(font
					(size 1.27 1.27)
					(thickness 0.15)
				)
				(justify mirror)
			)
		)
		(property "MPN" "ERJ2GE0R00X"
			(at 0 0 90)
			(unlocked yes)
			(layer "B.Fab")
			(hide yes)
			(effects
				(font
					(size 1 1)
					(thickness 0.15)
				)
				(justify mirror)
			)
		)
		(property "Manufacturer" "Panasonic"
			(at 0 0 90)
			(unlocked yes)
			(layer "B.Fab")
			(hide yes)
			(effects
				(font
					(size 1 1)
					(thickness 0.15)
				)
				(justify mirror)
			)
		)
		(property "License" "Apache-2.0"
			(at 0 0 90)
			(unlocked yes)
			(layer "B.Fab")
			(hide yes)
			(effects
				(font
					(size 1 1)
					(thickness 0.15)
				)
				(justify mirror)
			)
		)
		(property "Author" "Antmicro"
			(at 0 0 90)
			(unlocked yes)
			(layer "B.Fab")
			(hide yes)
			(effects
				(font
					(size 1 1)
					(thickness 0.15)
				)
				(justify mirror)
			)
		)
		(property "Val" "0R"
			(at 0 0 90)
			(unlocked yes)
			(layer "B.Fab")
			(hide yes)
			(effects
				(font
					(size 1 1)
					(thickness 0.15)
				)
				(justify mirror)
			)
		)
		(property "Tolerance" "~"
			(at 0 0 90)
			(unlocked yes)
			(layer "B.Fab")
			(hide yes)
			(effects
				(font
					(size 1 1)
					(thickness 0.15)
				)
				(justify mirror)
			)
		)
		(property "Current" "1A"
			(at 0 0 90)
			(unlocked yes)
			(layer "B.Fab")
			(hide yes)
			(effects
				(font
					(size 1 1)
					(thickness 0.15)
				)
				(justify mirror)
			)
		)
		(sheetname "/SoM_IO2/")
		(sheetfile "som_io2.kicad_sch")
		(attr smd exclude_from_pos_files exclude_from_bom dnp)
		(fp_rect
			(start -0.925 0.47)
			(end 0.925 -0.47)
			(stroke
				(width 0.05)
				(type default)
			)
			(fill no)
			(layer "B.CrtYd")
		)
		(fp_rect
			(start -0.5 0.25)
			(end 0.5 -0.25)
			(stroke
				(width 0.15)
				(type solid)
			)
			(fill no)
			(layer "B.Fab")
		)
		(fp_text user "Author: Antmicro"
			(at -0.95 -4.169 90)
			(layer "B.Fab")
			(effects
				(font
					(size 0.7 0.7)
					(thickness 0.15)
				)
				(justify left bottom mirror)
			)
		)
		(fp_text user "${REFERENCE}"
			(at -0.95 -3.168 90)
			(layer "B.Fab")
			(effects
				(font
					(size 0.7 0.7)
					(thickness 0.15)
				)
				(justify left bottom mirror)
			)
		)
		(fp_text user "License: Apache-2.0"
			(at -0.95 -5.169 90)
			(layer "B.Fab")
			(effects
				(font
					(size 0.7 0.7)
					(thickness 0.15)
				)
				(justify left bottom mirror)
			)
		)
		(pad "1" smd roundrect
			(at -0.48 0 270)
			(size 0.59 0.64)
			(layers "B.Cu" "B.Mask" "B.Paste")
			(roundrect_rratio 0.25)
			(net 11 "+1V8")
			(pintype "passive")
		)
		(pad "2" smd roundrect
			(at 0.48 0 270)
			(size 0.59 0.64)
			(layers "B.Cu" "B.Mask" "B.Paste")
			(roundrect_rratio 0.25)
			(net 606 "/SoM_IO2/NVJTAG_SEL")
			(pintype "passive")
		)
	)
	(footprint "antmicro-footprints:C_0402_1005Metric"
		(layer "B.Cu")
		(at 110.25 98.5)
		(descr "Capacitor SMD 0402")
		(tags "capacitor SMD 0402")
		(property "Reference" "C184"
			(at -0.95 -0.4 0)
			(layer "B.SilkS")
			(effects
				(font
					(size 0.7 0.7)
					(thickness 0.15)
				)
				(justify left top mirror)
			)
		)
		(property "Value" "C_220n_0402"
			(at -1.022927 -2.155213 0)
			(layer "B.Fab")
			(effects
				(font
					(size 0.7 0.7)
					(thickness 0.15)
				)
				(justify right top mirror)
			)
		)
		(property "Datasheet" "https://www.yageo.com/en/Chart/Download/pdf/CC0402KRX5R6BB224"
			(at 0 0 0)
			(layer "B.Fab")
			(hide yes)
			(effects
				(font
					(size 1.27 1.27)
					(thickness 0.15)
				)
				(justify mirror)
			)
		)
		(property "Description" "SMD Multilayer Ceramic Capacitor, 0.22 µF, 10 V, 0402 [1005 Metric], ± 10%, X5R, CC Series"
			(at 0 0 0)
			(layer "B.Fab")
			(hide yes)
			(effects
				(font
					(size 1.27 1.27)
					(thickness 0.15)
				)
				(justify mirror)
			)
		)
		(property "MPN" "CC0402KRX5R6BB224"
			(at 0 0 0)
			(unlocked yes)
			(layer "B.Fab")
			(hide yes)
			(effects
				(font
					(size 1 1)
					(thickness 0.15)
				)
				(justify mirror)
			)
		)
		(property "Val" "220n"
			(at 0 0 0)
			(unlocked yes)
			(layer "B.Fab")
			(hide yes)
			(effects
				(font
					(size 1 1)
					(thickness 0.15)
				)
				(justify mirror)
			)
		)
		(property "Voltage" "25V"
			(at 0 0 0)
			(unlocked yes)
			(layer "B.Fab")
			(hide yes)
			(effects
				(font
					(size 1 1)
					(thickness 0.15)
				)
				(justify mirror)
			)
		)
		(property "Dielectric" "X7R"
			(at 0 0 0)
			(unlocked yes)
			(layer "B.Fab")
			(hide yes)
			(effects
				(font
					(size 1 1)
					(thickness 0.15)
				)
				(justify mirror)
			)
		)
		(property "Manufacturer" "YAGEO"
			(at 0 0 0)
			(unlocked yes)
			(layer "B.Fab")
			(hide yes)
			(effects
				(font
					(size 1 1)
					(thickness 0.15)
				)
				(justify mirror)
			)
		)
		(property "License" "Apache-2.0"
			(at 0 0 0)
			(unlocked yes)
			(layer "B.Fab")
			(hide yes)
			(effects
				(font
					(size 1 1)
					(thickness 0.15)
				)
				(justify mirror)
			)
		)
		(property "Author" "Antmicro"
			(at 0 0 0)
			(unlocked yes)
			(layer "B.Fab")
			(hide yes)
			(effects
				(font
					(size 1 1)
					(thickness 0.15)
				)
				(justify mirror)
			)
		)
		(property "Public" "False"
			(at 0 0 0)
			(unlocked yes)
			(layer "B.Fab")
			(hide yes)
			(effects
				(font
					(size 1 1)
					(thickness 0.15)
				)
				(justify mirror)
			)
		)
		(sheetname "/M.2/")
		(sheetfile "m2.kicad_sch")
		(attr smd)
		(fp_poly
			(pts
				(xy -0.925 0.47) (xy -0.925 -0.47) (xy 0.925 -0.47) (xy 0.925 0.47)
			)
			(stroke
				(width 0.05)
				(type default)
			)
			(fill no)
			(layer "B.CrtYd")
		)
		(fp_line
			(start -0.494 -0.248)
			(end -0.494 0.25)
			(stroke
				(width 0.15)
				(type solid)
			)
			(layer "B.Fab")
		)
		(fp_line
			(start -0.494 0.25)
			(end 0.504 0.25)
			(stroke
				(width 0.15)
				(type solid)
			)
			(layer "B.Fab")
		)
		(fp_line
			(start 0.504 -0.248)
			(end -0.494 -0.248)
			(stroke
				(width 0.15)
				(type solid)
			)
			(layer "B.Fab")
		)
		(fp_line
			(start 0.504 0.25)
			(end 0.504 -0.248)
			(stroke
				(width 0.15)
				(type solid)
			)
			(layer "B.Fab")
		)
		(fp_text user "License: Apache-2.0"
			(at -0.939 -5.799 0)
			(layer "B.Fab")
			(effects
				(font
					(size 0.7 0.7)
					(thickness 0.15)
				)
				(justify right top mirror)
			)
		)
		(fp_text user "Author: Antmicro"
			(at -0.939 -3.399 0)
			(layer "B.Fab")
			(effects
				(font
					(size 0.7 0.7)
					(thickness 0.15)
				)
				(justify right top mirror)
			)
		)
		(fp_text user "${REFERENCE}"
			(at -0.939 -4.599 0)
			(layer "B.Fab")
			(effects
				(font
					(size 0.7 0.7)
					(thickness 0.15)
				)
				(justify right top mirror)
			)
		)
		(pad "1" smd roundrect
			(at -0.48 0)
			(size 0.59 0.64)
			(layers "B.Cu" "B.Mask" "B.Paste")
			(roundrect_rratio 0.25)
			(net 410 "/M.2/PCIe_{C5x4}.TX3+")
			(pintype "passive")
		)
		(pad "2" smd roundrect
			(at 0.48 0)
			(size 0.59 0.64)
			(layers "B.Cu" "B.Mask" "B.Paste")
			(roundrect_rratio 0.25)
			(net 408 "/M.2/M2_M_PET3_P")
			(pintype "passive")
		)
	)
	(footprint "antmicro-footprints:R_0402_1005Metric"
		(layer "B.Cu")
		(at 115.78 116.58)
		(descr "Resistor SMD 0402")
		(tags "resistor SMD 0402")
		(property "Reference" "R211"
			(at 3.12 -0.38 0)
			(layer "B.SilkS")
			(effects
				(font
					(size 0.7 0.7)
					(thickness 0.15)
				)
				(justify right top mirror)
			)
		)
		(property "Value" "R_200R_0402"
			(at -1.011843 -1.772047 0)
			(layer "B.Fab")
			(effects
				(font
					(size 0.7 0.7)
					(thickness 0.15)
				)
				(justify right top mirror)
			)
		)
		(property "Datasheet" "https://www.bourns.com/docs/product-datasheets/cr.pdf"
			(at 0 0 0)
			(layer "B.Fab")
			(hide yes)
			(effects
				(font
					(size 1.27 1.27)
					(thickness 0.15)
				)
				(justify mirror)
			)
		)
		(property "Description" "SMD Chip Resistor, 200 ohm, ± 1%, 62.5 mW, 0402 [1005 Metric], Thick Film, General Purpose"
			(at 0 0 0)
			(layer "B.Fab")
			(hide yes)
			(effects
				(font
					(size 1.27 1.27)
					(thickness 0.15)
				)
				(justify mirror)
			)
		)
		(property "Manufacturer" "Bourns"
			(at 0 0 180)
			(unlocked yes)
			(layer "B.Fab")
			(hide yes)
			(effects
				(font
					(size 1 1)
					(thickness 0.15)
				)
				(justify mirror)
			)
		)
		(property "MPN" "CR0402-FX-2000GLF"
			(at 0 0 180)
			(unlocked yes)
			(layer "B.Fab")
			(hide yes)
			(effects
				(font
					(size 1 1)
					(thickness 0.15)
				)
				(justify mirror)
			)
		)
		(property "Val" "200R"
			(at 0 0 180)
			(unlocked yes)
			(layer "B.Fab")
			(hide yes)
			(effects
				(font
					(size 1 1)
					(thickness 0.15)
				)
				(justify mirror)
			)
		)
		(property "License" "Apache-2.0"
			(at 0 0 180)
			(unlocked yes)
			(layer "B.Fab")
			(hide yes)
			(effects
				(font
					(size 1 1)
					(thickness 0.15)
				)
				(justify mirror)
			)
		)
		(property "Author" "Antmicro"
			(at 0 0 180)
			(unlocked yes)
			(layer "B.Fab")
			(hide yes)
			(effects
				(font
					(size 1 1)
					(thickness 0.15)
				)
				(justify mirror)
			)
		)
		(property "Tolerance" "1%"
			(at 0 0 180)
			(unlocked yes)
			(layer "B.Fab")
			(hide yes)
			(effects
				(font
					(size 1 1)
					(thickness 0.15)
				)
				(justify mirror)
			)
		)
		(sheetname "/M.2/")
		(sheetfile "m2.kicad_sch")
		(attr smd)
		(fp_rect
			(start -0.925 0.47)
			(end 0.925 -0.47)
			(stroke
				(width 0.05)
				(type default)
			)
			(fill no)
			(layer "B.CrtYd")
		)
		(fp_rect
			(start -0.5 0.25)
			(end 0.5 -0.25)
			(stroke
				(width 0.15)
				(type solid)
			)
			(fill no)
			(layer "B.Fab")
		)
		(fp_text user "Author: Antmicro"
			(at -0.95 -4.169 0)
			(layer "B.Fab")
			(effects
				(font
					(size 0.7 0.7)
					(thickness 0.15)
				)
				(justify right top mirror)
			)
		)
		(fp_text user "License: Apache-2.0"
			(at -0.95 -5.169 0)
			(layer "B.Fab")
			(effects
				(font
					(size 0.7 0.7)
					(thickness 0.15)
				)
				(justify right top mirror)
			)
		)
		(fp_text user "${REFERENCE}"
			(at -0.95 -3.168 0)
			(layer "B.Fab")
			(effects
				(font
					(size 0.7 0.7)
					(thickness 0.15)
				)
				(justify right top mirror)
			)
		)
		(pad "1" smd roundrect
			(at -0.48 0)
			(size 0.59 0.64)
			(layers "B.Cu" "B.Mask" "B.Paste")
			(roundrect_rratio 0.25)
			(net 544 "Net-(D32-A)")
			(pintype "passive")
		)
		(pad "2" smd roundrect
			(at 0.48 0)
			(size 0.59 0.64)
			(layers "B.Cu" "B.Mask" "B.Paste")
			(roundrect_rratio 0.25)
			(net 2 "+3V3")
			(pintype "passive")
		)
	)
	(footprint "antmicro-footprints:C_0402_1005Metric"
		(layer "B.Cu")
		(at 126.5635 141.8 180)
		(descr "Capacitor SMD 0402")
		(tags "capacitor SMD 0402")
		(property "Reference" "C207"
			(at -1.899968 0.584 0)
			(layer "B.SilkS")
			(effects
				(font
					(size 0.7 0.7)
					(thickness 0.15)
				)
				(justify left bottom mirror)
			)
		)
		(property "Value" "C_10u_0402"
			(at -1.022927 -2.155213 0)
			(layer "B.Fab")
			(effects
				(font
					(size 0.7 0.7)
					(thickness 0.15)
				)
				(justify left bottom mirror)
			)
		)
		(property "Datasheet" "https://www.yageo.com/en/Chart/Download/pdf/CC0402MRX5R5BB106"
			(at 0 0 0)
			(layer "B.Fab")
			(hide yes)
			(effects
				(font
					(size 1.27 1.27)
					(thickness 0.15)
				)
				(justify mirror)
			)
		)
		(property "Description" "SMD Multilayer Ceramic Capacitor, 10 µF, 6.3 V, 0402 [1005 Metric], ± 20%, X5R, CC Series"
			(at 0 0 0)
			(layer "B.Fab")
			(hide yes)
			(effects
				(font
					(size 1.27 1.27)
					(thickness 0.15)
				)
				(justify mirror)
			)
		)
		(property "MPN" "CC0402MRX5R5BB106"
			(at 0 0 0)
			(unlocked yes)
			(layer "B.Fab")
			(hide yes)
			(effects
				(font
					(size 1 1)
					(thickness 0.15)
				)
				(justify mirror)
			)
		)
		(property "Manufacturer" "YAGEO"
			(at 0 0 0)
			(unlocked yes)
			(layer "B.Fab")
			(hide yes)
			(effects
				(font
					(size 1 1)
					(thickness 0.15)
				)
				(justify mirror)
			)
		)
		(property "License" "Apache-2.0"
			(at 0 0 0)
			(unlocked yes)
			(layer "B.Fab")
			(hide yes)
			(effects
				(font
					(size 1 1)
					(thickness 0.15)
				)
				(justify mirror)
			)
		)
		(property "Author" "Antmicro"
			(at 0 0 0)
			(unlocked yes)
			(layer "B.Fab")
			(hide yes)
			(effects
				(font
					(size 1 1)
					(thickness 0.15)
				)
				(justify mirror)
			)
		)
		(property "Val" "10u"
			(at 0 0 0)
			(unlocked yes)
			(layer "B.Fab")
			(hide yes)
			(effects
				(font
					(size 1 1)
					(thickness 0.15)
				)
				(justify mirror)
			)
		)
		(property "Voltage" "16V"
			(at 0 0 0)
			(unlocked yes)
			(layer "B.Fab")
			(hide yes)
			(effects
				(font
					(size 1 1)
					(thickness 0.15)
				)
				(justify mirror)
			)
		)
		(property "Dielectric" ""
			(at 0 0 0)
			(unlocked yes)
			(layer "B.Fab")
			(hide yes)
			(effects
				(font
					(size 1 1)
					(thickness 0.15)
				)
				(justify mirror)
			)
		)
		(sheetname "/Peripherals/")
		(sheetfile "peripherals.kicad_sch")
		(attr smd)
		(fp_rect
			(start -0.925 0.47)
			(end 0.925 -0.47)
			(stroke
				(width 0.05)
				(type default)
			)
			(fill no)
			(layer "B.CrtYd")
		)
		(fp_line
			(start 0.504 0.25)
			(end 0.504 -0.248)
			(stroke
				(width 0.15)
				(type solid)
			)
			(layer "B.Fab")
		)
		(fp_line
			(start 0.504 -0.248)
			(end -0.494 -0.248)
			(stroke
				(width 0.15)
				(type solid)
			)
			(layer "B.Fab")
		)
		(fp_line
			(start -0.494 0.25)
			(end 0.504 0.25)
			(stroke
				(width 0.15)
				(type solid)
			)
			(layer "B.Fab")
		)
		(fp_line
			(start -0.494 -0.248)
			(end -0.494 0.25)
			(stroke
				(width 0.15)
				(type solid)
			)
			(layer "B.Fab")
		)
		(fp_text user "${REFERENCE}"
			(at -0.939 -4.599 0)
			(layer "B.Fab")
			(effects
				(font
					(size 0.7 0.7)
					(thickness 0.15)
				)
				(justify left bottom mirror)
			)
		)
		(fp_text user "License: Apache-2.0"
			(at -0.939 -5.799 0)
			(layer "B.Fab")
			(effects
				(font
					(size 0.7 0.7)
					(thickness 0.15)
				)
				(justify left bottom mirror)
			)
		)
		(fp_text user "Author: Antmicro"
			(at -0.939 -3.399 0)
			(layer "B.Fab")
			(effects
				(font
					(size 0.7 0.7)
					(thickness 0.15)
				)
				(justify left bottom mirror)
			)
		)
		(pad "1" smd roundrect
			(at -0.48 0 180)
			(size 0.59 0.64)
			(layers "B.Cu" "B.Mask" "B.Paste")
			(roundrect_rratio 0.25)
			(net 1 "GND")
			(pintype "passive")
		)
		(pad "2" smd roundrect
			(at 0.48 0 180)
			(size 0.59 0.64)
			(layers "B.Cu" "B.Mask" "B.Paste")
			(roundrect_rratio 0.25)
			(net 2 "+3V3")
			(pintype "passive")
		)
	)
	(footprint "antmicro-footprints:C_0402_1005Metric"
		(layer "B.Cu")
		(at 214.4 87.2 -90)
		(descr "Capacitor SMD 0402")
		(tags "capacitor SMD 0402")
		(property "Reference" "C125"
			(at 0.8 -0.4 90)
			(layer "B.SilkS")
			(effects
				(font
					(size 0.7 0.7)
					(thickness 0.15)
				)
				(justify left bottom mirror)
			)
		)
		(property "Value" "C_100n_0402"
			(at -1.022927 -2.155213 90)
			(layer "B.Fab")
			(effects
				(font
					(size 0.7 0.7)
					(thickness 0.15)
				)
				(justify left bottom mirror)
			)
		)
		(property "Datasheet" "https://www.murata.com/products/productdetail?partno=GRM155R61H104KE14%23"
			(at 0 0 90)
			(layer "B.Fab")
			(hide yes)
			(effects
				(font
					(size 1.27 1.27)
					(thickness 0.15)
				)
				(justify mirror)
			)
		)
		(property "Description" "SMD Multilayer Ceramic Capacitor, 0.1 µF, 50 V, 0402 [1005 Metric], ± 10%, X5R, GRM Series"
			(at 0 0 90)
			(layer "B.Fab")
			(hide yes)
			(effects
				(font
					(size 1.27 1.27)
					(thickness 0.15)
				)
				(justify mirror)
			)
		)
		(property "Manufacturer" "Murata"
			(at 0 0 90)
			(unlocked yes)
			(layer "B.Fab")
			(hide yes)
			(effects
				(font
					(size 1 1)
					(thickness 0.15)
				)
				(justify mirror)
			)
		)
		(property "MPN" "GRM155R61H104KE14D"
			(at 0 0 90)
			(unlocked yes)
			(layer "B.Fab")
			(hide yes)
			(effects
				(font
					(size 1 1)
					(thickness 0.15)
				)
				(justify mirror)
			)
		)
		(property "Val" "100n"
			(at 0 0 90)
			(unlocked yes)
			(layer "B.Fab")
			(hide yes)
			(effects
				(font
					(size 1 1)
					(thickness 0.15)
				)
				(justify mirror)
			)
		)
		(property "License" "Apache-2.0"
			(at 0 0 90)
			(unlocked yes)
			(layer "B.Fab")
			(hide yes)
			(effects
				(font
					(size 1 1)
					(thickness 0.15)
				)
				(justify mirror)
			)
		)
		(property "Author" "Antmicro"
			(at 0 0 90)
			(unlocked yes)
			(layer "B.Fab")
			(hide yes)
			(effects
				(font
					(size 1 1)
					(thickness 0.15)
				)
				(justify mirror)
			)
		)
		(property "Voltage" "50V"
			(at 0 0 90)
			(unlocked yes)
			(layer "B.Fab")
			(hide yes)
			(effects
				(font
					(size 1 1)
					(thickness 0.15)
				)
				(justify mirror)
			)
		)
		(property "Dielectric" "X5R"
			(at 0 0 90)
			(unlocked yes)
			(layer "B.Fab")
			(hide yes)
			(effects
				(font
					(size 1 1)
					(thickness 0.15)
				)
				(justify mirror)
			)
		)
		(sheetname "/USB DP Alt mode/")
		(sheetfile "usb_dp.kicad_sch")
		(attr smd)
		(fp_poly
			(pts
				(xy -0.925 0.47) (xy -0.925 -0.47) (xy 0.925 -0.47) (xy 0.925 0.47)
			)
			(stroke
				(width 0.05)
				(type default)
			)
			(fill no)
			(layer "B.CrtYd")
		)
		(fp_line
			(start -0.494 0.25)
			(end 0.504 0.25)
			(stroke
				(width 0.15)
				(type solid)
			)
			(layer "B.Fab")
		)
		(fp_line
			(start 0.504 0.25)
			(end 0.504 -0.248)
			(stroke
				(width 0.15)
				(type solid)
			)
			(layer "B.Fab")
		)
		(fp_line
			(start -0.494 -0.248)
			(end -0.494 0.25)
			(stroke
				(width 0.15)
				(type solid)
			)
			(layer "B.Fab")
		)
		(fp_line
			(start 0.504 -0.248)
			(end -0.494 -0.248)
			(stroke
				(width 0.15)
				(type solid)
			)
			(layer "B.Fab")
		)
		(fp_text user "Author: Antmicro"
			(at -0.939 -3.399 90)
			(layer "B.Fab")
			(effects
				(font
					(size 0.7 0.7)
					(thickness 0.15)
				)
				(justify left bottom mirror)
			)
		)
		(fp_text user "License: Apache-2.0"
			(at -0.939 -5.799 90)
			(layer "B.Fab")
			(effects
				(font
					(size 0.7 0.7)
					(thickness 0.15)
				)
				(justify left bottom mirror)
			)
		)
		(fp_text user "${REFERENCE}"
			(at -0.939 -4.599 90)
			(layer "B.Fab")
			(effects
				(font
					(size 0.7 0.7)
					(thickness 0.15)
				)
				(justify left bottom mirror)
			)
		)
		(pad "1" smd roundrect
			(at -0.48 0 270)
			(size 0.59 0.64)
			(layers "B.Cu" "B.Mask" "B.Paste")
			(roundrect_rratio 0.25)
			(net 2 "+3V3")
			(pintype "passive")
		)
		(pad "2" smd roundrect
			(at 0.48 0 270)
			(size 0.59 0.64)
			(layers "B.Cu" "B.Mask" "B.Paste")
			(roundrect_rratio 0.25)
			(net 1 "GND")
			(pintype "passive")
		)
	)
	(footprint "antmicro-footprints:R_0402_1005Metric"
		(layer "B.Cu")
		(at 145.6 65.2 90)
		(descr "Resistor SMD 0402")
		(tags "resistor SMD 0402")
		(property "Reference" "R244"
			(at -3.6 -0.4 90)
			(layer "B.SilkS")
			(effects
				(font
					(size 0.7 0.7)
					(thickness 0.15)
				)
				(justify right top mirror)
			)
		)
		(property "Value" "R_100k_0402"
			(at -1.011843 -1.772046 90)
			(layer "B.Fab")
			(effects
				(font
					(size 0.7 0.7)
					(thickness 0.15)
				)
				(justify right top mirror)
			)
		)
		(property "Datasheet" "https://www.bourns.com/docs/product-datasheets/cr.pdf"
			(at 0 0 90)
			(layer "B.Fab")
			(hide yes)
			(effects
				(font
					(size 1.27 1.27)
					(thickness 0.15)
				)
				(justify mirror)
			)
		)
		(property "Description" "SMD Chip Resistor, 100 kohm, ± 1%, 62.5 mW, 0402 [1005 Metric], Thick Film, General Purpose"
			(at 0 0 90)
			(layer "B.Fab")
			(hide yes)
			(effects
				(font
					(size 1.27 1.27)
					(thickness 0.15)
				)
				(justify mirror)
			)
		)
		(property "Manufacturer" "Bourns"
			(at 0 0 270)
			(unlocked yes)
			(layer "B.Fab")
			(hide yes)
			(effects
				(font
					(size 1 1)
					(thickness 0.15)
				)
				(justify mirror)
			)
		)
		(property "MPN" "CR0402-FX-1003GLF"
			(at 0 0 270)
			(unlocked yes)
			(layer "B.Fab")
			(hide yes)
			(effects
				(font
					(size 1 1)
					(thickness 0.15)
				)
				(justify mirror)
			)
		)
		(property "Val" "100k"
			(at 0 0 270)
			(unlocked yes)
			(layer "B.Fab")
			(hide yes)
			(effects
				(font
					(size 1 1)
					(thickness 0.15)
				)
				(justify mirror)
			)
		)
		(property "License" "Apache-2.0"
			(at 0 0 270)
			(unlocked yes)
			(layer "B.Fab")
			(hide yes)
			(effects
				(font
					(size 1 1)
					(thickness 0.15)
				)
				(justify mirror)
			)
		)
		(property "Author" "Antmicro"
			(at 0 0 270)
			(unlocked yes)
			(layer "B.Fab")
			(hide yes)
			(effects
				(font
					(size 1 1)
					(thickness 0.15)
				)
				(justify mirror)
			)
		)
		(property "Tolerance" "1%"
			(at 0 0 270)
			(unlocked yes)
			(layer "B.Fab")
			(hide yes)
			(effects
				(font
					(size 1 1)
					(thickness 0.15)
				)
				(justify mirror)
			)
		)
		(sheetname "/Peripherals/")
		(sheetfile "peripherals.kicad_sch")
		(attr smd exclude_from_pos_files exclude_from_bom dnp)
		(fp_poly
			(pts
				(xy -0.925 0.47) (xy -0.925 -0.47) (xy 0.925 -0.47) (xy 0.925 0.47)
			)
			(stroke
				(width 0.05)
				(type default)
			)
			(fill no)
			(layer "B.CrtYd")
		)
		(fp_poly
			(pts
				(xy -0.5 0.25) (xy -0.5 -0.25) (xy 0.5 -0.25) (xy 0.5 0.25)
			)
			(stroke
				(width 0.15)
				(type solid)
			)
			(fill no)
			(layer "B.Fab")
		)
		(fp_text user "Author: Antmicro"
			(at -0.95 -4.169 90)
			(layer "B.Fab")
			(effects
				(font
					(size 0.7 0.7)
					(thickness 0.15)
				)
				(justify right top mirror)
			)
		)
		(fp_text user "License: Apache-2.0"
			(at -0.949999 -5.169 90)
			(layer "B.Fab")
			(effects
				(font
					(size 0.7 0.7)
					(thickness 0.15)
				)
				(justify right top mirror)
			)
		)
		(fp_text user "${REFERENCE}"
			(at -0.95 -3.168 90)
			(layer "B.Fab")
			(effects
				(font
					(size 0.7 0.7)
					(thickness 0.15)
				)
				(justify right top mirror)
			)
		)
		(pad "1" smd roundrect
			(at -0.48 0 90)
			(size 0.59 0.64)
			(layers "B.Cu" "B.Mask" "B.Paste")
			(roundrect_rratio 0.25)
			(net 1 "GND")
			(pintype "passive")
		)
		(pad "2" smd roundrect
			(at 0.48 0 90)
			(size 0.59 0.64)
			(layers "B.Cu" "B.Mask" "B.Paste")
			(roundrect_rratio 0.25)
			(net 90 "/Peripherals/I2C_CONN_PEN")
			(pintype "passive")
		)
	)
	(footprint "antmicro-footprints:C_0402_1005Metric"
		(layer "B.Cu")
		(at 215.426 137.8)
		(descr "Capacitor SMD 0402")
		(tags "capacitor SMD 0402")
		(property "Reference" "C174"
			(at -1.6 0.71 0)
			(layer "B.SilkS")
			(effects
				(font
					(size 0.7 0.7)
					(thickness 0.15)
				)
				(justify right top mirror)
			)
		)
		(property "Value" "C_100n_0402"
			(at -1.022927 -2.155213 0)
			(layer "B.Fab")
			(effects
				(font
					(size 0.7 0.7)
					(thickness 0.15)
				)
				(justify right top mirror)
			)
		)
		(property "Datasheet" "https://www.murata.com/products/productdetail?partno=GRM155R61H104KE14%23"
			(at 0 0 0)
			(layer "B.Fab")
			(hide yes)
			(effects
				(font
					(size 1.27 1.27)
					(thickness 0.15)
				)
				(justify mirror)
			)
		)
		(property "Description" "SMD Multilayer Ceramic Capacitor, 0.1 µF, 50 V, 0402 [1005 Metric], ± 10%, X5R, GRM Series"
			(at 0 0 0)
			(layer "B.Fab")
			(hide yes)
			(effects
				(font
					(size 1.27 1.27)
					(thickness 0.15)
				)
				(justify mirror)
			)
		)
		(property "MPN" "GRM155R61H104KE14D"
			(at 0 0 180)
			(unlocked yes)
			(layer "B.Fab")
			(hide yes)
			(effects
				(font
					(size 1 1)
					(thickness 0.15)
				)
				(justify mirror)
			)
		)
		(property "Manufacturer" "Murata"
			(at 0 0 180)
			(unlocked yes)
			(layer "B.Fab")
			(hide yes)
			(effects
				(font
					(size 1 1)
					(thickness 0.15)
				)
				(justify mirror)
			)
		)
		(property "License" "Apache-2.0"
			(at 0 0 180)
			(unlocked yes)
			(layer "B.Fab")
			(hide yes)
			(effects
				(font
					(size 1 1)
					(thickness 0.15)
				)
				(justify mirror)
			)
		)
		(property "Author" "Antmicro"
			(at 0 0 180)
			(unlocked yes)
			(layer "B.Fab")
			(hide yes)
			(effects
				(font
					(size 1 1)
					(thickness 0.15)
				)
				(justify mirror)
			)
		)
		(property "Val" "100n"
			(at 0 0 180)
			(unlocked yes)
			(layer "B.Fab")
			(hide yes)
			(effects
				(font
					(size 1 1)
					(thickness 0.15)
				)
				(justify mirror)
			)
		)
		(property "Voltage" "50V"
			(at 0 0 180)
			(unlocked yes)
			(layer "B.Fab")
			(hide yes)
			(effects
				(font
					(size 1 1)
					(thickness 0.15)
				)
				(justify mirror)
			)
		)
		(property "Dielectric" "X5R"
			(at 0 0 180)
			(unlocked yes)
			(layer "B.Fab")
			(hide yes)
			(effects
				(font
					(size 1 1)
					(thickness 0.15)
				)
				(justify mirror)
			)
		)
		(sheetname "/SFP/")
		(sheetfile "sfp.kicad_sch")
		(attr smd)
		(fp_poly
			(pts
				(xy -0.925 0.47) (xy -0.925 -0.47) (xy 0.925 -0.47) (xy 0.925 0.47)
			)
			(stroke
				(width 0.05)
				(type default)
			)
			(fill no)
			(layer "B.CrtYd")
		)
		(fp_line
			(start -0.494 -0.248)
			(end -0.494 0.25)
			(stroke
				(width 0.15)
				(type solid)
			)
			(layer "B.Fab")
		)
		(fp_line
			(start -0.494 0.25)
			(end 0.504 0.25)
			(stroke
				(width 0.15)
				(type solid)
			)
			(layer "B.Fab")
		)
		(fp_line
			(start 0.504 -0.248)
			(end -0.494 -0.248)
			(stroke
				(width 0.15)
				(type solid)
			)
			(layer "B.Fab")
		)
		(fp_line
			(start 0.504 0.25)
			(end 0.504 -0.248)
			(stroke
				(width 0.15)
				(type solid)
			)
			(layer "B.Fab")
		)
		(fp_text user "${REFERENCE}"
			(at -0.939 -4.599 0)
			(layer "B.Fab")
			(effects
				(font
					(size 0.7 0.7)
					(thickness 0.15)
				)
				(justify right top mirror)
			)
		)
		(fp_text user "License: Apache-2.0"
			(at -0.939 -5.799 0)
			(layer "B.Fab")
			(effects
				(font
					(size 0.7 0.7)
					(thickness 0.15)
				)
				(justify right top mirror)
			)
		)
		(fp_text user "Author: Antmicro"
			(at -0.939 -3.399 0)
			(layer "B.Fab")
			(effects
				(font
					(size 0.7 0.7)
					(thickness 0.15)
				)
				(justify right top mirror)
			)
		)
		(pad "1" smd roundrect
			(at -0.48 0)
			(size 0.59 0.64)
			(layers "B.Cu" "B.Mask" "B.Paste")
			(roundrect_rratio 0.25)
			(net 1 "GND")
			(pintype "passive")
		)
		(pad "2" smd roundrect
			(at 0.48 0)
			(size 0.59 0.64)
			(layers "B.Cu" "B.Mask" "B.Paste")
			(roundrect_rratio 0.25)
			(net 379 "/SFP/SH")
			(pintype "passive")
		)
	)
	(footprint "antmicro-footprints:Spacer_Drill3.7mm_H8mm_9774080151R"
		(locked yes)
		(layer "B.Cu")
		(at 108.930532 112.71 180)
		(descr "Spacer M=3 h=8mm fi=5.1mm")
		(property "Reference" "H13"
			(at 0 3.2 0)
			(layer "B.SilkS")
			(effects
				(font
					(size 0.7 0.7)
					(thickness 0.15)
				)
				(justify left bottom mirror)
			)
		)
		(property "Value" "Spacer_Drill3.7mm_H8mm_9774080151R"
			(at 0 -4 0)
			(layer "B.Fab")
			(effects
				(font
					(size 0.7 0.7)
					(thickness 0.15)
				)
				(justify left bottom mirror)
			)
		)
		(property "Datasheet" "https://www.we-online.com/components/products/datasheet/9774080151R.pdf"
			(at 0 0 0)
			(layer "B.Fab")
			(hide yes)
			(effects
				(font
					(size 1.27 1.27)
					(thickness 0.15)
				)
				(justify mirror)
			)
		)
		(property "Description" "Spacer, SMT, Non Stop, Steel, Swage Round, 5.1 mm x 8 mm, M2.5 Thread, WA-SMSI Series"
			(at 0 0 0)
			(layer "B.Fab")
			(hide yes)
			(effects
				(font
					(size 1.27 1.27)
					(thickness 0.15)
				)
				(justify mirror)
			)
		)
		(property "Manufacturer" "Würth Elektronik"
			(at 0 0 180)
			(unlocked yes)
			(layer "B.Fab")
			(hide yes)
			(effects
				(font
					(size 1 1)
					(thickness 0.15)
				)
				(justify mirror)
			)
		)
		(property "MPN" "9774080151R"
			(at 0 0 180)
			(unlocked yes)
			(layer "B.Fab")
			(hide yes)
			(effects
				(font
					(size 1 1)
					(thickness 0.15)
				)
				(justify mirror)
			)
		)
		(property "Author" "Antmicro"
			(at 0 0 180)
			(unlocked yes)
			(layer "B.Fab")
			(hide yes)
			(effects
				(font
					(size 1 1)
					(thickness 0.15)
				)
				(justify mirror)
			)
		)
		(property "License" "Apache-2.0"
			(at 0 0 180)
			(unlocked yes)
			(layer "B.Fab")
			(hide yes)
			(effects
				(font
					(size 1 1)
					(thickness 0.15)
				)
				(justify mirror)
			)
		)
		(sheetname "/")
		(sheetfile "jetson-agx-thor-baseboard.kicad_sch")
		(solder_paste_margin_ratio -1)
		(attr smd)
		(fp_circle
			(center 0 0)
			(end 3.05 0)
			(stroke
				(width 0.05)
				(type solid)
			)
			(fill no)
			(layer "B.CrtYd")
		)
		(fp_circle
			(center 0 0)
			(end 2.6 0)
			(stroke
				(width 0.15)
				(type solid)
			)
			(fill no)
			(layer "B.Fab")
		)
		(fp_text user "License: Apache-2.0"
			(at -9.6 -8.9 0)
			(layer "B.Fab")
			(effects
				(font
					(size 0.7 0.7)
					(thickness 0.15)
				)
				(justify left bottom mirror)
			)
		)
		(fp_text user "Author: Antmicro"
			(at -9.6 -7.7 0)
			(layer "B.Fab")
			(effects
				(font
					(size 0.7 0.7)
					(thickness 0.15)
				)
				(justify left bottom mirror)
			)
		)
		(fp_text user "${REFERENCE}"
			(at -9.6 -6.5 0)
			(layer "B.Fab")
			(effects
				(font
					(size 0.7 0.7)
					(thickness 0.15)
				)
				(justify left bottom mirror)
			)
		)
		(pad "" smd custom
			(at -1.7 -1.7 90)
			(size 0.62 0.62)
			(layers "B.Paste")
			(thermal_bridge_angle 90)
			(options
				(clearance outline)
				(anchor circle)
			)
			(primitives
				(gr_arc
					(start 1.266786 0.24747)
					(mid 0.285453 -0.29439)
					(end -0.250195 -1.279127)
					(width 0.2)
				)
				(gr_arc
					(start 1.259603 0.339191)
					(mid 0.218448 -0.232561)
					(end -0.34334 -1.279127)
					(width 0.2)
				)
				(gr_arc
					(start 1.255279 0.431435)
					(mid 0.152481 -0.169693)
					(end -0.436309 -1.279127)
					(width 0.2)
				)
				(gr_arc
					(start 1.253811 0.524161)
					(mid 0.087542 -0.105784)
					(end -0.529126 -1.279127)
					(width 0.2)
				)
				(gr_arc
					(start 1.275473 0.621136)
					(mid 0.0309 -0.033527)
					(end -0.621807 -1.279127)
					(width 0.2)
				)
				(gr_arc
					(start 1.263664 0.711602)
					(mid -0.037759 0.026651)
					(end -0.71437 -1.279127)
					(width 0.2)
				)
				(gr_arc
					(start 1.253435 0.802342)
					(mid -0.105837 0.087395)
					(end -0.806826 -1.279127)
					(width 0.2)
				)
				(gr_arc
					(start 1.267475 0.897258)
					(mid -0.165236 0.156885)
					(end -0.899187 -1.279127)
					(width 0.2)
				)
				(gr_arc
					(start 1.270645 0.990112)
					(mid -0.228522 0.222449)
					(end -0.991463 -1.279127)
					(width 0.2)
				)
				(gr_arc
					(start 1.266278 1.081674)
					(mid -0.294507 0.285313)
					(end -1.083663 -1.279127)
					(width 0.2)
				)
				(gr_line
					(start 1.279127 0.250195)
					(end 1.279127 1.083663)
					(width 0.2)
				)
				(gr_line
					(start -0.250195 -1.279127)
					(end -1.083663 -1.279127)
					(width 0.2)
				)
			)
		)
		(pad "" smd custom
			(at -1.7 1.7 180)
			(size 0.62 0.62)
			(layers "B.Paste")
			(thermal_bridge_angle 90)
			(options
				(clearance outline)
				(anchor circle)
			)
			(primitives
				(gr_arc
					(start 1.266786 0.24747)
					(mid 0.285453 -0.29439)
					(end -0.250195 -1.279127)
					(width 0.2)
				)
				(gr_arc
					(start 1.259603 0.339191)
					(mid 0.218448 -0.232561)
					(end -0.34334 -1.279127)
					(width 0.2)
				)
				(gr_arc
					(start 1.255279 0.431435)
					(mid 0.152481 -0.169693)
					(end -0.436309 -1.279127)
					(width 0.2)
				)
				(gr_arc
					(start 1.253811 0.524161)
					(mid 0.087542 -0.105784)
					(end -0.529126 -1.279127)
					(width 0.2)
				)
				(gr_arc
					(start 1.275473 0.621136)
					(mid 0.0309 -0.033527)
					(end -0.621807 -1.279127)
					(width 0.2)
				)
				(gr_arc
					(start 1.263664 0.711602)
					(mid -0.037759 0.026651)
					(end -0.71437 -1.279127)
					(width 0.2)
				)
				(gr_arc
					(start 1.253435 0.802342)
					(mid -0.105837 0.087395)
					(end -0.806826 -1.279127)
					(width 0.2)
				)
				(gr_arc
					(start 1.267475 0.897258)
					(mid -0.165236 0.156885)
					(end -0.899187 -1.279127)
					(width 0.2)
				)
				(gr_arc
					(start 1.270645 0.990112)
					(mid -0.228522 0.222449)
					(end -0.991463 -1.279127)
					(width 0.2)
				)
				(gr_arc
					(start 1.266278 1.081674)
					(mid -0.294507 0.285313)
					(end -1.083663 -1.279127)
					(width 0.2)
				)
				(gr_line
					(start 1.279127 0.250195)
					(end 1.279127 1.083663)
					(width 0.2)
				)
				(gr_line
					(start -0.250195 -1.279127)
					(end -1.083663 -1.279127)
					(width 0.2)
				)
			)
		)
		(pad "" smd custom
			(at 1.7 -1.7)
			(size 0.62 0.62)
			(layers "B.Paste")
			(thermal_bridge_angle 90)
			(options
				(clearance outline)
				(anchor circle)
			)
			(primitives
				(gr_arc
					(start 1.266786 0.24747)
					(mid 0.285453 -0.29439)
					(end -0.250195 -1.279127)
					(width 0.2)
				)
				(gr_arc
					(start 1.259603 0.339191)
					(mid 0.218448 -0.232561)
					(end -0.34334 -1.279127)
					(width 0.2)
				)
				(gr_arc
					(start 1.255279 0.431435)
					(mid 0.152481 -0.169693)
					(end -0.436309 -1.279127)
					(width 0.2)
				)
				(gr_arc
					(start 1.253811 0.524161)
					(mid 0.087542 -0.105784)
					(end -0.529126 -1.279127)
					(width 0.2)
				)
				(gr_arc
					(start 1.275473 0.621136)
					(mid 0.0309 -0.033527)
					(end -0.621807 -1.279127)
					(width 0.2)
				)
				(gr_arc
					(start 1.263664 0.711602)
					(mid -0.037759 0.026651)
					(end -0.71437 -1.279127)
					(width 0.2)
				)
				(gr_arc
					(start 1.253435 0.802342)
					(mid -0.105837 0.087395)
					(end -0.806826 -1.279127)
					(width 0.2)
				)
				(gr_arc
					(start 1.267475 0.897258)
					(mid -0.165236 0.156885)
					(end -0.899187 -1.279127)
					(width 0.2)
				)
				(gr_arc
					(start 1.270645 0.990112)
					(mid -0.228522 0.222449)
					(end -0.991463 -1.279127)
					(width 0.2)
				)
				(gr_arc
					(start 1.266278 1.081674)
					(mid -0.294507 0.285313)
					(end -1.083663 -1.279127)
					(width 0.2)
				)
				(gr_line
					(start 1.279127 0.250195)
					(end 1.279127 1.083663)
					(width 0.2)
				)
				(gr_line
					(start -0.250195 -1.279127)
					(end -1.083663 -1.279127)
					(width 0.2)
				)
			)
		)
		(pad "" smd custom
			(at 1.7 1.7 270)
			(size 0.62 0.62)
			(layers "B.Paste")
			(thermal_bridge_angle 90)
			(options
				(clearance outline)
				(anchor circle)
			)
			(primitives
				(gr_arc
					(start 1.266786 0.24747)
					(mid 0.285453 -0.29439)
					(end -0.250195 -1.279127)
					(width 0.2)
				)
				(gr_arc
					(start 1.259603 0.339191)
					(mid 0.218448 -0.232561)
					(end -0.34334 -1.279127)
					(width 0.2)
				)
				(gr_arc
					(start 1.255279 0.431435)
					(mid 0.152481 -0.169693)
					(end -0.436309 -1.279127)
					(width 0.2)
				)
				(gr_arc
					(start 1.253811 0.524161)
					(mid 0.087542 -0.105784)
					(end -0.529126 -1.279127)
					(width 0.2)
				)
				(gr_arc
					(start 1.275473 0.621136)
					(mid 0.0309 -0.033527)
					(end -0.621807 -1.279127)
					(width 0.2)
				)
				(gr_arc
					(start 1.263664 0.711602)
					(mid -0.037759 0.026651)
					(end -0.71437 -1.279127)
					(width 0.2)
				)
				(gr_arc
					(start 1.253435 0.802342)
					(mid -0.105837 0.087395)
					(end -0.806826 -1.279127)
					(width 0.2)
				)
				(gr_arc
					(start 1.267475 0.897258)
					(mid -0.165236 0.156885)
					(end -0.899187 -1.279127)
					(width 0.2)
				)
				(gr_arc
					(start 1.270645 0.990112)
					(mid -0.228522 0.222449)
					(end -0.991463 -1.279127)
					(width 0.2)
				)
				(gr_arc
					(start 1.266278 1.081674)
					(mid -0.294507 0.285313)
					(end -1.083663 -1.279127)
					(width 0.2)
				)
				(gr_line
					(start 1.279127 0.250195)
					(end 1.279127 1.083663)
					(width 0.2)
				)
				(gr_line
					(start -0.250195 -1.279127)
					(end -1.083663 -1.279127)
					(width 0.2)
				)
			)
		)
		(pad "1" thru_hole circle
			(at 0 0 180)
			(size 6 6)
			(drill 3.7)
			(layers "*.Cu" "*.Mask")
			(remove_unused_layers no)
			(net 1 "GND")
			(pintype "passive")
		)
	)
	(footprint "antmicro-footprints:TP_SMD_0.75mm"
		(layer "B.Cu")
		(at 129.2 69.2 -45)
		(property "Reference" "TP105"
			(at -2.446589 -3.082986 270)
			(layer "B.SilkS")
			(effects
				(font
					(size 0.7 0.7)
					(thickness 0.15)
				)
				(justify left bottom mirror)
			)
		)
		(property "Value" "TP_0.75mm_SMD"
			(at 0 -1.2 135)
			(layer "B.Fab")
			(effects
				(font
					(size 0.7 0.7)
					(thickness 0.15)
				)
				(justify left bottom mirror)
			)
		)
		(property "Description" "SMT test point"
			(at 0 0 135)
			(layer "B.Fab")
			(hide yes)
			(effects
				(font
					(size 1.27 1.27)
					(thickness 0.15)
				)
				(justify mirror)
			)
		)
		(property "MPN" ""
			(at 0 0 135)
			(unlocked yes)
			(layer "B.Fab")
			(hide yes)
			(effects
				(font
					(size 1 1)
					(thickness 0.15)
				)
				(justify mirror)
			)
		)
		(property "Manufacturer" ""
			(at 0 0 135)
			(unlocked yes)
			(layer "B.Fab")
			(hide yes)
			(effects
				(font
					(size 1 1)
					(thickness 0.15)
				)
				(justify mirror)
			)
		)
		(property "Author" "Antmicro"
			(at 0 0 135)
			(unlocked yes)
			(layer "B.Fab")
			(hide yes)
			(effects
				(font
					(size 1 1)
					(thickness 0.15)
				)
				(justify mirror)
			)
		)
		(property "License" "Apache-2.0"
			(at 0 0 135)
			(unlocked yes)
			(layer "B.Fab")
			(hide yes)
			(effects
				(font
					(size 1 1)
					(thickness 0.15)
				)
				(justify mirror)
			)
		)
		(sheetname "/SoM_IO/")
		(sheetfile "som_io.kicad_sch")
		(attr exclude_from_pos_files exclude_from_bom)
		(fp_circle
			(center 0 0)
			(end 0.475 0)
			(stroke
				(width 0.05)
				(type default)
			)
			(fill no)
			(layer "B.CrtYd")
		)
		(fp_text user "${REFERENCE}"
			(at -0.4 -2.7 135)
			(layer "B.Fab")
			(effects
				(font
					(size 0.7 0.7)
					(thickness 0.15)
				)
				(justify left bottom mirror)
			)
		)
		(fp_text user "Author: Antmicro"
			(at -0.4 -3.901 135)
			(layer "B.Fab")
			(effects
				(font
					(size 0.7 0.7)
					(thickness 0.15)
				)
				(justify left bottom mirror)
			)
		)
		(fp_text user "License: Apache-2.0"
			(at -0.4 -5.101 135)
			(layer "B.Fab")
			(effects
				(font
					(size 0.7 0.7)
					(thickness 0.15)
				)
				(justify left bottom mirror)
			)
		)
		(pad "1" smd circle
			(at 0 0 315)
			(size 0.75 0.75)
			(layers "B.Cu" "B.Mask")
			(net 126 "/SoM_IO/UART1.RTS")
			(pinfunction "1")
			(pintype "passive")
		)
	)
	(footprint "antmicro-footprints:TP_SMD_0.75mm"
		(layer "B.Cu")
		(at 90.1 81.6 90)
		(property "Reference" "TP53"
			(at -0.8 0.7 90)
			(layer "B.SilkS")
			(effects
				(font
					(size 0.7 0.7)
					(thickness 0.15)
				)
				(justify right top mirror)
			)
		)
		(property "Value" "TP_0.75mm_SMD"
			(at 0 -1.2 90)
			(layer "B.Fab")
			(effects
				(font
					(size 0.7 0.7)
					(thickness 0.15)
				)
				(justify right top mirror)
			)
		)
		(property "Description" "SMT test point"
			(at 0 0 90)
			(layer "B.Fab")
			(hide yes)
			(effects
				(font
					(size 1.27 1.27)
					(thickness 0.15)
				)
				(justify mirror)
			)
		)
		(property "MPN" ""
			(at 0 0 270)
			(unlocked yes)
			(layer "B.Fab")
			(hide yes)
			(effects
				(font
					(size 1 1)
					(thickness 0.15)
				)
				(justify mirror)
			)
		)
		(property "Manufacturer" ""
			(at 0 0 270)
			(unlocked yes)
			(layer "B.Fab")
			(hide yes)
			(effects
				(font
					(size 1 1)
					(thickness 0.15)
				)
				(justify mirror)
			)
		)
		(property "Author" "Antmicro"
			(at 0 0 270)
			(unlocked yes)
			(layer "B.Fab")
			(hide yes)
			(effects
				(font
					(size 1 1)
					(thickness 0.15)
				)
				(justify mirror)
			)
		)
		(property "License" "Apache-2.0"
			(at 0 0 270)
			(unlocked yes)
			(layer "B.Fab")
			(hide yes)
			(effects
				(font
					(size 1 1)
					(thickness 0.15)
				)
				(justify mirror)
			)
		)
		(sheetname "/SoM_Power/")
		(sheetfile "som_power.kicad_sch")
		(attr exclude_from_pos_files exclude_from_bom)
		(fp_circle
			(center 0 0)
			(end 0.475 0)
			(stroke
				(width 0.05)
				(type default)
			)
			(fill no)
			(layer "B.CrtYd")
		)
		(fp_text user "License: Apache-2.0"
			(at -0.4 -5.101 90)
			(layer "B.Fab")
			(effects
				(font
					(size 0.7 0.7)
					(thickness 0.15)
				)
				(justify right top mirror)
			)
		)
		(fp_text user "Author: Antmicro"
			(at -0.4 -3.901 90)
			(layer "B.Fab")
			(effects
				(font
					(size 0.7 0.7)
					(thickness 0.15)
				)
				(justify right top mirror)
			)
		)
		(fp_text user "${REFERENCE}"
			(at -0.4 -2.7 90)
			(layer "B.Fab")
			(effects
				(font
					(size 0.7 0.7)
					(thickness 0.15)
				)
				(justify right top mirror)
			)
		)
		(pad "1" smd circle
			(at 0 0 90)
			(size 0.75 0.75)
			(layers "B.Cu" "B.Mask")
			(net 796 "Net-(J1A-UFS0_RST_N)")
			(pinfunction "1")
			(pintype "passive")
		)
	)
	(footprint "antmicro-footprints:C_0402_1005Metric"
		(layer "B.Cu")
		(at 94 117.8 180)
		(descr "Capacitor SMD 0402")
		(tags "capacitor SMD 0402")
		(property "Reference" "C219"
			(at -3.8 -0.655 0)
			(layer "B.SilkS")
			(effects
				(font
					(size 0.7 0.7)
					(thickness 0.15)
				)
				(justify left bottom mirror)
			)
		)
		(property "Value" "C_220n_0402"
			(at -1.022927 -2.155213 0)
			(layer "B.Fab")
			(effects
				(font
					(size 0.7 0.7)
					(thickness 0.15)
				)
				(justify left bottom mirror)
			)
		)
		(property "Datasheet" "https://www.yageo.com/en/Chart/Download/pdf/CC0402KRX5R6BB224"
			(at 0 0 0)
			(layer "B.Fab")
			(hide yes)
			(effects
				(font
					(size 1.27 1.27)
					(thickness 0.15)
				)
				(justify mirror)
			)
		)
		(property "Description" "SMD Multilayer Ceramic Capacitor, 0.22 µF, 10 V, 0402 [1005 Metric], ± 10%, X5R, CC Series"
			(at 0 0 0)
			(layer "B.Fab")
			(hide yes)
			(effects
				(font
					(size 1.27 1.27)
					(thickness 0.15)
				)
				(justify mirror)
			)
		)
		(property "MPN" "CC0402KRX5R6BB224"
			(at 0 0 180)
			(unlocked yes)
			(layer "B.Fab")
			(hide yes)
			(effects
				(font
					(size 1 1)
					(thickness 0.15)
				)
				(justify mirror)
			)
		)
		(property "Val" "220n"
			(at 0 0 180)
			(unlocked yes)
			(layer "B.Fab")
			(hide yes)
			(effects
				(font
					(size 1 1)
					(thickness 0.15)
				)
				(justify mirror)
			)
		)
		(property "Voltage" "25V"
			(at 0 0 180)
			(unlocked yes)
			(layer "B.Fab")
			(hide yes)
			(effects
				(font
					(size 1 1)
					(thickness 0.15)
				)
				(justify mirror)
			)
		)
		(property "Dielectric" "X7R"
			(at 0 0 180)
			(unlocked yes)
			(layer "B.Fab")
			(hide yes)
			(effects
				(font
					(size 1 1)
					(thickness 0.15)
				)
				(justify mirror)
			)
		)
		(property "Manufacturer" "YAGEO"
			(at 0 0 180)
			(unlocked yes)
			(layer "B.Fab")
			(hide yes)
			(effects
				(font
					(size 1 1)
					(thickness 0.15)
				)
				(justify mirror)
			)
		)
		(property "License" "Apache-2.0"
			(at 0 0 180)
			(unlocked yes)
			(layer "B.Fab")
			(hide yes)
			(effects
				(font
					(size 1 1)
					(thickness 0.15)
				)
				(justify mirror)
			)
		)
		(property "Author" "Antmicro"
			(at 0 0 180)
			(unlocked yes)
			(layer "B.Fab")
			(hide yes)
			(effects
				(font
					(size 1 1)
					(thickness 0.15)
				)
				(justify mirror)
			)
		)
		(property "Public" "False"
			(at 0 0 180)
			(unlocked yes)
			(layer "B.Fab")
			(hide yes)
			(effects
				(font
					(size 1 1)
					(thickness 0.15)
				)
				(justify mirror)
			)
		)
		(sheetname "/Expansion connector/")
		(sheetfile "expansion_connector.kicad_sch")
		(attr smd)
		(fp_poly
			(pts
				(xy -0.925 0.47) (xy 0.925 0.47) (xy 0.925 -0.47) (xy -0.925 -0.47)
			)
			(stroke
				(width 0.05)
				(type default)
			)
			(fill no)
			(layer "B.CrtYd")
		)
		(fp_line
			(start 0.504 0.25)
			(end 0.504 -0.248)
			(stroke
				(width 0.15)
				(type solid)
			)
			(layer "B.Fab")
		)
		(fp_line
			(start 0.504 -0.248)
			(end -0.494 -0.248)
			(stroke
				(width 0.15)
				(type solid)
			)
			(layer "B.Fab")
		)
		(fp_line
			(start -0.494 0.25)
			(end 0.504 0.25)
			(stroke
				(width 0.15)
				(type solid)
			)
			(layer "B.Fab")
		)
		(fp_line
			(start -0.494 -0.248)
			(end -0.494 0.25)
			(stroke
				(width 0.15)
				(type solid)
			)
			(layer "B.Fab")
		)
		(fp_text user "Author: Antmicro"
			(at -0.939 -3.399 0)
			(layer "B.Fab")
			(effects
				(font
					(size 0.7 0.7)
					(thickness 0.15)
				)
				(justify left bottom mirror)
			)
		)
		(fp_text user "License: Apache-2.0"
			(at -0.939 -5.799 0)
			(layer "B.Fab")
			(effects
				(font
					(size 0.7 0.7)
					(thickness 0.15)
				)
				(justify left bottom mirror)
			)
		)
		(fp_text user "${REFERENCE}"
			(at -0.939 -4.599 0)
			(layer "B.Fab")
			(effects
				(font
					(size 0.7 0.7)
					(thickness 0.15)
				)
				(justify left bottom mirror)
			)
		)
		(pad "1" smd roundrect
			(at -0.48 0 180)
			(size 0.59 0.64)
			(layers "B.Cu" "B.Mask" "B.Paste")
			(roundrect_rratio 0.25)
			(net 517 "/Expansion connector/PCIe_{C3x2}.TX0-")
			(pintype "passive")
		)
		(pad "2" smd roundrect
			(at 0.48 0 180)
			(size 0.59 0.64)
			(layers "B.Cu" "B.Mask" "B.Paste")
			(roundrect_rratio 0.25)
			(net 518 "/Expansion connector/PET0_C3_N")
			(pintype "passive")
		)
	)
	(footprint "antmicro-footprints:Conn_JST_SH_1x4_SM04B-SRSS-TB-LF-SN"
		(locked yes)
		(layer "B.Cu")
		(at 139.13 56.86)
		(property "Reference" "J16"
			(at 3.57 -0.86 270)
			(layer "B.SilkS")
			(effects
				(font
					(size 0.7 0.7)
					(thickness 0.15)
				)
				(justify right top mirror)
			)
		)
		(property "Value" "JST_SH_1x4_SM04B-SRSS-TB-LF-SN"
			(at -4 -3.88 0)
			(layer "B.Fab")
			(effects
				(font
					(size 0.7 0.7)
					(thickness 0.15)
				)
				(justify right top mirror)
			)
		)
		(property "Datasheet" "https://www.jst-mfg.com/product/pdf/eng/eSH.pdf"
			(at 0 0 0)
			(layer "B.Fab")
			(hide yes)
			(effects
				(font
					(size 1.27 1.27)
					(thickness 0.15)
				)
				(justify mirror)
			)
		)
		(property "Description" "Pin Header, Right Angle, Wire-to-Board, 1 mm, 1 Rows, 4 Contacts, Surface Mount Right Angle, SH"
			(at 0 0 0)
			(layer "B.Fab")
			(hide yes)
			(effects
				(font
					(size 1.27 1.27)
					(thickness 0.15)
				)
				(justify mirror)
			)
		)
		(property "MPN" "SM04B-SRSS-TB(LF)(SN)"
			(at 0 0 180)
			(unlocked yes)
			(layer "B.Fab")
			(hide yes)
			(effects
				(font
					(size 1 1)
					(thickness 0.15)
				)
				(justify mirror)
			)
		)
		(property "Manufacturer" "JST Automotive Connectors"
			(at 0 0 180)
			(unlocked yes)
			(layer "B.Fab")
			(hide yes)
			(effects
				(font
					(size 1 1)
					(thickness 0.15)
				)
				(justify mirror)
			)
		)
		(property "Author" "Antmicro"
			(at 0 0 180)
			(unlocked yes)
			(layer "B.Fab")
			(hide yes)
			(effects
				(font
					(size 1 1)
					(thickness 0.15)
				)
				(justify mirror)
			)
		)
		(property "License" "Apache-2.0"
			(at 0 0 180)
			(unlocked yes)
			(layer "B.Fab")
			(hide yes)
			(effects
				(font
					(size 1 1)
					(thickness 0.15)
				)
				(justify mirror)
			)
		)
		(sheetname "/Peripherals/")
		(sheetfile "peripherals.kicad_sch")
		(attr smd)
		(fp_line
			(start -3.2 2)
			(end -3.2 -0.6)
			(stroke
				(width 0.15)
				(type solid)
			)
			(layer "B.SilkS")
		)
		(fp_line
			(start -2 -2.6)
			(end 2 -2.6)
			(stroke
				(width 0.15)
				(type solid)
			)
			(layer "B.SilkS")
		)
		(fp_line
			(start -2 2)
			(end -3.2 2)
			(stroke
				(width 0.15)
				(type solid)
			)
			(layer "B.SilkS")
		)
		(fp_line
			(start 2 2)
			(end 3.2 2)
			(stroke
				(width 0.15)
				(type solid)
			)
			(layer "B.SilkS")
		)
		(fp_line
			(start 3.2 2)
			(end 3.2 -0.6)
			(stroke
				(width 0.15)
				(type solid)
			)
			(layer "B.SilkS")
		)
		(fp_circle
			(center -2.1 2.5)
			(end -2.05 2.5)
			(stroke
				(width 0.15)
				(type solid)
			)
			(fill yes)
			(layer "B.SilkS")
		)
		(fp_rect
			(start -3.65 3.14)
			(end 3.65 -2.9)
			(stroke
				(width 0.05)
				(type solid)
			)
			(fill no)
			(layer "B.CrtYd")
		)
		(fp_rect
			(start -3 2.475)
			(end 3 -2.475)
			(stroke
				(width 0.15)
				(type solid)
			)
			(fill no)
			(layer "B.Fab")
		)
		(fp_text user "Author: Antmicro"
			(at -4 -7.08 0)
			(layer "B.Fab")
			(effects
				(font
					(size 0.7 0.7)
					(thickness 0.15)
				)
				(justify right top mirror)
			)
		)
		(fp_text user "License: Apache-2.0"
			(at -4 -5.88 0)
			(layer "B.Fab")
			(effects
				(font
					(size 0.7 0.7)
					(thickness 0.15)
				)
				(justify right top mirror)
			)
		)
		(fp_text user "${REFERENCE}"
			(at -4 -8.28 0)
			(layer "B.Fab")
			(effects
				(font
					(size 0.7 0.7)
					(thickness 0.15)
				)
				(justify right top mirror)
			)
		)
		(pad "1" smd roundrect
			(at -1.5 2.12 180)
			(size 0.6 1.55)
			(layers "B.Cu" "B.Mask" "B.Paste")
			(roundrect_rratio 0.25)
			(net 1 "GND")
			(pintype "passive")
		)
		(pad "2" smd roundrect
			(at -0.5 2.12 180)
			(size 0.6 1.55)
			(layers "B.Cu" "B.Mask" "B.Paste")
			(roundrect_rratio 0.25)
			(net 838 "/Peripherals/I2C_CONN1_3V3")
			(pintype "passive")
		)
		(pad "3" smd roundrect
			(at 0.5 2.12 180)
			(size 0.6 1.55)
			(layers "B.Cu" "B.Mask" "B.Paste")
			(roundrect_rratio 0.25)
			(net 43 "/Peripherals/I2C_{CONN}.SDA")
			(pintype "passive")
		)
		(pad "4" smd roundrect
			(at 1.5 2.12 180)
			(size 0.6 1.55)
			(layers "B.Cu" "B.Mask" "B.Paste")
			(roundrect_rratio 0.25)
			(net 42 "/Peripherals/I2C_{CONN}.SCL")
			(pintype "passive")
		)
		(pad "MP" smd roundrect
			(at -2.8 -1.755)
			(size 1.2 1.8)
			(layers "B.Cu" "B.Mask" "B.Paste")
			(roundrect_rratio 0.25)
			(net 1 "GND")
			(pintype "passive")
		)
		(pad "MP" smd roundrect
			(at 2.8 -1.755)
			(size 1.2 1.8)
			(layers "B.Cu" "B.Mask" "B.Paste")
			(roundrect_rratio 0.25)
			(net 1 "GND")
			(pintype "passive")
		)
	)
	(footprint "antmicro-footprints:Vishay_PowerPAK_1212-8_Single"
		(layer "B.Cu")
		(at 183.08 88.537 90)
		(descr "PowerPAK 1212-8 Single")
		(tags "Vishay PowerPAK 1212-8 Single")
		(property "Reference" "Q5"
			(at 0.637 1.92 90)
			(layer "B.SilkS")
			(effects
				(font
					(size 0.7 0.7)
					(thickness 0.15)
				)
				(justify right top mirror)
			)
		)
		(property "Value" "SISS05DN-T1-GE3"
			(at 0 -2.7 90)
			(layer "B.Fab")
			(effects
				(font
					(size 0.7 0.7)
					(thickness 0.15)
				)
				(justify right top mirror)
			)
		)
		(property "Datasheet" "https://www.vishay.com/docs/77029/siss05dn.pdf"
			(at 0 0 90)
			(layer "B.Fab")
			(hide yes)
			(effects
				(font
					(size 1.27 1.27)
					(thickness 0.15)
				)
				(justify mirror)
			)
		)
		(property "Description" "Power MOSFET, P Channel, 30 V, 108 A, 0.0035 ohm, PowerPAK 1212, Surface Mount"
			(at 0 0 90)
			(layer "B.Fab")
			(hide yes)
			(effects
				(font
					(size 1.27 1.27)
					(thickness 0.15)
				)
				(justify mirror)
			)
		)
		(property "MPN" "SISS05DN-T1-GE3"
			(at 0 0 270)
			(unlocked yes)
			(layer "B.Fab")
			(hide yes)
			(effects
				(font
					(size 1 1)
					(thickness 0.15)
				)
				(justify mirror)
			)
		)
		(property "Manufacturer" "Vishay"
			(at 0 0 270)
			(unlocked yes)
			(layer "B.Fab")
			(hide yes)
			(effects
				(font
					(size 1 1)
					(thickness 0.15)
				)
				(justify mirror)
			)
		)
		(property "Author" "Antmicro"
			(at 0 0 270)
			(unlocked yes)
			(layer "B.Fab")
			(hide yes)
			(effects
				(font
					(size 1 1)
					(thickness 0.15)
				)
				(justify mirror)
			)
		)
		(property "License" "Apache-2.0"
			(at 0 0 270)
			(unlocked yes)
			(layer "B.Fab")
			(hide yes)
			(effects
				(font
					(size 1 1)
					(thickness 0.15)
				)
				(justify mirror)
			)
		)
		(sheetname "/Power/")
		(sheetfile "power.kicad_sch")
		(attr smd exclude_from_pos_files exclude_from_bom dnp)
		(fp_line
			(start -1.635 -1.634)
			(end 1.634 -1.634)
			(stroke
				(width 0.15)
				(type solid)
			)
			(layer "B.SilkS")
		)
		(fp_line
			(start 1.634 -1.3)
			(end 1.634 -1.634)
			(stroke
				(width 0.15)
				(type solid)
			)
			(layer "B.SilkS")
		)
		(fp_line
			(start -1.635 -1.3)
			(end -1.635 -1.634)
			(stroke
				(width 0.15)
				(type solid)
			)
			(layer "B.SilkS")
		)
		(fp_line
			(start 1.648 1.651)
			(end 1.648 1.317)
			(stroke
				(width 0.15)
				(type solid)
			)
			(layer "B.SilkS")
		)
		(fp_line
			(start -1.651 1.651)
			(end -1.651 1.317)
			(stroke
				(width 0.15)
				(type solid)
			)
			(layer "B.SilkS")
		)
		(fp_line
			(start -1.651 1.651)
			(end 1.648 1.651)
			(stroke
				(width 0.15)
				(type solid)
			)
			(layer "B.SilkS")
		)
		(fp_circle
			(center -1.9 1.4)
			(end -1.85 1.4)
			(stroke
				(width 0.15)
				(type solid)
			)
			(fill yes)
			(layer "B.SilkS")
		)
		(fp_rect
			(start -2 1.8)
			(end 2 -1.798)
			(stroke
				(width 0.05)
				(type solid)
			)
			(fill no)
			(layer "B.CrtYd")
		)
		(fp_line
			(start -1.6425 1.4175)
			(end -1.4175 1.6425)
			(stroke
				(width 0.15)
				(type solid)
			)
			(layer "B.Fab")
		)
		(fp_rect
			(start -1.651 1.651)
			(end 1.648 -1.648)
			(stroke
				(width 0.15)
				(type solid)
			)
			(fill no)
			(layer "B.Fab")
		)
		(fp_text user "License: Apache-2.0"
			(at -8 -7.1 90)
			(layer "B.Fab")
			(effects
				(font
					(size 0.7 0.7)
					(thickness 0.15)
				)
				(justify right top mirror)
			)
		)
		(fp_text user "${REFERENCE}"
			(at -8 -4.7 90)
			(layer "B.Fab")
			(effects
				(font
					(size 0.7 0.7)
					(thickness 0.15)
				)
				(justify right top mirror)
			)
		)
		(fp_text user "Author: Antmicro"
			(at -8 -5.9 90)
			(layer "B.Fab")
			(effects
				(font
					(size 0.7 0.7)
					(thickness 0.15)
				)
				(justify right top mirror)
			)
		)
		(pad "1" smd rect
			(at -1.436 0.99 90)
			(size 0.99 0.405)
			(layers "B.Cu" "B.Mask" "B.Paste")
			(net 13 "VCC")
			(pinfunction "S")
			(pintype "passive")
		)
		(pad "2" smd rect
			(at -1.436 0.332 90)
			(size 0.99 0.405)
			(layers "B.Cu" "B.Mask" "B.Paste")
			(net 13 "VCC")
			(pinfunction "S")
			(pintype "passive")
		)
		(pad "3" smd rect
			(at -1.436 -0.33 90)
			(size 0.99 0.405)
			(layers "B.Cu" "B.Mask" "B.Paste")
			(net 13 "VCC")
			(pinfunction "S")
			(pintype "passive")
		)
		(pad "4" smd rect
			(at -1.436 -0.988 90)
			(size 0.99 0.405)
			(layers "B.Cu" "B.Mask" "B.Paste")
			(net 1200 "Net-(Q5-G)")
			(pinfunction "G")
			(pintype "input")
		)
		(pad "5" smd custom
			(at 0.557 0 90)
			(size 1.725 2.235)
			(layers "B.Cu" "B.Mask" "B.Paste")
			(net 522 "/Power/USBPD1_HV")
			(pinfunction "D")
			(pintype "passive")
			(zone_connect 2)
			(options
				(clearance outline)
				(anchor rect)
			)
			(primitives
				(gr_poly
					(pts
						(xy 0.8625 -0.1275) (xy 0.8625 0.1275) (xy 1.3725 0.1275) (xy 1.3725 0.5325) (xy 0.8625 0.5325)
						(xy 0.8625 0.7875) (xy 1.3725 0.7875) (xy 1.3725 1.195) (xy 0.6125 1.195) (xy 0.6125 -1.195) (xy 1.3725 -1.195)
						(xy 1.3725 -0.7875) (xy 0.8625 -0.7875) (xy 0.8625 -0.5325) (xy 1.3725 -0.5325) (xy 1.3725 -0.1275)
					)
					(width 0)
					(fill yes)
				)
			)
		)
	)
	(footprint "antmicro-footprints:C_0402_1005Metric"
		(layer "B.Cu")
		(at 89.9 78.9 -90)
		(descr "Capacitor SMD 0402")
		(tags "capacitor SMD 0402")
		(property "Reference" "C365"
			(at -1.9 -1.5 90)
			(layer "B.SilkS")
			(effects
				(font
					(size 0.7 0.7)
					(thickness 0.15)
				)
				(justify left bottom mirror)
			)
		)
		(property "Value" "C_1u_25V_0402"
			(at -1.022927 -2.155213 90)
			(layer "B.Fab")
			(effects
				(font
					(size 0.7 0.7)
					(thickness 0.15)
				)
				(justify left bottom mirror)
			)
		)
		(property "Datasheet" "https://www.murata.com/products/productdetail?partno=GRM155R61E105KE11%23"
			(at 0 0 90)
			(layer "B.Fab")
			(hide yes)
			(effects
				(font
					(size 1.27 1.27)
					(thickness 0.15)
				)
				(justify mirror)
			)
		)
		(property "Description" "SMD Multilayer Ceramic Capacitor, 1 µF, 25 V, 0402 [1005 Metric], ± 10%, X5R, GRM Series"
			(at 0 0 90)
			(layer "B.Fab")
			(hide yes)
			(effects
				(font
					(size 1.27 1.27)
					(thickness 0.15)
				)
				(justify mirror)
			)
		)
		(property "MPN" "GRM155R61E105KE11J"
			(at 0 0 90)
			(unlocked yes)
			(layer "B.Fab")
			(hide yes)
			(effects
				(font
					(size 1 1)
					(thickness 0.15)
				)
				(justify mirror)
			)
		)
		(property "Manufacturer" "Murata"
			(at 0 0 90)
			(unlocked yes)
			(layer "B.Fab")
			(hide yes)
			(effects
				(font
					(size 1 1)
					(thickness 0.15)
				)
				(justify mirror)
			)
		)
		(property "License" "Apache-2.0"
			(at 0 0 90)
			(unlocked yes)
			(layer "B.Fab")
			(hide yes)
			(effects
				(font
					(size 1 1)
					(thickness 0.15)
				)
				(justify mirror)
			)
		)
		(property "Author" "Antmicro"
			(at 0 0 90)
			(unlocked yes)
			(layer "B.Fab")
			(hide yes)
			(effects
				(font
					(size 1 1)
					(thickness 0.15)
				)
				(justify mirror)
			)
		)
		(property "Val" "1u"
			(at 0 0 90)
			(unlocked yes)
			(layer "B.Fab")
			(hide yes)
			(effects
				(font
					(size 1 1)
					(thickness 0.15)
				)
				(justify mirror)
			)
		)
		(property "Voltage" "25V"
			(at 0 0 90)
			(unlocked yes)
			(layer "B.Fab")
			(hide yes)
			(effects
				(font
					(size 1 1)
					(thickness 0.15)
				)
				(justify mirror)
			)
		)
		(property "Dielectric" "X5R"
			(at 0 0 90)
			(unlocked yes)
			(layer "B.Fab")
			(hide yes)
			(effects
				(font
					(size 1 1)
					(thickness 0.15)
				)
				(justify mirror)
			)
		)
		(sheetname "/SoM_Power/")
		(sheetfile "som_power.kicad_sch")
		(attr smd)
		(fp_poly
			(pts
				(xy -0.925 0.47) (xy 0.925 0.47) (xy 0.925 -0.47) (xy -0.925 -0.47)
			)
			(stroke
				(width 0.05)
				(type default)
			)
			(fill no)
			(layer "B.CrtYd")
		)
		(fp_line
			(start -0.494 0.25)
			(end 0.504 0.25)
			(stroke
				(width 0.15)
				(type solid)
			)
			(layer "B.Fab")
		)
		(fp_line
			(start 0.504 0.25)
			(end 0.504 -0.248)
			(stroke
				(width 0.15)
				(type solid)
			)
			(layer "B.Fab")
		)
		(fp_line
			(start -0.494 -0.248)
			(end -0.494 0.25)
			(stroke
				(width 0.15)
				(type solid)
			)
			(layer "B.Fab")
		)
		(fp_line
			(start 0.504 -0.248)
			(end -0.494 -0.248)
			(stroke
				(width 0.15)
				(type solid)
			)
			(layer "B.Fab")
		)
		(fp_text user "${REFERENCE}"
			(at -0.939 -4.599 90)
			(layer "B.Fab")
			(effects
				(font
					(size 0.7 0.7)
					(thickness 0.15)
				)
				(justify left bottom mirror)
			)
		)
		(fp_text user "License: Apache-2.0"
			(at -0.939 -5.799 90)
			(layer "B.Fab")
			(effects
				(font
					(size 0.7 0.7)
					(thickness 0.15)
				)
				(justify left bottom mirror)
			)
		)
		(fp_text user "Author: Antmicro"
			(at -0.939 -3.399 90)
			(layer "B.Fab")
			(effects
				(font
					(size 0.7 0.7)
					(thickness 0.15)
				)
				(justify left bottom mirror)
			)
		)
		(pad "1" smd roundrect
			(at -0.48 0 270)
			(size 0.59 0.64)
			(layers "B.Cu" "B.Mask" "B.Paste")
			(roundrect_rratio 0.25)
			(net 1 "GND")
			(pintype "passive")
		)
		(pad "2" smd roundrect
			(at 0.48 0 270)
			(size 0.59 0.64)
			(layers "B.Cu" "B.Mask" "B.Paste")
			(roundrect_rratio 0.25)
			(net 12 "SYS_VIN_HV")
			(pintype "passive")
		)
	)
	(footprint "antmicro-footprints:R_0402_1005Metric"
		(layer "B.Cu")
		(at 111.12 121.6)
		(descr "Resistor SMD 0402")
		(tags "resistor SMD 0402")
		(property "Reference" "R219"
			(at -3.72 -0.39 0)
			(layer "B.SilkS")
			(effects
				(font
					(size 0.7 0.7)
					(thickness 0.15)
				)
				(justify right top mirror)
			)
		)
		(property "Value" "R_0R_0402"
			(at -1.011843 -1.772047 0)
			(layer "B.Fab")
			(effects
				(font
					(size 0.7 0.7)
					(thickness 0.15)
				)
				(justify right top mirror)
			)
		)
		(property "Datasheet" "https://industrial.panasonic.com/cdbs/www-data/pdf/RDA0000/AOA0000C301.pdf"
			(at 0 0 0)
			(layer "B.Fab")
			(hide yes)
			(effects
				(font
					(size 1.27 1.27)
					(thickness 0.15)
				)
				(justify mirror)
			)
		)
		(property "Description" "SMD Chip Resistor, Jumper, 0 ohm, 100 mW, 0402 [1005 Metric], Thick Film, General Purpose"
			(at 0 0 0)
			(layer "B.Fab")
			(hide yes)
			(effects
				(font
					(size 1.27 1.27)
					(thickness 0.15)
				)
				(justify mirror)
			)
		)
		(property "MPN" "ERJ2GE0R00X"
			(at 0 0 180)
			(unlocked yes)
			(layer "B.Fab")
			(hide yes)
			(effects
				(font
					(size 1 1)
					(thickness 0.15)
				)
				(justify mirror)
			)
		)
		(property "Manufacturer" "Panasonic"
			(at 0 0 180)
			(unlocked yes)
			(layer "B.Fab")
			(hide yes)
			(effects
				(font
					(size 1 1)
					(thickness 0.15)
				)
				(justify mirror)
			)
		)
		(property "License" "Apache-2.0"
			(at 0 0 180)
			(unlocked yes)
			(layer "B.Fab")
			(hide yes)
			(effects
				(font
					(size 1 1)
					(thickness 0.15)
				)
				(justify mirror)
			)
		)
		(property "Val" "0R"
			(at 0 0 180)
			(unlocked yes)
			(layer "B.Fab")
			(hide yes)
			(effects
				(font
					(size 1 1)
					(thickness 0.15)
				)
				(justify mirror)
			)
		)
		(property "Tolerance" "~"
			(at 0 0 180)
			(unlocked yes)
			(layer "B.Fab")
			(hide yes)
			(effects
				(font
					(size 1 1)
					(thickness 0.15)
				)
				(justify mirror)
			)
		)
		(property "Current" "1A"
			(at 0 0 180)
			(unlocked yes)
			(layer "B.Fab")
			(hide yes)
			(effects
				(font
					(size 1 1)
					(thickness 0.15)
				)
				(justify mirror)
			)
		)
		(property "Author" "Antmicro"
			(at 0 0 180)
			(unlocked yes)
			(layer "B.Fab")
			(hide yes)
			(effects
				(font
					(size 1 1)
					(thickness 0.15)
				)
				(justify mirror)
			)
		)
		(property "Public" "False"
			(at 0 0 180)
			(unlocked yes)
			(layer "B.Fab")
			(hide yes)
			(effects
				(font
					(size 1 1)
					(thickness 0.15)
				)
				(justify mirror)
			)
		)
		(sheetname "/M.2/")
		(sheetfile "m2.kicad_sch")
		(attr smd)
		(fp_rect
			(start -0.925 0.47)
			(end 0.925 -0.47)
			(stroke
				(width 0.05)
				(type default)
			)
			(fill no)
			(layer "B.CrtYd")
		)
		(fp_rect
			(start -0.5 0.25)
			(end 0.5 -0.25)
			(stroke
				(width 0.15)
				(type solid)
			)
			(fill no)
			(layer "B.Fab")
		)
		(fp_text user "License: Apache-2.0"
			(at -0.95 -5.169 0)
			(layer "B.Fab")
			(effects
				(font
					(size 0.7 0.7)
					(thickness 0.15)
				)
				(justify right top mirror)
			)
		)
		(fp_text user "${REFERENCE}"
			(at -0.95 -3.168 0)
			(layer "B.Fab")
			(effects
				(font
					(size 0.7 0.7)
					(thickness 0.15)
				)
				(justify right top mirror)
			)
		)
		(fp_text user "Author: Antmicro"
			(at -0.95 -4.169 0)
			(layer "B.Fab")
			(effects
				(font
					(size 0.7 0.7)
					(thickness 0.15)
				)
				(justify right top mirror)
			)
		)
		(pad "1" smd roundrect
			(at -0.48 0)
			(size 0.59 0.64)
			(layers "B.Cu" "B.Mask" "B.Paste")
			(roundrect_rratio 0.25)
			(net 642 "/M.2/USB3.D-")
			(pintype "passive")
		)
		(pad "2" smd roundrect
			(at 0.48 0)
			(size 0.59 0.64)
			(layers "B.Cu" "B.Mask" "B.Paste")
			(roundrect_rratio 0.25)
			(net 259 "/M.2/WIFI_BT_USB_D_N")
			(pintype "passive")
		)
	)
	(footprint "antmicro-footprints:TP_SMD_0.75mm"
		(layer "B.Cu")
		(at 218.2 100.3 -90)
		(property "Reference" "TP46"
			(at 0.23 -3.131 0)
			(layer "B.SilkS")
			(effects
				(font
					(size 0.7 0.7)
					(thickness 0.15)
				)
				(justify left bottom mirror)
			)
		)
		(property "Value" "TP_0.75mm_SMD"
			(at 0 -1.2 90)
			(layer "B.Fab")
			(effects
				(font
					(size 0.7 0.7)
					(thickness 0.15)
				)
				(justify left bottom mirror)
			)
		)
		(property "Description" "SMT test point"
			(at 0 0 90)
			(layer "B.Fab")
			(hide yes)
			(effects
				(font
					(size 1.27 1.27)
					(thickness 0.15)
				)
				(justify mirror)
			)
		)
		(property "MPN" ""
			(at 0 0 90)
			(unlocked yes)
			(layer "B.Fab")
			(hide yes)
			(effects
				(font
					(size 1 1)
					(thickness 0.15)
				)
				(justify mirror)
			)
		)
		(property "Manufacturer" ""
			(at 0 0 90)
			(unlocked yes)
			(layer "B.Fab")
			(hide yes)
			(effects
				(font
					(size 1 1)
					(thickness 0.15)
				)
				(justify mirror)
			)
		)
		(property "Author" "Antmicro"
			(at 0 0 90)
			(unlocked yes)
			(layer "B.Fab")
			(hide yes)
			(effects
				(font
					(size 1 1)
					(thickness 0.15)
				)
				(justify mirror)
			)
		)
		(property "License" "Apache-2.0"
			(at 0 0 90)
			(unlocked yes)
			(layer "B.Fab")
			(hide yes)
			(effects
				(font
					(size 1 1)
					(thickness 0.15)
				)
				(justify mirror)
			)
		)
		(sheetname "/Recovery USB/")
		(sheetfile "recovery_usb.kicad_sch")
		(attr exclude_from_pos_files exclude_from_bom)
		(fp_circle
			(center 0 0)
			(end 0.475 0)
			(stroke
				(width 0.05)
				(type default)
			)
			(fill no)
			(layer "B.CrtYd")
		)
		(fp_text user "${REFERENCE}"
			(at -0.4 -2.7 90)
			(layer "B.Fab")
			(effects
				(font
					(size 0.7 0.7)
					(thickness 0.15)
				)
				(justify left bottom mirror)
			)
		)
		(fp_text user "Author: Antmicro"
			(at -0.4 -3.901 90)
			(layer "B.Fab")
			(effects
				(font
					(size 0.7 0.7)
					(thickness 0.15)
				)
				(justify left bottom mirror)
			)
		)
		(fp_text user "License: Apache-2.0"
			(at -0.4 -5.101 90)
			(layer "B.Fab")
			(effects
				(font
					(size 0.7 0.7)
					(thickness 0.15)
				)
				(justify left bottom mirror)
			)
		)
		(pad "1" smd circle
			(at 0 0 270)
			(size 0.75 0.75)
			(layers "B.Cu" "B.Mask")
			(net 1014 "/Recovery USB/USBC2_FAULT_N")
			(pinfunction "1")
			(pintype "passive")
		)
	)
	(footprint "antmicro-footprints:C_0805_2012Metric"
		(layer "B.Cu")
		(at 229.1 108.3 90)
		(descr "Capacitor SMD 0805")
		(tags "capacitor SMD 0805")
		(property "Reference" "C115"
			(at -4.5 0.7 90)
			(layer "B.SilkS")
			(effects
				(font
					(size 0.7 0.7)
					(thickness 0.15)
				)
				(justify right top mirror)
			)
		)
		(property "Value" "C_22u_25V_0805"
			(at -2.055717 -1.963153 90)
			(layer "B.Fab")
			(effects
				(font
					(size 0.7 0.7)
					(thickness 0.15)
				)
				(justify right top mirror)
			)
		)
		(property "Datasheet" "https://product.samsungsem.com/mlcc/CL21A226MAYNNN.do"
			(at 0 0 90)
			(layer "B.Fab")
			(hide yes)
			(effects
				(font
					(size 1.27 1.27)
					(thickness 0.15)
				)
				(justify mirror)
			)
		)
		(property "Description" "SMT Multilayer Ceramic Capacitor, 22uF, +/-20%, 25V, X5R, 0805 [2012 Metric]"
			(at 0 0 90)
			(layer "B.Fab")
			(hide yes)
			(effects
				(font
					(size 1.27 1.27)
					(thickness 0.15)
				)
				(justify mirror)
			)
		)
		(property "Manufacturer" "Samsung Electro-Mechanics"
			(at 0 0 90)
			(unlocked yes)
			(layer "B.Fab")
			(hide yes)
			(effects
				(font
					(size 1 1)
					(thickness 0.15)
				)
				(justify mirror)
			)
		)
		(property "MPN" "CL21A226MAYNNNE"
			(at 0 0 90)
			(unlocked yes)
			(layer "B.Fab")
			(hide yes)
			(effects
				(font
					(size 1 1)
					(thickness 0.15)
				)
				(justify mirror)
			)
		)
		(property "Val" "22u"
			(at 0 0 90)
			(unlocked yes)
			(layer "B.Fab")
			(hide yes)
			(effects
				(font
					(size 1 1)
					(thickness 0.15)
				)
				(justify mirror)
			)
		)
		(property "License" "Apache-2.0"
			(at 0 0 90)
			(unlocked yes)
			(layer "B.Fab")
			(hide yes)
			(effects
				(font
					(size 1 1)
					(thickness 0.15)
				)
				(justify mirror)
			)
		)
		(property "Author" "Antmicro"
			(at 0 0 90)
			(unlocked yes)
			(layer "B.Fab")
			(hide yes)
			(effects
				(font
					(size 1 1)
					(thickness 0.15)
				)
				(justify mirror)
			)
		)
		(property "Voltage" "25V"
			(at 0 0 90)
			(unlocked yes)
			(layer "B.Fab")
			(hide yes)
			(effects
				(font
					(size 1 1)
					(thickness 0.15)
				)
				(justify mirror)
			)
		)
		(property "Dielectric" "X5R"
			(at 0 0 90)
			(unlocked yes)
			(layer "B.Fab")
			(hide yes)
			(effects
				(font
					(size 1 1)
					(thickness 0.15)
				)
				(justify mirror)
			)
		)
		(property "Public" "False"
			(at 0 0 90)
			(unlocked yes)
			(layer "B.Fab")
			(hide yes)
			(effects
				(font
					(size 1 1)
					(thickness 0.15)
				)
				(justify mirror)
			)
		)
		(sheetname "/Recovery USB/")
		(sheetfile "recovery_usb.kicad_sch")
		(attr smd)
		(fp_line
			(start -0.3 -0.7)
			(end 0.3 -0.7)
			(stroke
				(width 0.15)
				(type solid)
			)
			(layer "B.SilkS")
		)
		(fp_line
			(start -0.3 0.7)
			(end 0.3 0.7)
			(stroke
				(width 0.15)
				(type solid)
			)
			(layer "B.SilkS")
		)
		(fp_poly
			(pts
				(xy 1.95 0.9) (xy -1.95 0.9) (xy -1.95 -0.9) (xy 1.95 -0.9)
			)
			(stroke
				(width 0.05)
				(type default)
			)
			(fill no)
			(layer "B.CrtYd")
		)
		(fp_poly
			(pts
				(xy -0.95 0.675001) (xy 0.95 0.675001) (xy 0.95 -0.675001) (xy -0.95 -0.675001)
			)
			(stroke
				(width 0.15)
				(type solid)
			)
			(fill no)
			(layer "B.Fab")
		)
		(fp_text user "${REFERENCE}"
			(at -1.899999 -3.947 90)
			(layer "B.Fab")
			(effects
				(font
					(size 0.7 0.7)
					(thickness 0.15)
				)
				(justify right top mirror)
			)
		)
		(fp_text user "Author: Antmicro"
			(at -1.9 -5.947 90)
			(layer "B.Fab")
			(effects
				(font
					(size 0.7 0.7)
					(thickness 0.15)
				)
				(justify right top mirror)
			)
		)
		(fp_text user "License: Apache-2.0"
			(at -1.9 -4.947 90)
			(layer "B.Fab")
			(effects
				(font
					(size 0.7 0.7)
					(thickness 0.15)
				)
				(justify right top mirror)
			)
		)
		(pad "1" smd roundrect
			(at -1.099999 0 90)
			(size 1.2 1.3)
			(layers "B.Cu" "B.Mask" "B.Paste")
			(roundrect_rratio 0.25)
			(net 287 "/Recovery USB/USBC2_VBUS")
			(pintype "passive")
		)
		(pad "2" smd roundrect
			(at 1.099999 0 90)
			(size 1.2 1.3)
			(layers "B.Cu" "B.Mask" "B.Paste")
			(roundrect_rratio 0.25)
			(net 1 "GND")
			(pintype "passive")
		)
	)
	(footprint "antmicro-footprints:LED_0603_1608Metric_G"
		(layer "B.Cu")
		(at 235.425 65.175 180)
		(descr "LED SMD 0603 Green")
		(tags "LED SMD 0603 Green")
		(property "Reference" "D65"
			(at 4.025 -0.025 0)
			(layer "B.SilkS")
			(effects
				(font
					(size 0.7 0.7)
					(thickness 0.15)
				)
				(justify left bottom mirror)
			)
		)
		(property "Value" "LED_G_0603_LTST-C190GKT"
			(at -0.001 -1.599 0)
			(layer "B.Fab")
			(effects
				(font
					(size 0.7 0.7)
					(thickness 0.15)
				)
				(justify left bottom mirror)
			)
		)
		(property "Datasheet" "https://media.digikey.com/pdf/Data%20Sheets/Lite-On%20PDFs/LTST-C190GKT.pdf"
			(at 0 0 0)
			(layer "B.Fab")
			(hide yes)
			(effects
				(font
					(size 1.27 1.27)
					(thickness 0.15)
				)
				(justify mirror)
			)
		)
		(property "Description" "LED, Green, SMD, 0603, 20 mA, 2.1 V, 569 nm"
			(at 0 0 0)
			(layer "B.Fab")
			(hide yes)
			(effects
				(font
					(size 1.27 1.27)
					(thickness 0.15)
				)
				(justify mirror)
			)
		)
		(property "MPN" "LTST-C190GKT"
			(at 0 0 0)
			(unlocked yes)
			(layer "B.Fab")
			(hide yes)
			(effects
				(font
					(size 1 1)
					(thickness 0.15)
				)
				(justify mirror)
			)
		)
		(property "Manufacturer" "Lite-On"
			(at 0 0 0)
			(unlocked yes)
			(layer "B.Fab")
			(hide yes)
			(effects
				(font
					(size 1 1)
					(thickness 0.15)
				)
				(justify mirror)
			)
		)
		(property "Author" "Antmicro"
			(at 0 0 0)
			(unlocked yes)
			(layer "B.Fab")
			(hide yes)
			(effects
				(font
					(size 1 1)
					(thickness 0.15)
				)
				(justify mirror)
			)
		)
		(property "License" "Apache-2.0"
			(at 0 0 0)
			(unlocked yes)
			(layer "B.Fab")
			(hide yes)
			(effects
				(font
					(size 1 1)
					(thickness 0.15)
				)
				(justify mirror)
			)
		)
		(property "Color" "Green"
			(at 0 0 0)
			(unlocked yes)
			(layer "B.Fab")
			(hide yes)
			(effects
				(font
					(size 1 1)
					(thickness 0.15)
				)
				(justify mirror)
			)
		)
		(sheetname "/SoM_Power/")
		(sheetfile "som_power.kicad_sch")
		(attr smd)
		(fp_line
			(start 0.22 0.35)
			(end -0.22 0.35)
			(stroke
				(width 0.15)
				(type solid)
			)
			(layer "B.SilkS")
		)
		(fp_line
			(start 0.22 -0.35)
			(end -0.22 -0.35)
			(stroke
				(width 0.15)
				(type solid)
			)
			(layer "B.SilkS")
		)
		(fp_line
			(start 0.105328 -0.001008)
			(end 0.240001 -0.001)
			(stroke
				(width 0.1)
				(type solid)
			)
			(layer "B.SilkS")
		)
		(fp_line
			(start 0.105328 -0.201008)
			(end 0.105329 0.198992)
			(stroke
				(width 0.1)
				(type solid)
			)
			(layer "B.SilkS")
		)
		(fp_line
			(start 0.105328 -0.201008)
			(end -0.094672 -0.001008)
			(stroke
				(width 0.1)
				(type solid)
			)
			(layer "B.SilkS")
		)
		(fp_line
			(start -0.094672 -0.001008)
			(end 0.105329 0.198992)
			(stroke
				(width 0.1)
				(type solid)
			)
			(layer "B.SilkS")
		)
		(fp_line
			(start -0.094672 -0.001008)
			(end -0.24 -0.001008)
			(stroke
				(width 0.1)
				(type solid)
			)
			(layer "B.SilkS")
		)
		(fp_line
			(start -0.094672 -0.201008)
			(end -0.094672 0.198992)
			(stroke
				(width 0.1)
				(type solid)
			)
			(layer "B.SilkS")
		)
		(fp_line
			(start -1.18 0.319)
			(end -1.18 -0.321)
			(stroke
				(width 0.15)
				(type solid)
			)
			(layer "B.SilkS")
		)
		(fp_poly
			(pts
				(xy 1.25 -0.65) (xy -1.25 -0.65) (xy -1.25 0.65) (xy 1.25 0.65)
			)
			(stroke
				(width 0.05)
				(type solid)
			)
			(fill no)
			(layer "B.CrtYd")
		)
		(fp_line
			(start 0.599 0)
			(end 0.200999 0)
			(stroke
				(width 0.15)
				(type solid)
			)
			(layer "B.Fab")
		)
		(fp_line
			(start 0.201 0.202)
			(end -0.101 0)
			(stroke
				(width 0.15)
				(type solid)
			)
			(layer "B.Fab")
		)
		(fp_line
			(start 0.201 -0.2)
			(end 0.200999 0)
			(stroke
				(width 0.15)
				(type solid)
			)
			(layer "B.Fab")
		)
		(fp_line
			(start 0.200999 0)
			(end 0.201 0.202)
			(stroke
				(width 0.15)
				(type solid)
			)
			(layer "B.Fab")
		)
		(fp_line
			(start -0.101 0)
			(end 0.201 -0.2)
			(stroke
				(width 0.15)
				(type solid)
			)
			(layer "B.Fab")
		)
		(fp_line
			(start -0.199 0.202)
			(end -0.199 -0.1)
			(stroke
				(width 0.15)
				(type solid)
			)
			(layer "B.Fab")
		)
		(fp_line
			(start -0.199 0)
			(end -0.597 0)
			(stroke
				(width 0.15)
				(type solid)
			)
			(layer "B.Fab")
		)
		(fp_line
			(start -0.199 -0.2)
			(end -0.199 -0.1)
			(stroke
				(width 0.15)
				(type solid)
			)
			(layer "B.Fab")
		)
		(fp_poly
			(pts
				(xy 0.848 -0.4) (xy -0.85 -0.4) (xy -0.85 0.402) (xy 0.848 0.401999)
			)
			(stroke
				(width 0.15)
				(type solid)
			)
			(fill no)
			(layer "B.Fab")
		)
		(fp_text user "Author: Antmicro"
			(at -1.4224 -4.799 0)
			(layer "B.Fab")
			(effects
				(font
					(size 0.7 0.7)
					(thickness 0.15)
				)
				(justify left bottom mirror)
			)
		)
		(fp_text user "${REFERENCE}"
			(at -1.4224 -5.999 0)
			(layer "B.Fab")
			(effects
				(font
					(size 0.7 0.7)
					(thickness 0.15)
				)
				(justify left bottom mirror)
			)
		)
		(fp_text user "License: Apache-2.0"
			(at -1.4224 -3.599 0)
			(layer "B.Fab")
			(effects
				(font
					(size 0.7 0.7)
					(thickness 0.15)
				)
				(justify left bottom mirror)
			)
		)
		(pad "1" smd roundrect
			(at -0.7 0)
			(size 0.8 1)
			(layers "B.Cu" "B.Mask" "B.Paste")
			(roundrect_rratio 0.2)
			(net 1393 "Net-(D65-C)")
			(pinfunction "C")
			(pintype "passive")
		)
		(pad "2" smd roundrect
			(at 0.7 0)
			(size 0.8 1)
			(layers "B.Cu" "B.Mask" "B.Paste")
			(roundrect_rratio 0.2)
			(net 1394 "Net-(D65-A)")
			(pinfunction "A")
			(pintype "passive")
		)
	)
	(footprint "antmicro-footprints:TP_SMD_0.75mm"
		(layer "B.Cu")
		(at 200.2 116.4 90)
		(property "Reference" "TP65"
			(at 0.58 -0.33 90)
			(layer "B.SilkS")
			(effects
				(font
					(size 0.7 0.7)
					(thickness 0.15)
				)
				(justify right top mirror)
			)
		)
		(property "Value" "TP_0.75mm_SMD"
			(at 0 -1.2 90)
			(layer "B.Fab")
			(effects
				(font
					(size 0.7 0.7)
					(thickness 0.15)
				)
				(justify right top mirror)
			)
		)
		(property "Description" "SMT test point"
			(at 0 0 90)
			(layer "B.Fab")
			(hide yes)
			(effects
				(font
					(size 1.27 1.27)
					(thickness 0.15)
				)
				(justify mirror)
			)
		)
		(property "MPN" ""
			(at 0 0 270)
			(unlocked yes)
			(layer "B.Fab")
			(hide yes)
			(effects
				(font
					(size 1 1)
					(thickness 0.15)
				)
				(justify mirror)
			)
		)
		(property "Manufacturer" ""
			(at 0 0 270)
			(unlocked yes)
			(layer "B.Fab")
			(hide yes)
			(effects
				(font
					(size 1 1)
					(thickness 0.15)
				)
				(justify mirror)
			)
		)
		(property "Author" "Antmicro"
			(at 0 0 270)
			(unlocked yes)
			(layer "B.Fab")
			(hide yes)
			(effects
				(font
					(size 1 1)
					(thickness 0.15)
				)
				(justify mirror)
			)
		)
		(property "License" "Apache-2.0"
			(at 0 0 270)
			(unlocked yes)
			(layer "B.Fab")
			(hide yes)
			(effects
				(font
					(size 1 1)
					(thickness 0.15)
				)
				(justify mirror)
			)
		)
		(sheetname "/USB Hub/")
		(sheetfile "usb_hub.kicad_sch")
		(attr exclude_from_pos_files exclude_from_bom)
		(fp_circle
			(center 0 0)
			(end 0.475 0)
			(stroke
				(width 0.05)
				(type default)
			)
			(fill no)
			(layer "B.CrtYd")
		)
		(fp_text user "${REFERENCE}"
			(at -0.4 -2.7 90)
			(layer "B.Fab")
			(effects
				(font
					(size 0.7 0.7)
					(thickness 0.15)
				)
				(justify right top mirror)
			)
		)
		(fp_text user "Author: Antmicro"
			(at -0.4 -3.901 90)
			(layer "B.Fab")
			(effects
				(font
					(size 0.7 0.7)
					(thickness 0.15)
				)
				(justify right top mirror)
			)
		)
		(fp_text user "License: Apache-2.0"
			(at -0.4 -5.101 90)
			(layer "B.Fab")
			(effects
				(font
					(size 0.7 0.7)
					(thickness 0.15)
				)
				(justify right top mirror)
			)
		)
		(pad "1" smd circle
			(at 0 0 90)
			(size 0.75 0.75)
			(layers "B.Cu" "B.Mask")
			(net 1085 "/USB Hub/DP2_DISCH")
			(pinfunction "1")
			(pintype "passive")
		)
	)
	(footprint "antmicro-footprints:Spacer_Drill3.7mm_H8mm_9774080151R"
		(locked yes)
		(layer "B.Cu")
		(at 152.430532 63.71 180)
		(descr "Spacer M=3 h=8mm fi=5.1mm")
		(property "Reference" "H11"
			(at 0 3.2 0)
			(layer "B.SilkS")
			(effects
				(font
					(size 0.7 0.7)
					(thickness 0.15)
				)
				(justify left bottom mirror)
			)
		)
		(property "Value" "Spacer_Drill3.7mm_H8mm_9774080151R"
			(at 0 -4 0)
			(layer "B.Fab")
			(effects
				(font
					(size 0.7 0.7)
					(thickness 0.15)
				)
				(justify left bottom mirror)
			)
		)
		(property "Datasheet" "https://www.we-online.com/components/products/datasheet/9774080151R.pdf"
			(at 0 0 0)
			(layer "B.Fab")
			(hide yes)
			(effects
				(font
					(size 1.27 1.27)
					(thickness 0.15)
				)
				(justify mirror)
			)
		)
		(property "Description" "Spacer, SMT, Non Stop, Steel, Swage Round, 5.1 mm x 8 mm, M2.5 Thread, WA-SMSI Series"
			(at 0 0 0)
			(layer "B.Fab")
			(hide yes)
			(effects
				(font
					(size 1.27 1.27)
					(thickness 0.15)
				)
				(justify mirror)
			)
		)
		(property "Manufacturer" "Würth Elektronik"
			(at 0 0 180)
			(unlocked yes)
			(layer "B.Fab")
			(hide yes)
			(effects
				(font
					(size 1 1)
					(thickness 0.15)
				)
				(justify mirror)
			)
		)
		(property "MPN" "9774080151R"
			(at 0 0 180)
			(unlocked yes)
			(layer "B.Fab")
			(hide yes)
			(effects
				(font
					(size 1 1)
					(thickness 0.15)
				)
				(justify mirror)
			)
		)
		(property "Author" "Antmicro"
			(at 0 0 180)
			(unlocked yes)
			(layer "B.Fab")
			(hide yes)
			(effects
				(font
					(size 1 1)
					(thickness 0.15)
				)
				(justify mirror)
			)
		)
		(property "License" "Apache-2.0"
			(at 0 0 180)
			(unlocked yes)
			(layer "B.Fab")
			(hide yes)
			(effects
				(font
					(size 1 1)
					(thickness 0.15)
				)
				(justify mirror)
			)
		)
		(sheetname "/")
		(sheetfile "jetson-agx-thor-baseboard.kicad_sch")
		(solder_paste_margin_ratio -1)
		(attr smd)
		(fp_circle
			(center 0 0)
			(end 3.05 0)
			(stroke
				(width 0.05)
				(type solid)
			)
			(fill no)
			(layer "B.CrtYd")
		)
		(fp_circle
			(center 0 0)
			(end 2.6 0)
			(stroke
				(width 0.15)
				(type solid)
			)
			(fill no)
			(layer "B.Fab")
		)
		(fp_text user "Author: Antmicro"
			(at -9.6 -7.7 0)
			(layer "B.Fab")
			(effects
				(font
					(size 0.7 0.7)
					(thickness 0.15)
				)
				(justify left bottom mirror)
			)
		)
		(fp_text user "License: Apache-2.0"
			(at -9.6 -8.9 0)
			(layer "B.Fab")
			(effects
				(font
					(size 0.7 0.7)
					(thickness 0.15)
				)
				(justify left bottom mirror)
			)
		)
		(fp_text user "${REFERENCE}"
			(at -9.6 -6.5 0)
			(layer "B.Fab")
			(effects
				(font
					(size 0.7 0.7)
					(thickness 0.15)
				)
				(justify left bottom mirror)
			)
		)
		(pad "" smd custom
			(at -1.7 -1.7 90)
			(size 0.62 0.62)
			(layers "B.Paste")
			(thermal_bridge_angle 90)
			(options
				(clearance outline)
				(anchor circle)
			)
			(primitives
				(gr_arc
					(start 1.266786 0.24747)
					(mid 0.285453 -0.29439)
					(end -0.250195 -1.279127)
					(width 0.2)
				)
				(gr_arc
					(start 1.259603 0.339191)
					(mid 0.218448 -0.232561)
					(end -0.34334 -1.279127)
					(width 0.2)
				)
				(gr_arc
					(start 1.255279 0.431435)
					(mid 0.152481 -0.169693)
					(end -0.436309 -1.279127)
					(width 0.2)
				)
				(gr_arc
					(start 1.253811 0.524161)
					(mid 0.087542 -0.105784)
					(end -0.529126 -1.279127)
					(width 0.2)
				)
				(gr_arc
					(start 1.275473 0.621136)
					(mid 0.0309 -0.033527)
					(end -0.621807 -1.279127)
					(width 0.2)
				)
				(gr_arc
					(start 1.263664 0.711602)
					(mid -0.037759 0.026651)
					(end -0.71437 -1.279127)
					(width 0.2)
				)
				(gr_arc
					(start 1.253435 0.802342)
					(mid -0.105837 0.087395)
					(end -0.806826 -1.279127)
					(width 0.2)
				)
				(gr_arc
					(start 1.267475 0.897258)
					(mid -0.165236 0.156885)
					(end -0.899187 -1.279127)
					(width 0.2)
				)
				(gr_arc
					(start 1.270645 0.990112)
					(mid -0.228522 0.222449)
					(end -0.991463 -1.279127)
					(width 0.2)
				)
				(gr_arc
					(start 1.266278 1.081674)
					(mid -0.294507 0.285313)
					(end -1.083663 -1.279127)
					(width 0.2)
				)
				(gr_line
					(start 1.279127 0.250195)
					(end 1.279127 1.083663)
					(width 0.2)
				)
				(gr_line
					(start -0.250195 -1.279127)
					(end -1.083663 -1.279127)
					(width 0.2)
				)
			)
		)
		(pad "" smd custom
			(at -1.7 1.7 180)
			(size 0.62 0.62)
			(layers "B.Paste")
			(thermal_bridge_angle 90)
			(options
				(clearance outline)
				(anchor circle)
			)
			(primitives
				(gr_arc
					(start 1.266786 0.24747)
					(mid 0.285453 -0.29439)
					(end -0.250195 -1.279127)
					(width 0.2)
				)
				(gr_arc
					(start 1.259603 0.339191)
					(mid 0.218448 -0.232561)
					(end -0.34334 -1.279127)
					(width 0.2)
				)
				(gr_arc
					(start 1.255279 0.431435)
					(mid 0.152481 -0.169693)
					(end -0.436309 -1.279127)
					(width 0.2)
				)
				(gr_arc
					(start 1.253811 0.524161)
					(mid 0.087542 -0.105784)
					(end -0.529126 -1.279127)
					(width 0.2)
				)
				(gr_arc
					(start 1.275473 0.621136)
					(mid 0.0309 -0.033527)
					(end -0.621807 -1.279127)
					(width 0.2)
				)
				(gr_arc
					(start 1.263664 0.711602)
					(mid -0.037759 0.026651)
					(end -0.71437 -1.279127)
					(width 0.2)
				)
				(gr_arc
					(start 1.253435 0.802342)
					(mid -0.105837 0.087395)
					(end -0.806826 -1.279127)
					(width 0.2)
				)
				(gr_arc
					(start 1.267475 0.897258)
					(mid -0.165236 0.156885)
					(end -0.899187 -1.279127)
					(width 0.2)
				)
				(gr_arc
					(start 1.270645 0.990112)
					(mid -0.228522 0.222449)
					(end -0.991463 -1.279127)
					(width 0.2)
				)
				(gr_arc
					(start 1.266278 1.081674)
					(mid -0.294507 0.285313)
					(end -1.083663 -1.279127)
					(width 0.2)
				)
				(gr_line
					(start 1.279127 0.250195)
					(end 1.279127 1.083663)
					(width 0.2)
				)
				(gr_line
					(start -0.250195 -1.279127)
					(end -1.083663 -1.279127)
					(width 0.2)
				)
			)
		)
		(pad "" smd custom
			(at 1.7 -1.7)
			(size 0.62 0.62)
			(layers "B.Paste")
			(thermal_bridge_angle 90)
			(options
				(clearance outline)
				(anchor circle)
			)
			(primitives
				(gr_arc
					(start 1.266786 0.24747)
					(mid 0.285453 -0.29439)
					(end -0.250195 -1.279127)
					(width 0.2)
				)
				(gr_arc
					(start 1.259603 0.339191)
					(mid 0.218448 -0.232561)
					(end -0.34334 -1.279127)
					(width 0.2)
				)
				(gr_arc
					(start 1.255279 0.431435)
					(mid 0.152481 -0.169693)
					(end -0.436309 -1.279127)
					(width 0.2)
				)
				(gr_arc
					(start 1.253811 0.524161)
					(mid 0.087542 -0.105784)
					(end -0.529126 -1.279127)
					(width 0.2)
				)
				(gr_arc
					(start 1.275473 0.621136)
					(mid 0.0309 -0.033527)
					(end -0.621807 -1.279127)
					(width 0.2)
				)
				(gr_arc
					(start 1.263664 0.711602)
					(mid -0.037759 0.026651)
					(end -0.71437 -1.279127)
					(width 0.2)
				)
				(gr_arc
					(start 1.253435 0.802342)
					(mid -0.105837 0.087395)
					(end -0.806826 -1.279127)
					(width 0.2)
				)
				(gr_arc
					(start 1.267475 0.897258)
					(mid -0.165236 0.156885)
					(end -0.899187 -1.279127)
					(width 0.2)
				)
				(gr_arc
					(start 1.270645 0.990112)
					(mid -0.228522 0.222449)
					(end -0.991463 -1.279127)
					(width 0.2)
				)
				(gr_arc
					(start 1.266278 1.081674)
					(mid -0.294507 0.285313)
					(end -1.083663 -1.279127)
					(width 0.2)
				)
				(gr_line
					(start 1.279127 0.250195)
					(end 1.279127 1.083663)
					(width 0.2)
				)
				(gr_line
					(start -0.250195 -1.279127)
					(end -1.083663 -1.279127)
					(width 0.2)
				)
			)
		)
		(pad "" smd custom
			(at 1.7 1.7 270)
			(size 0.62 0.62)
			(layers "B.Paste")
			(thermal_bridge_angle 90)
			(options
				(clearance outline)
				(anchor circle)
			)
			(primitives
				(gr_arc
					(start 1.266786 0.24747)
					(mid 0.285453 -0.29439)
					(end -0.250195 -1.279127)
					(width 0.2)
				)
				(gr_arc
					(start 1.259603 0.339191)
					(mid 0.218448 -0.232561)
					(end -0.34334 -1.279127)
					(width 0.2)
				)
				(gr_arc
					(start 1.255279 0.431435)
					(mid 0.152481 -0.169693)
					(end -0.436309 -1.279127)
					(width 0.2)
				)
				(gr_arc
					(start 1.253811 0.524161)
					(mid 0.087542 -0.105784)
					(end -0.529126 -1.279127)
					(width 0.2)
				)
				(gr_arc
					(start 1.275473 0.621136)
					(mid 0.0309 -0.033527)
					(end -0.621807 -1.279127)
					(width 0.2)
				)
				(gr_arc
					(start 1.263664 0.711602)
					(mid -0.037759 0.026651)
					(end -0.71437 -1.279127)
					(width 0.2)
				)
				(gr_arc
					(start 1.253435 0.802342)
					(mid -0.105837 0.087395)
					(end -0.806826 -1.279127)
					(width 0.2)
				)
				(gr_arc
					(start 1.267475 0.897258)
					(mid -0.165236 0.156885)
					(end -0.899187 -1.279127)
					(width 0.2)
				)
				(gr_arc
					(start 1.270645 0.990112)
					(mid -0.228522 0.222449)
					(end -0.991463 -1.279127)
					(width 0.2)
				)
				(gr_arc
					(start 1.266278 1.081674)
					(mid -0.294507 0.285313)
					(end -1.083663 -1.279127)
					(width 0.2)
				)
				(gr_line
					(start 1.279127 0.250195)
					(end 1.279127 1.083663)
					(width 0.2)
				)
				(gr_line
					(start -0.250195 -1.279127)
					(end -1.083663 -1.279127)
					(width 0.2)
				)
			)
		)
		(pad "1" thru_hole circle
			(at 0 0 180)
			(size 6 6)
			(drill 3.7)
			(layers "*.Cu" "*.Mask")
			(remove_unused_layers no)
			(net 1 "GND")
			(pintype "passive")
		)
	)
	(footprint "antmicro-footprints:R_0402_1005Metric"
		(layer "B.Cu")
		(at 238.579002 93.424001)
		(descr "Resistor SMD 0402")
		(tags "resistor SMD 0402")
		(property "Reference" "R142"
			(at -1.579002 -2.624001 0)
			(layer "B.SilkS")
			(effects
				(font
					(size 0.7 0.7)
					(thickness 0.15)
				)
				(justify right top mirror)
			)
		)
		(property "Value" "R_0R_0402"
			(at -1.011843 -1.772046 0)
			(layer "B.Fab")
			(effects
				(font
					(size 0.7 0.7)
					(thickness 0.15)
				)
				(justify right top mirror)
			)
		)
		(property "Datasheet" "https://industrial.panasonic.com/cdbs/www-data/pdf/RDA0000/AOA0000C301.pdf"
			(at 0 0 0)
			(layer "B.Fab")
			(hide yes)
			(effects
				(font
					(size 1.27 1.27)
					(thickness 0.15)
				)
				(justify mirror)
			)
		)
		(property "Description" "SMD Chip Resistor, Jumper, 0 ohm, 100 mW, 0402 [1005 Metric], Thick Film, General Purpose"
			(at 0 0 0)
			(layer "B.Fab")
			(hide yes)
			(effects
				(font
					(size 1.27 1.27)
					(thickness 0.15)
				)
				(justify mirror)
			)
		)
		(property "Manufacturer" "Panasonic"
			(at 0 0 180)
			(unlocked yes)
			(layer "B.Fab")
			(hide yes)
			(effects
				(font
					(size 1 1)
					(thickness 0.15)
				)
				(justify mirror)
			)
		)
		(property "MPN" "ERJ2GE0R00X"
			(at 0 0 180)
			(unlocked yes)
			(layer "B.Fab")
			(hide yes)
			(effects
				(font
					(size 1 1)
					(thickness 0.15)
				)
				(justify mirror)
			)
		)
		(property "Val" "0R"
			(at 0 0 180)
			(unlocked yes)
			(layer "B.Fab")
			(hide yes)
			(effects
				(font
					(size 1 1)
					(thickness 0.15)
				)
				(justify mirror)
			)
		)
		(property "License" "Apache-2.0"
			(at 0 0 180)
			(unlocked yes)
			(layer "B.Fab")
			(hide yes)
			(effects
				(font
					(size 1 1)
					(thickness 0.15)
				)
				(justify mirror)
			)
		)
		(property "Author" "Antmicro"
			(at 0 0 180)
			(unlocked yes)
			(layer "B.Fab")
			(hide yes)
			(effects
				(font
					(size 1 1)
					(thickness 0.15)
				)
				(justify mirror)
			)
		)
		(property "Tolerance" "~"
			(at 0 0 180)
			(unlocked yes)
			(layer "B.Fab")
			(hide yes)
			(effects
				(font
					(size 1 1)
					(thickness 0.15)
				)
				(justify mirror)
			)
		)
		(property "Current" "1A"
			(at 0 0 180)
			(unlocked yes)
			(layer "B.Fab")
			(hide yes)
			(effects
				(font
					(size 1 1)
					(thickness 0.15)
				)
				(justify mirror)
			)
		)
		(sheetname "/USB DP Alt mode/")
		(sheetfile "usb_dp.kicad_sch")
		(attr smd exclude_from_pos_files exclude_from_bom dnp)
		(fp_poly
			(pts
				(xy -0.925 0.47) (xy -0.925 -0.47) (xy 0.925 -0.47) (xy 0.925 0.47)
			)
			(stroke
				(width 0.05)
				(type default)
			)
			(fill no)
			(layer "B.CrtYd")
		)
		(fp_poly
			(pts
				(xy -0.5 0.25) (xy -0.5 -0.25) (xy 0.5 -0.25) (xy 0.5 0.25)
			)
			(stroke
				(width 0.15)
				(type solid)
			)
			(fill no)
			(layer "B.Fab")
		)
		(fp_text user "License: Apache-2.0"
			(at -0.949999 -5.169 0)
			(layer "B.Fab")
			(effects
				(font
					(size 0.7 0.7)
					(thickness 0.15)
				)
				(justify right top mirror)
			)
		)
		(fp_text user "${REFERENCE}"
			(at -0.95 -3.168 0)
			(layer "B.Fab")
			(effects
				(font
					(size 0.7 0.7)
					(thickness 0.15)
				)
				(justify right top mirror)
			)
		)
		(fp_text user "Author: Antmicro"
			(at -0.95 -4.169 0)
			(layer "B.Fab")
			(effects
				(font
					(size 0.7 0.7)
					(thickness 0.15)
				)
				(justify right top mirror)
			)
		)
		(pad "1" smd roundrect
			(at -0.48 0)
			(size 0.59 0.64)
			(layers "B.Cu" "B.Mask" "B.Paste")
			(roundrect_rratio 0.25)
			(net 970 "/USB DP Alt mode/USBC1_5V_PEN")
			(pintype "passive")
		)
		(pad "2" smd roundrect
			(at 0.48 0)
			(size 0.59 0.64)
			(layers "B.Cu" "B.Mask" "B.Paste")
			(roundrect_rratio 0.25)
			(net 5 "+5V")
			(pintype "passive")
		)
	)
	(footprint "antmicro-footprints:TP_SMD_0.75mm"
		(layer "B.Cu")
		(at 127.4 152.2 -90)
		(property "Reference" "TP96"
			(at 0.4 0.6 0)
			(layer "B.SilkS")
			(effects
				(font
					(size 0.7 0.7)
					(thickness 0.15)
				)
				(justify left bottom mirror)
			)
		)
		(property "Value" "TP_0.75mm_SMD"
			(at 0 -1.2 90)
			(layer "B.Fab")
			(effects
				(font
					(size 0.7 0.7)
					(thickness 0.15)
				)
				(justify left bottom mirror)
			)
		)
		(property "Description" "SMT test point"
			(at 0 0 90)
			(layer "B.Fab")
			(hide yes)
			(effects
				(font
					(size 1.27 1.27)
					(thickness 0.15)
				)
				(justify mirror)
			)
		)
		(property "MPN" ""
			(at 0 0 90)
			(unlocked yes)
			(layer "B.Fab")
			(hide yes)
			(effects
				(font
					(size 1 1)
					(thickness 0.15)
				)
				(justify mirror)
			)
		)
		(property "Manufacturer" ""
			(at 0 0 90)
			(unlocked yes)
			(layer "B.Fab")
			(hide yes)
			(effects
				(font
					(size 1 1)
					(thickness 0.15)
				)
				(justify mirror)
			)
		)
		(property "Author" "Antmicro"
			(at 0 0 90)
			(unlocked yes)
			(layer "B.Fab")
			(hide yes)
			(effects
				(font
					(size 1 1)
					(thickness 0.15)
				)
				(justify mirror)
			)
		)
		(property "License" "Apache-2.0"
			(at 0 0 90)
			(unlocked yes)
			(layer "B.Fab")
			(hide yes)
			(effects
				(font
					(size 1 1)
					(thickness 0.15)
				)
				(justify mirror)
			)
		)
		(sheetname "/Peripherals/")
		(sheetfile "peripherals.kicad_sch")
		(attr exclude_from_pos_files exclude_from_bom)
		(fp_circle
			(center 0 0)
			(end 0.475 0)
			(stroke
				(width 0.05)
				(type default)
			)
			(fill no)
			(layer "B.CrtYd")
		)
		(fp_text user "Author: Antmicro"
			(at -0.4 -3.901 90)
			(layer "B.Fab")
			(effects
				(font
					(size 0.7 0.7)
					(thickness 0.15)
				)
				(justify left bottom mirror)
			)
		)
		(fp_text user "${REFERENCE}"
			(at -0.4 -2.7 90)
			(layer "B.Fab")
			(effects
				(font
					(size 0.7 0.7)
					(thickness 0.15)
				)
				(justify left bottom mirror)
			)
		)
		(fp_text user "License: Apache-2.0"
			(at -0.4 -5.101 90)
			(layer "B.Fab")
			(effects
				(font
					(size 0.7 0.7)
					(thickness 0.15)
				)
				(justify left bottom mirror)
			)
		)
		(pad "1" smd circle
			(at 0 0 270)
			(size 0.75 0.75)
			(layers "B.Cu" "B.Mask")
			(net 149 "/Peripherals/TPM_IRQ")
			(pinfunction "1")
			(pintype "passive")
		)
	)
	(footprint "antmicro-footprints:C_0603_1608Metric_EIA"
		(layer "B.Cu")
		(at 124.6 121.44 180)
		(descr "Capacitor SMD 0603, IPC-7351 Density Level A")
		(tags "Capacitor 0603")
		(property "Reference" "C74"
			(at -3.47 -0.415 0)
			(layer "B.SilkS")
			(effects
				(font
					(size 0.7 0.7)
					(thickness 0.15)
				)
				(justify left bottom mirror)
			)
		)
		(property "Value" "C_22u_16V_0603"
			(at -1.42757 -1.770288 0)
			(layer "B.Fab")
			(effects
				(font
					(size 0.7 0.7)
					(thickness 0.15)
				)
				(justify left bottom mirror)
			)
		)
		(property "Datasheet" "https://product.samsungsem.com/mlcc/CL10A226MO7JZN.do"
			(at 0 0 0)
			(layer "B.Fab")
			(hide yes)
			(effects
				(font
					(size 1.27 1.27)
					(thickness 0.15)
				)
				(justify mirror)
			)
		)
		(property "Description" "SMD Multilayer Ceramic Capacitor"
			(at 0 0 0)
			(layer "B.Fab")
			(hide yes)
			(effects
				(font
					(size 1.27 1.27)
					(thickness 0.15)
				)
				(justify mirror)
			)
		)
		(property "MPN" "CL10A226MO7JZNC"
			(at 0 0 180)
			(unlocked yes)
			(layer "B.Fab")
			(hide yes)
			(effects
				(font
					(size 1 1)
					(thickness 0.15)
				)
				(justify mirror)
			)
		)
		(property "Manufacturer" "Samsung Electro-Mechanics"
			(at 0 0 180)
			(unlocked yes)
			(layer "B.Fab")
			(hide yes)
			(effects
				(font
					(size 1 1)
					(thickness 0.15)
				)
				(justify mirror)
			)
		)
		(property "License" "Apache-2.0"
			(at 0 0 180)
			(unlocked yes)
			(layer "B.Fab")
			(hide yes)
			(effects
				(font
					(size 1 1)
					(thickness 0.15)
				)
				(justify mirror)
			)
		)
		(property "Author" "Antmicro"
			(at 0 0 180)
			(unlocked yes)
			(layer "B.Fab")
			(hide yes)
			(effects
				(font
					(size 1 1)
					(thickness 0.15)
				)
				(justify mirror)
			)
		)
		(property "Val" "22u"
			(at 0 0 180)
			(unlocked yes)
			(layer "B.Fab")
			(hide yes)
			(effects
				(font
					(size 1 1)
					(thickness 0.15)
				)
				(justify mirror)
			)
		)
		(property "Voltage" "16V"
			(at 0 0 180)
			(unlocked yes)
			(layer "B.Fab")
			(hide yes)
			(effects
				(font
					(size 1 1)
					(thickness 0.15)
				)
				(justify mirror)
			)
		)
		(property "Dielectric" ""
			(at 0 0 180)
			(unlocked yes)
			(layer "B.Fab")
			(hide yes)
			(effects
				(font
					(size 1 1)
					(thickness 0.15)
				)
				(justify mirror)
			)
		)
		(sheetname "/M.2/")
		(sheetfile "m2.kicad_sch")
		(attr smd)
		(fp_line
			(start -0.15 0.55)
			(end 0.15 0.55)
			(stroke
				(width 0.15)
				(type solid)
			)
			(layer "B.SilkS")
		)
		(fp_line
			(start -0.15 -0.55)
			(end 0.15 -0.55)
			(stroke
				(width 0.15)
				(type solid)
			)
			(layer "B.SilkS")
		)
		(fp_rect
			(start -1.25 0.65)
			(end 1.25 -0.65)
			(stroke
				(width 0.05)
				(type solid)
			)
			(fill no)
			(layer "B.CrtYd")
		)
		(fp_rect
			(start -0.8 0.45)
			(end 0.8 -0.45)
			(stroke
				(width 0.15)
				(type solid)
			)
			(fill no)
			(layer "B.Fab")
		)
		(fp_text user "${REFERENCE}"
			(at -1.682 -3.895 0)
			(layer "B.Fab")
			(effects
				(font
					(size 0.7 0.7)
					(thickness 0.15)
				)
				(justify left bottom mirror)
			)
		)
		(fp_text user "Author: Antmicro"
			(at -1.682 -4.894 0)
			(layer "B.Fab")
			(effects
				(font
					(size 0.7 0.7)
					(thickness 0.15)
				)
				(justify left bottom mirror)
			)
		)
		(fp_text user "License: Apache-2.0"
			(at -1.682 -5.895 0)
			(layer "B.Fab")
			(effects
				(font
					(size 0.7 0.7)
					(thickness 0.15)
				)
				(justify left bottom mirror)
			)
		)
		(pad "1" smd roundrect
			(at -0.7 0 180)
			(size 0.8 1.1)
			(layers "B.Cu" "B.Mask" "B.Paste")
			(roundrect_rratio 0.2)
			(net 1 "GND")
			(pintype "passive")
		)
		(pad "2" smd roundrect
			(at 0.7 0 180)
			(size 0.8 1.1)
			(layers "B.Cu" "B.Mask" "B.Paste")
			(roundrect_rratio 0.2)
			(net 2 "+3V3")
			(pintype "passive")
		)
	)
	(footprint "antmicro-footprints:TP_SMD_0.75mm"
		(layer "B.Cu")
		(at 124.5 104.5)
		(property "Reference" "TP36"
			(at 0.7 -0.47 0)
			(layer "B.SilkS")
			(effects
				(font
					(size 0.7 0.7)
					(thickness 0.15)
				)
				(justify right top mirror)
			)
		)
		(property "Value" "TP_0.75mm_SMD"
			(at 0 -1.2 0)
			(layer "B.Fab")
			(effects
				(font
					(size 0.7 0.7)
					(thickness 0.15)
				)
				(justify right top mirror)
			)
		)
		(property "Description" "SMT test point"
			(at 0 0 0)
			(layer "B.Fab")
			(hide yes)
			(effects
				(font
					(size 1.27 1.27)
					(thickness 0.15)
				)
				(justify mirror)
			)
		)
		(property "MPN" ""
			(at 0 0 180)
			(unlocked yes)
			(layer "B.Fab")
			(hide yes)
			(effects
				(font
					(size 1 1)
					(thickness 0.15)
				)
				(justify mirror)
			)
		)
		(property "Manufacturer" ""
			(at 0 0 180)
			(unlocked yes)
			(layer "B.Fab")
			(hide yes)
			(effects
				(font
					(size 1 1)
					(thickness 0.15)
				)
				(justify mirror)
			)
		)
		(property "Author" "Antmicro"
			(at 0 0 180)
			(unlocked yes)
			(layer "B.Fab")
			(hide yes)
			(effects
				(font
					(size 1 1)
					(thickness 0.15)
				)
				(justify mirror)
			)
		)
		(property "License" "Apache-2.0"
			(at 0 0 180)
			(unlocked yes)
			(layer "B.Fab")
			(hide yes)
			(effects
				(font
					(size 1 1)
					(thickness 0.15)
				)
				(justify mirror)
			)
		)
		(sheetname "/M.2/")
		(sheetfile "m2.kicad_sch")
		(attr exclude_from_pos_files exclude_from_bom)
		(fp_circle
			(center 0 0)
			(end 0.475 0)
			(stroke
				(width 0.05)
				(type default)
			)
			(fill no)
			(layer "B.CrtYd")
		)
		(fp_text user "${REFERENCE}"
			(at -0.4 -2.7 0)
			(layer "B.Fab")
			(effects
				(font
					(size 0.7 0.7)
					(thickness 0.15)
				)
				(justify right top mirror)
			)
		)
		(fp_text user "License: Apache-2.0"
			(at -0.4 -5.101 0)
			(layer "B.Fab")
			(effects
				(font
					(size 0.7 0.7)
					(thickness 0.15)
				)
				(justify right top mirror)
			)
		)
		(fp_text user "Author: Antmicro"
			(at -0.4 -3.901 0)
			(layer "B.Fab")
			(effects
				(font
					(size 0.7 0.7)
					(thickness 0.15)
				)
				(justify right top mirror)
			)
		)
		(pad "1" smd circle
			(at 0 0)
			(size 0.75 0.75)
			(layers "B.Cu" "B.Mask")
			(net 236 "/M.2/~{M2_M_ALERT}")
			(pinfunction "1")
			(pintype "passive")
		)
	)
	(footprint "antmicro-footprints:R_0402_1005Metric"
		(layer "B.Cu")
		(at 223.85 94.85)
		(descr "Resistor SMD 0402")
		(tags "resistor SMD 0402")
		(property "Reference" "R154"
			(at -1.45 1.555 0)
			(layer "B.SilkS")
			(effects
				(font
					(size 0.7 0.7)
					(thickness 0.15)
				)
				(justify right top mirror)
			)
		)
		(property "Value" "R_2M_0402"
			(at -1.011843 -1.772047 0)
			(layer "B.Fab")
			(effects
				(font
					(size 0.7 0.7)
					(thickness 0.15)
				)
				(justify right top mirror)
			)
		)
		(property "Datasheet" "https://www.mouser.com/datasheet/2/447/YAGEO_PYu_RC_Group_51_RoHS_L_12-3313492.pdf"
			(at 0 0 0)
			(layer "B.Fab")
			(hide yes)
			(effects
				(font
					(size 1.27 1.27)
					(thickness 0.15)
				)
				(justify mirror)
			)
		)
		(property "Description" "SMD Chip Resistor, 2 Mohm, ± 1%, 62.5 mW, 0402 [1005 Metric], Thick Film, General Purpose"
			(at 0 0 0)
			(layer "B.Fab")
			(hide yes)
			(effects
				(font
					(size 1.27 1.27)
					(thickness 0.15)
				)
				(justify mirror)
			)
		)
		(property "MPN" "RC0402FR-072ML"
			(at 0 0 180)
			(unlocked yes)
			(layer "B.Fab")
			(hide yes)
			(effects
				(font
					(size 1 1)
					(thickness 0.15)
				)
				(justify mirror)
			)
		)
		(property "Manufacturer" "YAGEO"
			(at 0 0 180)
			(unlocked yes)
			(layer "B.Fab")
			(hide yes)
			(effects
				(font
					(size 1 1)
					(thickness 0.15)
				)
				(justify mirror)
			)
		)
		(property "License" "Apache-2.0"
			(at 0 0 180)
			(unlocked yes)
			(layer "B.Fab")
			(hide yes)
			(effects
				(font
					(size 1 1)
					(thickness 0.15)
				)
				(justify mirror)
			)
		)
		(property "Author" "Antmicro"
			(at 0 0 180)
			(unlocked yes)
			(layer "B.Fab")
			(hide yes)
			(effects
				(font
					(size 1 1)
					(thickness 0.15)
				)
				(justify mirror)
			)
		)
		(property "Val" "2M"
			(at 0 0 180)
			(unlocked yes)
			(layer "B.Fab")
			(hide yes)
			(effects
				(font
					(size 1 1)
					(thickness 0.15)
				)
				(justify mirror)
			)
		)
		(property "Tolerance" "1%"
			(at 0 0 180)
			(unlocked yes)
			(layer "B.Fab")
			(hide yes)
			(effects
				(font
					(size 1 1)
					(thickness 0.15)
				)
				(justify mirror)
			)
		)
		(sheetname "/USB DP Alt mode/")
		(sheetfile "usb_dp.kicad_sch")
		(attr smd)
		(fp_rect
			(start -0.925 0.47)
			(end 0.925 -0.47)
			(stroke
				(width 0.05)
				(type default)
			)
			(fill no)
			(layer "B.CrtYd")
		)
		(fp_rect
			(start -0.5 0.25)
			(end 0.5 -0.25)
			(stroke
				(width 0.15)
				(type solid)
			)
			(fill no)
			(layer "B.Fab")
		)
		(fp_text user "${REFERENCE}"
			(at -0.95 -3.168 0)
			(layer "B.Fab")
			(effects
				(font
					(size 0.7 0.7)
					(thickness 0.15)
				)
				(justify right top mirror)
			)
		)
		(fp_text user "Author: Antmicro"
			(at -0.95 -4.169 0)
			(layer "B.Fab")
			(effects
				(font
					(size 0.7 0.7)
					(thickness 0.15)
				)
				(justify right top mirror)
			)
		)
		(fp_text user "License: Apache-2.0"
			(at -0.95 -5.169 0)
			(layer "B.Fab")
			(effects
				(font
					(size 0.7 0.7)
					(thickness 0.15)
				)
				(justify right top mirror)
			)
		)
		(pad "1" smd roundrect
			(at -0.48 0)
			(size 0.59 0.64)
			(layers "B.Cu" "B.Mask" "B.Paste")
			(roundrect_rratio 0.25)
			(net 821 "/USB DP Alt mode/USBC1_SBU_N")
			(pintype "passive")
		)
		(pad "2" smd roundrect
			(at 0.48 0)
			(size 0.59 0.64)
			(layers "B.Cu" "B.Mask" "B.Paste")
			(roundrect_rratio 0.25)
			(net 1 "GND")
			(pintype "passive")
		)
	)
	(footprint "antmicro-footprints:R_0402_1005Metric"
		(layer "B.Cu")
		(at 209.5 71.5 90)
		(descr "Resistor SMD 0402")
		(tags "resistor SMD 0402")
		(property "Reference" "R176"
			(at 0.89 -0.4 90)
			(layer "B.SilkS")
			(effects
				(font
					(size 0.7 0.7)
					(thickness 0.15)
				)
				(justify right top mirror)
			)
		)
		(property "Value" "R_10k_0402"
			(at -1.011843 -1.772046 90)
			(layer "B.Fab")
			(effects
				(font
					(size 0.7 0.7)
					(thickness 0.15)
				)
				(justify right top mirror)
			)
		)
		(property "Datasheet" "https://www.bourns.com/docs/product-datasheets/cr.pdf"
			(at 0 0 90)
			(layer "B.Fab")
			(hide yes)
			(effects
				(font
					(size 1.27 1.27)
					(thickness 0.15)
				)
				(justify mirror)
			)
		)
		(property "Description" "SMD Chip Resistor, 10 kohm, ± 1%, 62.5 mW, 0402 [1005 Metric], Thick Film, General Purpose"
			(at 0 0 90)
			(layer "B.Fab")
			(hide yes)
			(effects
				(font
					(size 1.27 1.27)
					(thickness 0.15)
				)
				(justify mirror)
			)
		)
		(property "Manufacturer" "Bourns"
			(at 0 0 270)
			(unlocked yes)
			(layer "B.Fab")
			(hide yes)
			(effects
				(font
					(size 1 1)
					(thickness 0.15)
				)
				(justify mirror)
			)
		)
		(property "MPN" "CR0402-FX-1002GLF"
			(at 0 0 270)
			(unlocked yes)
			(layer "B.Fab")
			(hide yes)
			(effects
				(font
					(size 1 1)
					(thickness 0.15)
				)
				(justify mirror)
			)
		)
		(property "Val" "10k"
			(at 0 0 270)
			(unlocked yes)
			(layer "B.Fab")
			(hide yes)
			(effects
				(font
					(size 1 1)
					(thickness 0.15)
				)
				(justify mirror)
			)
		)
		(property "License" "Apache-2.0"
			(at 0 0 270)
			(unlocked yes)
			(layer "B.Fab")
			(hide yes)
			(effects
				(font
					(size 1 1)
					(thickness 0.15)
				)
				(justify mirror)
			)
		)
		(property "Author" "Antmicro"
			(at 0 0 270)
			(unlocked yes)
			(layer "B.Fab")
			(hide yes)
			(effects
				(font
					(size 1 1)
					(thickness 0.15)
				)
				(justify mirror)
			)
		)
		(property "Tolerance" "1%"
			(at 0 0 270)
			(unlocked yes)
			(layer "B.Fab")
			(hide yes)
			(effects
				(font
					(size 1 1)
					(thickness 0.15)
				)
				(justify mirror)
			)
		)
		(sheetname "/CSI/")
		(sheetfile "csi.kicad_sch")
		(attr smd)
		(fp_poly
			(pts
				(xy -0.925 0.47) (xy -0.925 -0.47) (xy 0.925 -0.47) (xy 0.925 0.47)
			)
			(stroke
				(width 0.05)
				(type default)
			)
			(fill no)
			(layer "B.CrtYd")
		)
		(fp_poly
			(pts
				(xy -0.5 0.25) (xy -0.5 -0.25) (xy 0.5 -0.25) (xy 0.5 0.25)
			)
			(stroke
				(width 0.15)
				(type solid)
			)
			(fill no)
			(layer "B.Fab")
		)
		(fp_text user "Author: Antmicro"
			(at -0.95 -4.169 90)
			(layer "B.Fab")
			(effects
				(font
					(size 0.7 0.7)
					(thickness 0.15)
				)
				(justify right top mirror)
			)
		)
		(fp_text user "${REFERENCE}"
			(at -0.95 -3.168 90)
			(layer "B.Fab")
			(effects
				(font
					(size 0.7 0.7)
					(thickness 0.15)
				)
				(justify right top mirror)
			)
		)
		(fp_text user "License: Apache-2.0"
			(at -0.949999 -5.169 90)
			(layer "B.Fab")
			(effects
				(font
					(size 0.7 0.7)
					(thickness 0.15)
				)
				(justify right top mirror)
			)
		)
		(pad "1" smd roundrect
			(at -0.48 0 90)
			(size 0.59 0.64)
			(layers "B.Cu" "B.Mask" "B.Paste")
			(roundrect_rratio 0.25)
			(net 2 "+3V3")
			(pintype "passive")
		)
		(pad "2" smd roundrect
			(at 0.48 0 90)
			(size 0.59 0.64)
			(layers "B.Cu" "B.Mask" "B.Paste")
			(roundrect_rratio 0.25)
			(net 117 "/CSI/CAM_CTRL.CSIB_FLG")
			(pintype "passive")
		)
	)
	(footprint "antmicro-footprints:R_0402_1005Metric"
		(layer "B.Cu")
		(at 173 57.5 -90)
		(descr "Resistor SMD 0402")
		(tags "resistor SMD 0402")
		(property "Reference" "R35"
			(at -3.58 -0.415532 90)
			(layer "B.SilkS")
			(effects
				(font
					(size 0.7 0.7)
					(thickness 0.15)
				)
				(justify left bottom mirror)
			)
		)
		(property "Value" "R_470R_0402"
			(at -1.011843 -1.772047 90)
			(layer "B.Fab")
			(effects
				(font
					(size 0.7 0.7)
					(thickness 0.15)
				)
				(justify left bottom mirror)
			)
		)
		(property "Datasheet" "https://www.bourns.com/docs/product-datasheets/cr.pdf"
			(at 0 0 90)
			(layer "B.Fab")
			(hide yes)
			(effects
				(font
					(size 1.27 1.27)
					(thickness 0.15)
				)
				(justify mirror)
			)
		)
		(property "Description" "SMD Chip Resistor, 470 ohm, ± 1%, 62.5 mW, 0402 [1005 Metric], Thick Film, General Purpose"
			(at 0 0 90)
			(layer "B.Fab")
			(hide yes)
			(effects
				(font
					(size 1.27 1.27)
					(thickness 0.15)
				)
				(justify mirror)
			)
		)
		(property "MPN" "CR0402-FX-4700GLF"
			(at 0 0 90)
			(unlocked yes)
			(layer "B.Fab")
			(hide yes)
			(effects
				(font
					(size 1 1)
					(thickness 0.15)
				)
				(justify mirror)
			)
		)
		(property "Manufacturer" "Bourns"
			(at 0 0 90)
			(unlocked yes)
			(layer "B.Fab")
			(hide yes)
			(effects
				(font
					(size 1 1)
					(thickness 0.15)
				)
				(justify mirror)
			)
		)
		(property "License" "Apache-2.0"
			(at 0 0 90)
			(unlocked yes)
			(layer "B.Fab")
			(hide yes)
			(effects
				(font
					(size 1 1)
					(thickness 0.15)
				)
				(justify mirror)
			)
		)
		(property "Author" "Antmicro"
			(at 0 0 90)
			(unlocked yes)
			(layer "B.Fab")
			(hide yes)
			(effects
				(font
					(size 1 1)
					(thickness 0.15)
				)
				(justify mirror)
			)
		)
		(property "Val" "470R"
			(at 0 0 90)
			(unlocked yes)
			(layer "B.Fab")
			(hide yes)
			(effects
				(font
					(size 1 1)
					(thickness 0.15)
				)
				(justify mirror)
			)
		)
		(property "Tolerance" "1%"
			(at 0 0 90)
			(unlocked yes)
			(layer "B.Fab")
			(hide yes)
			(effects
				(font
					(size 1 1)
					(thickness 0.15)
				)
				(justify mirror)
			)
		)
		(sheetname "/Power/")
		(sheetfile "power.kicad_sch")
		(attr smd)
		(fp_rect
			(start -0.925 0.47)
			(end 0.925 -0.47)
			(stroke
				(width 0.05)
				(type default)
			)
			(fill no)
			(layer "B.CrtYd")
		)
		(fp_rect
			(start -0.5 0.25)
			(end 0.5 -0.25)
			(stroke
				(width 0.15)
				(type solid)
			)
			(fill no)
			(layer "B.Fab")
		)
		(fp_text user "License: Apache-2.0"
			(at -0.95 -5.169 90)
			(layer "B.Fab")
			(effects
				(font
					(size 0.7 0.7)
					(thickness 0.15)
				)
				(justify left bottom mirror)
			)
		)
		(fp_text user "Author: Antmicro"
			(at -0.95 -4.169 90)
			(layer "B.Fab")
			(effects
				(font
					(size 0.7 0.7)
					(thickness 0.15)
				)
				(justify left bottom mirror)
			)
		)
		(fp_text user "${REFERENCE}"
			(at -0.95 -3.168 90)
			(layer "B.Fab")
			(effects
				(font
					(size 0.7 0.7)
					(thickness 0.15)
				)
				(justify left bottom mirror)
			)
		)
		(pad "1" smd roundrect
			(at -0.48 0 270)
			(size 0.59 0.64)
			(layers "B.Cu" "B.Mask" "B.Paste")
			(roundrect_rratio 0.25)
			(net 1127 "Net-(D42-A)")
			(pintype "passive")
		)
		(pad "2" smd roundrect
			(at 0.48 0 270)
			(size 0.59 0.64)
			(layers "B.Cu" "B.Mask" "B.Paste")
			(roundrect_rratio 0.25)
			(net 491 "+5V_AON")
			(pintype "passive")
		)
	)
	(footprint "antmicro-footprints:TP_SMD_0.75mm"
		(layer "B.Cu")
		(at 92.2 72.9)
		(property "Reference" "TP102"
			(at 0.5 -0.4 0)
			(layer "B.SilkS")
			(effects
				(font
					(size 0.7 0.7)
					(thickness 0.15)
				)
				(justify right top mirror)
			)
		)
		(property "Value" "TP_0.75mm_SMD"
			(at 0 -1.2 0)
			(layer "B.Fab")
			(effects
				(font
					(size 0.7 0.7)
					(thickness 0.15)
				)
				(justify right top mirror)
			)
		)
		(property "Description" "SMT test point"
			(at 0 0 0)
			(layer "B.Fab")
			(hide yes)
			(effects
				(font
					(size 1.27 1.27)
					(thickness 0.15)
				)
				(justify mirror)
			)
		)
		(property "MPN" ""
			(at 0 0 180)
			(unlocked yes)
			(layer "B.Fab")
			(hide yes)
			(effects
				(font
					(size 1 1)
					(thickness 0.15)
				)
				(justify mirror)
			)
		)
		(property "Manufacturer" ""
			(at 0 0 180)
			(unlocked yes)
			(layer "B.Fab")
			(hide yes)
			(effects
				(font
					(size 1 1)
					(thickness 0.15)
				)
				(justify mirror)
			)
		)
		(property "Author" "Antmicro"
			(at 0 0 180)
			(unlocked yes)
			(layer "B.Fab")
			(hide yes)
			(effects
				(font
					(size 1 1)
					(thickness 0.15)
				)
				(justify mirror)
			)
		)
		(property "License" "Apache-2.0"
			(at 0 0 180)
			(unlocked yes)
			(layer "B.Fab")
			(hide yes)
			(effects
				(font
					(size 1 1)
					(thickness 0.15)
				)
				(justify mirror)
			)
		)
		(sheetname "/SoM_IO/")
		(sheetfile "som_io.kicad_sch")
		(attr exclude_from_pos_files exclude_from_bom)
		(fp_circle
			(center 0 0)
			(end 0.475 0)
			(stroke
				(width 0.05)
				(type default)
			)
			(fill no)
			(layer "B.CrtYd")
		)
		(fp_text user "Author: Antmicro"
			(at -0.4 -3.901 0)
			(layer "B.Fab")
			(effects
				(font
					(size 0.7 0.7)
					(thickness 0.15)
				)
				(justify right top mirror)
			)
		)
		(fp_text user "License: Apache-2.0"
			(at -0.4 -5.101 0)
			(layer "B.Fab")
			(effects
				(font
					(size 0.7 0.7)
					(thickness 0.15)
				)
				(justify right top mirror)
			)
		)
		(fp_text user "${REFERENCE}"
			(at -0.4 -2.7 0)
			(layer "B.Fab")
			(effects
				(font
					(size 0.7 0.7)
					(thickness 0.15)
				)
				(justify right top mirror)
			)
		)
		(pad "1" smd circle
			(at 0 0)
			(size 0.75 0.75)
			(layers "B.Cu" "B.Mask")
			(net 76 "/SoM_IO/I2S_{M.2}.SDIN")
			(pinfunction "1")
			(pintype "passive")
		)
	)
	(footprint "antmicro-footprints:TP_SMD_0.75mm"
		(layer "B.Cu")
		(at 90.1 67.8 -90)
		(property "Reference" "TP82"
			(at 0.4 -0.3 90)
			(layer "B.SilkS")
			(effects
				(font
					(size 0.7 0.7)
					(thickness 0.15)
				)
				(justify left bottom mirror)
			)
		)
		(property "Value" "TP_0.75mm_SMD"
			(at 0 -1.2 90)
			(layer "B.Fab")
			(effects
				(font
					(size 0.7 0.7)
					(thickness 0.15)
				)
				(justify left bottom mirror)
			)
		)
		(property "Description" "SMT test point"
			(at 0 0 90)
			(layer "B.Fab")
			(hide yes)
			(effects
				(font
					(size 1.27 1.27)
					(thickness 0.15)
				)
				(justify mirror)
			)
		)
		(property "MPN" ""
			(at 0 0 90)
			(unlocked yes)
			(layer "B.Fab")
			(hide yes)
			(effects
				(font
					(size 1 1)
					(thickness 0.15)
				)
				(justify mirror)
			)
		)
		(property "Manufacturer" ""
			(at 0 0 90)
			(unlocked yes)
			(layer "B.Fab")
			(hide yes)
			(effects
				(font
					(size 1 1)
					(thickness 0.15)
				)
				(justify mirror)
			)
		)
		(property "Author" "Antmicro"
			(at 0 0 90)
			(unlocked yes)
			(layer "B.Fab")
			(hide yes)
			(effects
				(font
					(size 1 1)
					(thickness 0.15)
				)
				(justify mirror)
			)
		)
		(property "License" "Apache-2.0"
			(at 0 0 90)
			(unlocked yes)
			(layer "B.Fab")
			(hide yes)
			(effects
				(font
					(size 1 1)
					(thickness 0.15)
				)
				(justify mirror)
			)
		)
		(sheetname "/SoM_Power/")
		(sheetfile "som_power.kicad_sch")
		(attr exclude_from_pos_files exclude_from_bom)
		(fp_circle
			(center 0 0)
			(end 0.475 0)
			(stroke
				(width 0.05)
				(type default)
			)
			(fill no)
			(layer "B.CrtYd")
		)
		(fp_text user "Author: Antmicro"
			(at -0.4 -3.901 90)
			(layer "B.Fab")
			(effects
				(font
					(size 0.7 0.7)
					(thickness 0.15)
				)
				(justify left bottom mirror)
			)
		)
		(fp_text user "License: Apache-2.0"
			(at -0.4 -5.101 90)
			(layer "B.Fab")
			(effects
				(font
					(size 0.7 0.7)
					(thickness 0.15)
				)
				(justify left bottom mirror)
			)
		)
		(fp_text user "${REFERENCE}"
			(at -0.4 -2.7 90)
			(layer "B.Fab")
			(effects
				(font
					(size 0.7 0.7)
					(thickness 0.15)
				)
				(justify left bottom mirror)
			)
		)
		(pad "1" smd circle
			(at 0 0 270)
			(size 0.75 0.75)
			(layers "B.Cu" "B.Mask")
			(net 605 "/SoM_Power/~{MODULE_SHDN}")
			(pinfunction "1")
			(pintype "passive")
		)
	)
	(footprint "antmicro-footprints:R_0402_1005Metric"
		(layer "B.Cu")
		(at 137.8 65.2 90)
		(descr "Resistor SMD 0402")
		(tags "resistor SMD 0402")
		(property "Reference" "R236"
			(at -3.7 -0.4 90)
			(layer "B.SilkS")
			(effects
				(font
					(size 0.7 0.7)
					(thickness 0.15)
				)
				(justify right top mirror)
			)
		)
		(property "Value" "R_100k_0402"
			(at -1.011843 -1.772046 90)
			(layer "B.Fab")
			(effects
				(font
					(size 0.7 0.7)
					(thickness 0.15)
				)
				(justify right top mirror)
			)
		)
		(property "Datasheet" "https://www.bourns.com/docs/product-datasheets/cr.pdf"
			(at 0 0 90)
			(layer "B.Fab")
			(hide yes)
			(effects
				(font
					(size 1.27 1.27)
					(thickness 0.15)
				)
				(justify mirror)
			)
		)
		(property "Description" "SMD Chip Resistor, 100 kohm, ± 1%, 62.5 mW, 0402 [1005 Metric], Thick Film, General Purpose"
			(at 0 0 90)
			(layer "B.Fab")
			(hide yes)
			(effects
				(font
					(size 1.27 1.27)
					(thickness 0.15)
				)
				(justify mirror)
			)
		)
		(property "Manufacturer" "Bourns"
			(at 0 0 270)
			(unlocked yes)
			(layer "B.Fab")
			(hide yes)
			(effects
				(font
					(size 1 1)
					(thickness 0.15)
				)
				(justify mirror)
			)
		)
		(property "MPN" "CR0402-FX-1003GLF"
			(at 0 0 270)
			(unlocked yes)
			(layer "B.Fab")
			(hide yes)
			(effects
				(font
					(size 1 1)
					(thickness 0.15)
				)
				(justify mirror)
			)
		)
		(property "Val" "100k"
			(at 0 0 270)
			(unlocked yes)
			(layer "B.Fab")
			(hide yes)
			(effects
				(font
					(size 1 1)
					(thickness 0.15)
				)
				(justify mirror)
			)
		)
		(property "License" "Apache-2.0"
			(at 0 0 270)
			(unlocked yes)
			(layer "B.Fab")
			(hide yes)
			(effects
				(font
					(size 1 1)
					(thickness 0.15)
				)
				(justify mirror)
			)
		)
		(property "Author" "Antmicro"
			(at 0 0 270)
			(unlocked yes)
			(layer "B.Fab")
			(hide yes)
			(effects
				(font
					(size 1 1)
					(thickness 0.15)
				)
				(justify mirror)
			)
		)
		(property "Tolerance" "1%"
			(at 0 0 270)
			(unlocked yes)
			(layer "B.Fab")
			(hide yes)
			(effects
				(font
					(size 1 1)
					(thickness 0.15)
				)
				(justify mirror)
			)
		)
		(sheetname "/Peripherals/")
		(sheetfile "peripherals.kicad_sch")
		(attr smd exclude_from_pos_files exclude_from_bom dnp)
		(fp_poly
			(pts
				(xy -0.925 0.47) (xy -0.925 -0.47) (xy 0.925 -0.47) (xy 0.925 0.47)
			)
			(stroke
				(width 0.05)
				(type default)
			)
			(fill no)
			(layer "B.CrtYd")
		)
		(fp_poly
			(pts
				(xy -0.5 0.25) (xy -0.5 -0.25) (xy 0.5 -0.25) (xy 0.5 0.25)
			)
			(stroke
				(width 0.15)
				(type solid)
			)
			(fill no)
			(layer "B.Fab")
		)
		(fp_text user "Author: Antmicro"
			(at -0.95 -4.169 90)
			(layer "B.Fab")
			(effects
				(font
					(size 0.7 0.7)
					(thickness 0.15)
				)
				(justify right top mirror)
			)
		)
		(fp_text user "License: Apache-2.0"
			(at -0.949999 -5.169 90)
			(layer "B.Fab")
			(effects
				(font
					(size 0.7 0.7)
					(thickness 0.15)
				)
				(justify right top mirror)
			)
		)
		(fp_text user "${REFERENCE}"
			(at -0.95 -3.168 90)
			(layer "B.Fab")
			(effects
				(font
					(size 0.7 0.7)
					(thickness 0.15)
				)
				(justify right top mirror)
			)
		)
		(pad "1" smd roundrect
			(at -0.48 0 90)
			(size 0.59 0.64)
			(layers "B.Cu" "B.Mask" "B.Paste")
			(roundrect_rratio 0.25)
			(net 1 "GND")
			(pintype "passive")
		)
		(pad "2" smd roundrect
			(at 0.48 0 90)
			(size 0.59 0.64)
			(layers "B.Cu" "B.Mask" "B.Paste")
			(roundrect_rratio 0.25)
			(net 90 "/Peripherals/I2C_CONN_PEN")
			(pintype "passive")
		)
	)
	(footprint "antmicro-footprints:SOT-563"
		(layer "B.Cu")
		(at 219.89 121.651698 90)
		(property "Reference" "Q29"
			(at -0.648302 1.21 90)
			(layer "B.SilkS")
			(effects
				(font
					(size 0.7 0.7)
					(thickness 0.15)
				)
				(justify right top mirror)
			)
		)
		(property "Value" "DMC2400UV-7"
			(at 0 -2 90)
			(layer "B.Fab")
			(effects
				(font
					(size 0.7 0.7)
					(thickness 0.15)
				)
				(justify right top mirror)
			)
		)
		(property "Datasheet" "https://www.mouser.com/datasheet/2/115/DIOD_S_A0010038249_1-2543538.pdf"
			(at 0 0 90)
			(layer "B.Fab")
			(hide yes)
			(effects
				(font
					(size 1.27 1.27)
					(thickness 0.15)
				)
				(justify mirror)
			)
		)
		(property "Description" "Dual MOSFET, Complementary N and P Channel, 20 V, 20 V, 1.03 A, 1.03 A, 0.3 ohm"
			(at 0 0 90)
			(layer "B.Fab")
			(hide yes)
			(effects
				(font
					(size 1.27 1.27)
					(thickness 0.15)
				)
				(justify mirror)
			)
		)
		(property "MPN" "DMC2400UV-7"
			(at 0 0 270)
			(unlocked yes)
			(layer "B.Fab")
			(hide yes)
			(effects
				(font
					(size 1 1)
					(thickness 0.15)
				)
				(justify mirror)
			)
		)
		(property "Manufacturer" "Diodes Incorporated"
			(at 0 0 270)
			(unlocked yes)
			(layer "B.Fab")
			(hide yes)
			(effects
				(font
					(size 1 1)
					(thickness 0.15)
				)
				(justify mirror)
			)
		)
		(property "Author" "Antmicro"
			(at 0 0 270)
			(unlocked yes)
			(layer "B.Fab")
			(hide yes)
			(effects
				(font
					(size 1 1)
					(thickness 0.15)
				)
				(justify mirror)
			)
		)
		(property "License" "Apache-2.0"
			(at 0 0 270)
			(unlocked yes)
			(layer "B.Fab")
			(hide yes)
			(effects
				(font
					(size 1 1)
					(thickness 0.15)
				)
				(justify mirror)
			)
		)
		(sheetname "/USB Hub/")
		(sheetfile "usb_hub.kicad_sch")
		(attr smd)
		(fp_line
			(start 0.776 -0.972)
			(end 0.526 -0.972)
			(stroke
				(width 0.15)
				(type solid)
			)
			(layer "B.SilkS")
		)
		(fp_line
			(start -0.778 -0.949)
			(end -0.424 -0.949)
			(stroke
				(width 0.15)
				(type solid)
			)
			(layer "B.SilkS")
		)
		(fp_line
			(start 0.776 -0.776)
			(end 0.776 -0.972)
			(stroke
				(width 0.15)
				(type solid)
			)
			(layer "B.SilkS")
		)
		(fp_line
			(start -0.778 -0.776)
			(end -0.778 -0.949)
			(stroke
				(width 0.15)
				(type solid)
			)
			(layer "B.SilkS")
		)
		(fp_line
			(start 0.776 0.974)
			(end 0.776 0.778)
			(stroke
				(width 0.15)
				(type solid)
			)
			(layer "B.SilkS")
		)
		(fp_line
			(start 0.776 0.974)
			(end 0.526 0.974)
			(stroke
				(width 0.15)
				(type solid)
			)
			(layer "B.SilkS")
		)
		(fp_line
			(start -0.499 0.974)
			(end -0.724 0.778)
			(stroke
				(width 0.15)
				(type solid)
			)
			(layer "B.SilkS")
		)
		(fp_circle
			(center -0.903 0.999)
			(end -0.952 0.95)
			(stroke
				(width 0.15)
				(type solid)
			)
			(fill yes)
			(layer "B.SilkS")
		)
		(fp_rect
			(start 1.19 1.12)
			(end -1.2 -1.1)
			(stroke
				(width 0.05)
				(type solid)
			)
			(fill no)
			(layer "B.CrtYd")
		)
		(fp_line
			(start 0.651 -0.847)
			(end -0.653 -0.847)
			(stroke
				(width 0.15)
				(type solid)
			)
			(layer "B.Fab")
		)
		(fp_line
			(start -0.653 0.678)
			(end -0.653 -0.847)
			(stroke
				(width 0.15)
				(type solid)
			)
			(layer "B.Fab")
		)
		(fp_line
			(start 0.651 0.849)
			(end 0.651 -0.847)
			(stroke
				(width 0.15)
				(type solid)
			)
			(layer "B.Fab")
		)
		(fp_line
			(start -0.453 0.849)
			(end -0.653 0.678)
			(stroke
				(width 0.15)
				(type solid)
			)
			(layer "B.Fab")
		)
		(fp_line
			(start -0.453 0.849)
			(end 0.651 0.849)
			(stroke
				(width 0.15)
				(type solid)
			)
			(layer "B.Fab")
		)
		(fp_text user "License: Apache-2.0"
			(at -1.299 -4.924 90)
			(layer "B.Fab")
			(effects
				(font
					(size 0.7 0.7)
					(thickness 0.15)
				)
				(justify right top mirror)
			)
		)
		(fp_text user "Author: Antmicro"
			(at -1.299 -6.124 90)
			(layer "B.Fab")
			(effects
				(font
					(size 0.7 0.7)
					(thickness 0.15)
				)
				(justify right top mirror)
			)
		)
		(fp_text user "${REFERENCE}"
			(at -1.299 -7.323 90)
			(layer "B.Fab")
			(effects
				(font
					(size 0.7 0.7)
					(thickness 0.15)
				)
				(justify right top mirror)
			)
		)
		(pad "1" smd roundrect
			(at -0.749 0.499 180)
			(size 0.3 0.6)
			(layers "B.Cu" "B.Mask" "B.Paste")
			(roundrect_rratio 0.25)
			(net 1 "GND")
			(pinfunction "S1")
			(pintype "passive")
		)
		(pad "2" smd roundrect
			(at -0.749 -0.001 180)
			(size 0.3 0.6)
			(layers "B.Cu" "B.Mask" "B.Paste")
			(roundrect_rratio 0.25)
			(net 1095 "/USB Hub/DP1_VCONN2")
			(pinfunction "G1")
			(pintype "input")
		)
		(pad "3" smd roundrect
			(at -0.749 -0.497 180)
			(size 0.3 0.6)
			(layers "B.Cu" "B.Mask" "B.Paste")
			(roundrect_rratio 0.25)
			(net 1240 "Net-(D60-A)")
			(pinfunction "D2")
			(pintype "passive")
		)
		(pad "4" smd roundrect
			(at 0.747 -0.497 180)
			(size 0.3 0.6)
			(layers "B.Cu" "B.Mask" "B.Paste")
			(roundrect_rratio 0.25)
			(net 5 "+5V")
			(pinfunction "S2")
			(pintype "passive")
		)
		(pad "5" smd roundrect
			(at 0.747 -0.001 180)
			(size 0.3 0.6)
			(layers "B.Cu" "B.Mask" "B.Paste")
			(roundrect_rratio 0.25)
			(net 1333 "Net-(Q29-D1)")
			(pinfunction "G2")
			(pintype "input")
		)
		(pad "6" smd roundrect
			(at 0.747 0.499 180)
			(size 0.3 0.6)
			(layers "B.Cu" "B.Mask" "B.Paste")
			(roundrect_rratio 0.25)
			(net 1333 "Net-(Q29-D1)")
			(pinfunction "D1")
			(pintype "passive")
		)
	)
	(footprint "antmicro-footprints:Conn_Plug_Samtec_UMPT_1x6_UMPT-06-02.5-L-V-S-W-TR"
		(layer "B.Cu")
		(at 93.930532 134.21 -90)
		(property "Reference" "J8"
			(at -10.32 4.75 90)
			(layer "B.SilkS")
			(effects
				(font
					(size 0.7 0.7)
					(thickness 0.15)
				)
				(justify left bottom mirror)
			)
		)
		(property "Value" "Plug_Samtec_UMPT_1x6_UMPT-06-02.5-L-V-S-W-TR"
			(at -10.32 -5.3 90)
			(layer "B.Fab")
			(effects
				(font
					(size 0.7 0.7)
					(thickness 0.15)
				)
				(justify left bottom mirror)
			)
		)
		(property "Datasheet" "https://suddendocs.samtec.com/catalog_english/umpt.pdf"
			(at 0 0 90)
			(layer "B.Fab")
			(effects
				(font
					(size 0.7 0.7)
					(thickness 0.15)
				)
				(justify right top mirror)
			)
		)
		(property "Description" "2.00 mm mPOWER® Ultra Micro Power Terminal, Vertical"
			(at 0 0 90)
			(layer "B.Fab")
			(effects
				(font
					(size 0.7 0.7)
					(thickness 0.15)
				)
				(justify right top mirror)
			)
		)
		(property "MPN" "UMPT-06-02.5-L-V-S-W-TR"
			(at 0 0 270)
			(unlocked yes)
			(layer "B.Fab")
			(hide yes)
			(effects
				(font
					(size 1 1)
					(thickness 0.15)
				)
				(justify mirror)
			)
		)
		(property "Manufacturer" "Samtec"
			(at 0 0 270)
			(unlocked yes)
			(layer "B.Fab")
			(hide yes)
			(effects
				(font
					(size 1 1)
					(thickness 0.15)
				)
				(justify mirror)
			)
		)
		(property "Author" "Antmicro"
			(at 0 0 270)
			(unlocked yes)
			(layer "B.Fab")
			(hide yes)
			(effects
				(font
					(size 1 1)
					(thickness 0.15)
				)
				(justify mirror)
			)
		)
		(property "License" "Apache-2.0"
			(at 0 0 270)
			(unlocked yes)
			(layer "B.Fab")
			(hide yes)
			(effects
				(font
					(size 1 1)
					(thickness 0.15)
				)
				(justify mirror)
			)
		)
		(sheetname "/Expansion connector/")
		(sheetfile "expansion_connector.kicad_sch")
		(attr smd)
		(fp_line
			(start -9.05 3.8)
			(end -9.65 3.2)
			(stroke
				(width 0.15)
				(type solid)
			)
			(layer "B.SilkS")
		)
		(fp_line
			(start 9.65 3.8)
			(end -9.05 3.8)
			(stroke
				(width 0.15)
				(type solid)
			)
			(layer "B.SilkS")
		)
		(fp_line
			(start 9.65 3.8)
			(end 9.65 3.53)
			(stroke
				(width 0.15)
				(type solid)
			)
			(layer "B.SilkS")
		)
		(fp_line
			(start -9.65 3.2)
			(end -9.65 3.03)
			(stroke
				(width 0.15)
				(type solid)
			)
			(layer "B.SilkS")
		)
		(fp_line
			(start 9.65 -2.13)
			(end 9.65 -3.8)
			(stroke
				(width 0.15)
				(type solid)
			)
			(layer "B.SilkS")
		)
		(fp_line
			(start -9.65 -2.63)
			(end -9.65 -3.8)
			(stroke
				(width 0.15)
				(type solid)
			)
			(layer "B.SilkS")
		)
		(fp_line
			(start 9.65 -3.8)
			(end -9.65 -3.8)
			(stroke
				(width 0.15)
				(type solid)
			)
			(layer "B.SilkS")
		)
		(fp_circle
			(center -5 4.04)
			(end -4.95 4.04)
			(stroke
				(width 0.15)
				(type solid)
			)
			(fill yes)
			(layer "B.SilkS")
		)
		(fp_rect
			(start -10.05 4.2)
			(end 10.05 -4.2)
			(stroke
				(width 0.05)
				(type solid)
			)
			(fill no)
			(layer "B.CrtYd")
		)
		(fp_line
			(start -9.05 3.8)
			(end -9.65 3.2)
			(stroke
				(width 0.15)
				(type solid)
			)
			(layer "B.Fab")
		)
		(fp_line
			(start 9.65 3.8)
			(end -9.05 3.8)
			(stroke
				(width 0.15)
				(type solid)
			)
			(layer "B.Fab")
		)
		(fp_line
			(start -9.65 3.2)
			(end -9.65 -3.8)
			(stroke
				(width 0.15)
				(type solid)
			)
			(layer "B.Fab")
		)
		(fp_line
			(start -9.65 -3.8)
			(end 9.65 -3.8)
			(stroke
				(width 0.15)
				(type solid)
			)
			(layer "B.Fab")
		)
		(fp_line
			(start 9.65 -3.8)
			(end 9.65 3.8)
			(stroke
				(width 0.15)
				(type solid)
			)
			(layer "B.Fab")
		)
		(fp_text user "${REFERENCE}"
			(at -10.32 -8.9 90)
			(layer "B.Fab")
			(effects
				(font
					(size 0.7 0.7)
					(thickness 0.15)
				)
				(justify left bottom mirror)
			)
		)
		(fp_text user "Author: Antmicro"
			(at -10.32 -7.7 90)
			(layer "B.Fab")
			(effects
				(font
					(size 0.7 0.7)
					(thickness 0.15)
				)
				(justify left bottom mirror)
			)
		)
		(fp_text user "License: Apache-2.0"
			(at -10.32 -6.5 90)
			(layer "B.Fab")
			(effects
				(font
					(size 0.7 0.7)
					(thickness 0.15)
				)
				(justify left bottom mirror)
			)
		)
		(pad "1" smd rect
			(at -5 0 90)
			(size 1.25 3.5)
			(layers "B.Cu" "B.Mask" "B.Paste")
			(net 297 "/Expansion connector/+3V3_FMC")
			(pintype "passive")
			(solder_mask_margin 0.102)
		)
		(pad "2" smd rect
			(at -3 0 90)
			(size 1.25 3.5)
			(layers "B.Cu" "B.Mask" "B.Paste")
			(net 307 "/Expansion connector/+5V_FMC")
			(pintype "passive")
			(solder_mask_margin 0.102)
		)
		(pad "3" smd rect
			(at -1 0 90)
			(size 1.25 3.5)
			(layers "B.Cu" "B.Mask" "B.Paste")
			(net 156 "/Expansion connector/+VCC_FMC")
			(pintype "passive")
			(solder_mask_margin 0.102)
		)
		(pad "4" smd rect
			(at 1 0 90)
			(size 1.25 3.5)
			(layers "B.Cu" "B.Mask" "B.Paste")
			(net 156 "/Expansion connector/+VCC_FMC")
			(pintype "passive")
			(solder_mask_margin 0.102)
		)
		(pad "5" smd rect
			(at 3 0 90)
			(size 1.25 3.5)
			(layers "B.Cu" "B.Mask" "B.Paste")
			(net 1 "GND")
			(pintype "passive")
			(solder_mask_margin 0.102)
		)
		(pad "6" smd rect
			(at 5 0 90)
			(size 1.25 3.5)
			(layers "B.Cu" "B.Mask" "B.Paste")
			(net 1 "GND")
			(pintype "passive")
			(solder_mask_margin 0.102)
		)
		(pad "MP1" thru_hole circle
			(at 8.85 -0.3 90)
			(size 1.308 1.308)
			(drill 0.8)
			(layers "*.Cu" "*.Mask")
			(remove_unused_layers no)
			(net 1 "GND")
			(pintype "passive")
			(solder_mask_margin 0.102)
		)
		(pad "MP1" thru_hole circle
			(at 8.85 1.7 90)
			(size 1.308 1.308)
			(drill 0.8)
			(layers "*.Cu" "*.Mask")
			(remove_unused_layers no)
			(net 1 "GND")
			(pintype "passive")
			(solder_mask_margin 0.102)
		)
		(pad "MP2" thru_hole circle
			(at -8.85 -0.8 90)
			(size 1.308 1.308)
			(drill 0.8)
			(layers "*.Cu" "*.Mask")
			(remove_unused_layers no)
			(net 1 "GND")
			(pintype "passive")
			(solder_mask_margin 0.102)
		)
		(pad "MP2" thru_hole circle
			(at -8.85 1.2 90)
			(size 1.308 1.308)
			(drill 0.8)
			(layers "*.Cu" "*.Mask")
			(remove_unused_layers no)
			(net 1 "GND")
			(pintype "passive")
			(solder_mask_margin 0.102)
		)
	)
	(footprint "antmicro-footprints:C_0402_1005Metric"
		(layer "B.Cu")
		(at 230.426 152.025)
		(descr "Capacitor SMD 0402")
		(tags "capacitor SMD 0402")
		(property "Reference" "C179"
			(at -1.56 -1.54 0)
			(layer "B.SilkS")
			(effects
				(font
					(size 0.7 0.7)
					(thickness 0.15)
				)
				(justify right top mirror)
			)
		)
		(property "Value" "C_100n_0402"
			(at -1.022927 -2.155213 0)
			(layer "B.Fab")
			(effects
				(font
					(size 0.7 0.7)
					(thickness 0.15)
				)
				(justify right top mirror)
			)
		)
		(property "Datasheet" "https://www.murata.com/products/productdetail?partno=GRM155R61H104KE14%23"
			(at 0 0 0)
			(layer "B.Fab")
			(hide yes)
			(effects
				(font
					(size 1.27 1.27)
					(thickness 0.15)
				)
				(justify mirror)
			)
		)
		(property "Description" "SMD Multilayer Ceramic Capacitor, 0.1 µF, 50 V, 0402 [1005 Metric], ± 10%, X5R, GRM Series"
			(at 0 0 0)
			(layer "B.Fab")
			(hide yes)
			(effects
				(font
					(size 1.27 1.27)
					(thickness 0.15)
				)
				(justify mirror)
			)
		)
		(property "MPN" "GRM155R61H104KE14D"
			(at 0 0 180)
			(unlocked yes)
			(layer "B.Fab")
			(hide yes)
			(effects
				(font
					(size 1 1)
					(thickness 0.15)
				)
				(justify mirror)
			)
		)
		(property "Manufacturer" "Murata"
			(at 0 0 180)
			(unlocked yes)
			(layer "B.Fab")
			(hide yes)
			(effects
				(font
					(size 1 1)
					(thickness 0.15)
				)
				(justify mirror)
			)
		)
		(property "License" "Apache-2.0"
			(at 0 0 180)
			(unlocked yes)
			(layer "B.Fab")
			(hide yes)
			(effects
				(font
					(size 1 1)
					(thickness 0.15)
				)
				(justify mirror)
			)
		)
		(property "Author" "Antmicro"
			(at 0 0 180)
			(unlocked yes)
			(layer "B.Fab")
			(hide yes)
			(effects
				(font
					(size 1 1)
					(thickness 0.15)
				)
				(justify mirror)
			)
		)
		(property "Val" "100n"
			(at 0 0 180)
			(unlocked yes)
			(layer "B.Fab")
			(hide yes)
			(effects
				(font
					(size 1 1)
					(thickness 0.15)
				)
				(justify mirror)
			)
		)
		(property "Voltage" "50V"
			(at 0 0 180)
			(unlocked yes)
			(layer "B.Fab")
			(hide yes)
			(effects
				(font
					(size 1 1)
					(thickness 0.15)
				)
				(justify mirror)
			)
		)
		(property "Dielectric" "X5R"
			(at 0 0 180)
			(unlocked yes)
			(layer "B.Fab")
			(hide yes)
			(effects
				(font
					(size 1 1)
					(thickness 0.15)
				)
				(justify mirror)
			)
		)
		(sheetname "/SFP/")
		(sheetfile "sfp.kicad_sch")
		(attr smd)
		(fp_rect
			(start -0.925 0.47)
			(end 0.925 -0.47)
			(stroke
				(width 0.05)
				(type default)
			)
			(fill no)
			(layer "B.CrtYd")
		)
		(fp_line
			(start -0.494 -0.248)
			(end -0.494 0.25)
			(stroke
				(width 0.15)
				(type solid)
			)
			(layer "B.Fab")
		)
		(fp_line
			(start -0.494 0.25)
			(end 0.504 0.25)
			(stroke
				(width 0.15)
				(type solid)
			)
			(layer "B.Fab")
		)
		(fp_line
			(start 0.504 -0.248)
			(end -0.494 -0.248)
			(stroke
				(width 0.15)
				(type solid)
			)
			(layer "B.Fab")
		)
		(fp_line
			(start 0.504 0.25)
			(end 0.504 -0.248)
			(stroke
				(width 0.15)
				(type solid)
			)
			(layer "B.Fab")
		)
		(fp_text user "Author: Antmicro"
			(at -0.939 -3.399 0)
			(layer "B.Fab")
			(effects
				(font
					(size 0.7 0.7)
					(thickness 0.15)
				)
				(justify right top mirror)
			)
		)
		(fp_text user "License: Apache-2.0"
			(at -0.939 -5.799 0)
			(layer "B.Fab")
			(effects
				(font
					(size 0.7 0.7)
					(thickness 0.15)
				)
				(justify right top mirror)
			)
		)
		(fp_text user "${REFERENCE}"
			(at -0.939 -4.599 0)
			(layer "B.Fab")
			(effects
				(font
					(size 0.7 0.7)
					(thickness 0.15)
				)
				(justify right top mirror)
			)
		)
		(pad "1" smd roundrect
			(at -0.48 0)
			(size 0.59 0.64)
			(layers "B.Cu" "B.Mask" "B.Paste")
			(roundrect_rratio 0.25)
			(net 1 "GND")
			(pintype "passive")
		)
		(pad "2" smd roundrect
			(at 0.48 0)
			(size 0.59 0.64)
			(layers "B.Cu" "B.Mask" "B.Paste")
			(roundrect_rratio 0.25)
			(net 379 "/SFP/SH")
			(pintype "passive")
		)
	)
	(footprint "antmicro-footprints:TP_SMD_0.75mm"
		(layer "B.Cu")
		(at 142.680532 74.41 90)
		(property "Reference" "TP55"
			(at 0.39 0.719468 0)
			(layer "B.SilkS")
			(effects
				(font
					(size 0.7 0.7)
					(thickness 0.15)
				)
				(justify right top mirror)
			)
		)
		(property "Value" "TP_0.75mm_SMD"
			(at 0 -1.2 90)
			(layer "B.Fab")
			(effects
				(font
					(size 0.7 0.7)
					(thickness 0.15)
				)
				(justify right top mirror)
			)
		)
		(property "Description" "SMT test point"
			(at 0 0 90)
			(layer "B.Fab")
			(hide yes)
			(effects
				(font
					(size 1.27 1.27)
					(thickness 0.15)
				)
				(justify mirror)
			)
		)
		(property "MPN" ""
			(at 0 0 270)
			(unlocked yes)
			(layer "B.Fab")
			(hide yes)
			(effects
				(font
					(size 1 1)
					(thickness 0.15)
				)
				(justify mirror)
			)
		)
		(property "Manufacturer" ""
			(at 0 0 270)
			(unlocked yes)
			(layer "B.Fab")
			(hide yes)
			(effects
				(font
					(size 1 1)
					(thickness 0.15)
				)
				(justify mirror)
			)
		)
		(property "Author" "Antmicro"
			(at 0 0 270)
			(unlocked yes)
			(layer "B.Fab")
			(hide yes)
			(effects
				(font
					(size 1 1)
					(thickness 0.15)
				)
				(justify mirror)
			)
		)
		(property "License" "Apache-2.0"
			(at 0 0 270)
			(unlocked yes)
			(layer "B.Fab")
			(hide yes)
			(effects
				(font
					(size 1 1)
					(thickness 0.15)
				)
				(justify mirror)
			)
		)
		(sheetname "/SoM_Power/")
		(sheetfile "som_power.kicad_sch")
		(attr exclude_from_pos_files exclude_from_bom)
		(fp_circle
			(center 0 0)
			(end 0.475 0)
			(stroke
				(width 0.05)
				(type default)
			)
			(fill no)
			(layer "B.CrtYd")
		)
		(fp_text user "Author: Antmicro"
			(at -0.4 -3.901 90)
			(layer "B.Fab")
			(effects
				(font
					(size 0.7 0.7)
					(thickness 0.15)
				)
				(justify right top mirror)
			)
		)
		(fp_text user "License: Apache-2.0"
			(at -0.4 -5.101 90)
			(layer "B.Fab")
			(effects
				(font
					(size 0.7 0.7)
					(thickness 0.15)
				)
				(justify right top mirror)
			)
		)
		(fp_text user "${REFERENCE}"
			(at -0.4 -2.7 90)
			(layer "B.Fab")
			(effects
				(font
					(size 0.7 0.7)
					(thickness 0.15)
				)
				(justify right top mirror)
			)
		)
		(pad "1" smd circle
			(at 0 0 90)
			(size 0.75 0.75)
			(layers "B.Cu" "B.Mask")
			(net 609 "/SoM_Power/~{MOD_SLEEP}")
			(pinfunction "1")
			(pintype "passive")
		)
	)
	(footprint "antmicro-footprints:R_0402_1005Metric"
		(layer "B.Cu")
		(at 223.5 54.75 180)
		(descr "Resistor SMD 0402")
		(tags "resistor SMD 0402")
		(property "Reference" "R177"
			(at -3 -3.15 0)
			(layer "B.SilkS")
			(effects
				(font
					(size 0.7 0.7)
					(thickness 0.15)
				)
				(justify left bottom mirror)
			)
		)
		(property "Value" "R_200R_0402"
			(at -1.011843 -1.772046 0)
			(layer "B.Fab")
			(effects
				(font
					(size 0.7 0.7)
					(thickness 0.15)
				)
				(justify left bottom mirror)
			)
		)
		(property "Datasheet" "https://www.bourns.com/docs/product-datasheets/cr.pdf"
			(at 0 0 0)
			(layer "B.Fab")
			(hide yes)
			(effects
				(font
					(size 1.27 1.27)
					(thickness 0.15)
				)
				(justify mirror)
			)
		)
		(property "Description" "SMD Chip Resistor, 200 ohm, ± 1%, 62.5 mW, 0402 [1005 Metric], Thick Film, General Purpose"
			(at 0 0 0)
			(layer "B.Fab")
			(hide yes)
			(effects
				(font
					(size 1.27 1.27)
					(thickness 0.15)
				)
				(justify mirror)
			)
		)
		(property "Manufacturer" "Bourns"
			(at 0 0 0)
			(unlocked yes)
			(layer "B.Fab")
			(hide yes)
			(effects
				(font
					(size 1 1)
					(thickness 0.15)
				)
				(justify mirror)
			)
		)
		(property "MPN" "CR0402-FX-2000GLF"
			(at 0 0 0)
			(unlocked yes)
			(layer "B.Fab")
			(hide yes)
			(effects
				(font
					(size 1 1)
					(thickness 0.15)
				)
				(justify mirror)
			)
		)
		(property "Val" "200R"
			(at 0 0 0)
			(unlocked yes)
			(layer "B.Fab")
			(hide yes)
			(effects
				(font
					(size 1 1)
					(thickness 0.15)
				)
				(justify mirror)
			)
		)
		(property "License" "Apache-2.0"
			(at 0 0 0)
			(unlocked yes)
			(layer "B.Fab")
			(hide yes)
			(effects
				(font
					(size 1 1)
					(thickness 0.15)
				)
				(justify mirror)
			)
		)
		(property "Author" "Antmicro"
			(at 0 0 0)
			(unlocked yes)
			(layer "B.Fab")
			(hide yes)
			(effects
				(font
					(size 1 1)
					(thickness 0.15)
				)
				(justify mirror)
			)
		)
		(property "Tolerance" "1%"
			(at 0 0 0)
			(unlocked yes)
			(layer "B.Fab")
			(hide yes)
			(effects
				(font
					(size 1 1)
					(thickness 0.15)
				)
				(justify mirror)
			)
		)
		(sheetname "/CSI/")
		(sheetfile "csi.kicad_sch")
		(attr smd)
		(fp_poly
			(pts
				(xy -0.925 0.47) (xy -0.925 -0.47) (xy 0.925 -0.47) (xy 0.925 0.47)
			)
			(stroke
				(width 0.05)
				(type default)
			)
			(fill no)
			(layer "B.CrtYd")
		)
		(fp_poly
			(pts
				(xy -0.5 0.25) (xy -0.5 -0.25) (xy 0.5 -0.25) (xy 0.5 0.25)
			)
			(stroke
				(width 0.15)
				(type solid)
			)
			(fill no)
			(layer "B.Fab")
		)
		(fp_text user "License: Apache-2.0"
			(at -0.949999 -5.169 0)
			(layer "B.Fab")
			(effects
				(font
					(size 0.7 0.7)
					(thickness 0.15)
				)
				(justify left bottom mirror)
			)
		)
		(fp_text user "${REFERENCE}"
			(at -0.95 -3.168 0)
			(layer "B.Fab")
			(effects
				(font
					(size 0.7 0.7)
					(thickness 0.15)
				)
				(justify left bottom mirror)
			)
		)
		(fp_text user "Author: Antmicro"
			(at -0.95 -4.169 0)
			(layer "B.Fab")
			(effects
				(font
					(size 0.7 0.7)
					(thickness 0.15)
				)
				(justify left bottom mirror)
			)
		)
		(pad "1" smd roundrect
			(at -0.48 0 180)
			(size 0.59 0.64)
			(layers "B.Cu" "B.Mask" "B.Paste")
			(roundrect_rratio 0.25)
			(net 539 "Net-(D26-A)")
			(pintype "passive")
		)
		(pad "2" smd roundrect
			(at 0.48 0 180)
			(size 0.59 0.64)
			(layers "B.Cu" "B.Mask" "B.Paste")
			(roundrect_rratio 0.25)
			(net 8 "/CSI/CSIB_3V3")
			(pintype "passive")
		)
	)
	(footprint "antmicro-footprints:TP_SMD_0.75mm"
		(layer "B.Cu")
		(at 190.4 80.6815)
		(property "Reference" "TP16"
			(at -0.4 -0.5315 90)
			(layer "B.SilkS")
			(effects
				(font
					(size 0.7 0.7)
					(thickness 0.15)
				)
				(justify right top mirror)
			)
		)
		(property "Value" "TP_0.75mm_SMD"
			(at 0 -1.2 180)
			(layer "B.Fab")
			(effects
				(font
					(size 0.7 0.7)
					(thickness 0.15)
				)
				(justify left bottom mirror)
			)
		)
		(property "Description" "SMT test point"
			(at 0 0 180)
			(layer "B.Fab")
			(hide yes)
			(effects
				(font
					(size 1.27 1.27)
					(thickness 0.15)
				)
				(justify mirror)
			)
		)
		(property "MPN" ""
			(at 0 0 180)
			(unlocked yes)
			(layer "B.Fab")
			(hide yes)
			(effects
				(font
					(size 1 1)
					(thickness 0.15)
				)
				(justify mirror)
			)
		)
		(property "Manufacturer" ""
			(at 0 0 180)
			(unlocked yes)
			(layer "B.Fab")
			(hide yes)
			(effects
				(font
					(size 1 1)
					(thickness 0.15)
				)
				(justify mirror)
			)
		)
		(property "Author" "Antmicro"
			(at 0 0 180)
			(unlocked yes)
			(layer "B.Fab")
			(hide yes)
			(effects
				(font
					(size 1 1)
					(thickness 0.15)
				)
				(justify mirror)
			)
		)
		(property "License" "Apache-2.0"
			(at 0 0 180)
			(unlocked yes)
			(layer "B.Fab")
			(hide yes)
			(effects
				(font
					(size 1 1)
					(thickness 0.15)
				)
				(justify mirror)
			)
		)
		(sheetname "/USB Debug, PD/")
		(sheetfile "usb_debug_pd.kicad_sch")
		(attr exclude_from_pos_files exclude_from_bom)
		(fp_circle
			(center 0 0)
			(end 0.475 0)
			(stroke
				(width 0.05)
				(type default)
			)
			(fill no)
			(layer "B.CrtYd")
		)
		(fp_text user "${REFERENCE}"
			(at -0.4 -2.7 180)
			(layer "B.Fab")
			(effects
				(font
					(size 0.7 0.7)
					(thickness 0.15)
				)
				(justify left bottom mirror)
			)
		)
		(fp_text user "License: Apache-2.0"
			(at -0.4 -5.101 180)
			(layer "B.Fab")
			(effects
				(font
					(size 0.7 0.7)
					(thickness 0.15)
				)
				(justify left bottom mirror)
			)
		)
		(fp_text user "Author: Antmicro"
			(at -0.4 -3.901 180)
			(layer "B.Fab")
			(effects
				(font
					(size 0.7 0.7)
					(thickness 0.15)
				)
				(justify left bottom mirror)
			)
		)
		(pad "1" smd circle
			(at 0 0)
			(size 0.75 0.75)
			(layers "B.Cu" "B.Mask")
			(net 1168 "Net-(U30A-HPD1)")
			(pinfunction "1")
			(pintype "passive")
		)
	)
	(footprint "antmicro-footprints:USON-10_2.5x1mm_P0.5mm"
		(layer "B.Cu")
		(at 139.2 60.89 90)
		(descr "USON-10 2.5x1mm_ Pitch 0.5mm")
		(tags "USON-10 2.5x1mm Pitch 0.5mm")
		(property "Reference" "U67"
			(at -1.03 -1 0)
			(layer "B.SilkS")
			(effects
				(font
					(size 0.7 0.7)
					(thickness 0.15)
				)
				(justify right top mirror)
			)
		)
		(property "Value" "TPD4E05U06QDQARQ1"
			(at 0.018 -2.499 90)
			(layer "B.Fab")
			(effects
				(font
					(size 0.7 0.7)
					(thickness 0.15)
				)
				(justify right top mirror)
			)
		)
		(property "Datasheet" "https://www.ti.com/lit/ds/symlink/tpd4e05u06-q1.pdf?HQS=dis-mous-null-mousermode-dsf-pf-null-wwe&ts=1663591265741&ref_url=https%253A%252F%252Fwww.mouser.com%252F"
			(at 0 0 90)
			(layer "B.Fab")
			(hide yes)
			(effects
				(font
					(size 1.27 1.27)
					(thickness 0.15)
				)
				(justify mirror)
			)
		)
		(property "Description" "TVS diode array, 12 kV, USON-10, 5.5 V, 0.5 pF"
			(at 0 0 90)
			(layer "B.Fab")
			(hide yes)
			(effects
				(font
					(size 1.27 1.27)
					(thickness 0.15)
				)
				(justify mirror)
			)
		)
		(property "Manufacturer" "Texas Instruments"
			(at 0 0 270)
			(unlocked yes)
			(layer "B.Fab")
			(hide yes)
			(effects
				(font
					(size 1 1)
					(thickness 0.15)
				)
				(justify mirror)
			)
		)
		(property "MPN" "TPD4E05U06QDQARQ1"
			(at 0 0 270)
			(unlocked yes)
			(layer "B.Fab")
			(hide yes)
			(effects
				(font
					(size 1 1)
					(thickness 0.15)
				)
				(justify mirror)
			)
		)
		(property "Author" "Antmicro"
			(at 0 0 270)
			(unlocked yes)
			(layer "B.Fab")
			(hide yes)
			(effects
				(font
					(size 1 1)
					(thickness 0.15)
				)
				(justify mirror)
			)
		)
		(property "License" "Apache-2.0"
			(at 0 0 270)
			(unlocked yes)
			(layer "B.Fab")
			(hide yes)
			(effects
				(font
					(size 1 1)
					(thickness 0.15)
				)
				(justify mirror)
			)
		)
		(sheetname "/Peripherals/")
		(sheetfile "peripherals.kicad_sch")
		(attr smd)
		(fp_line
			(start 0.498 -1.398)
			(end -0.5 -1.398)
			(stroke
				(width 0.15)
				(type solid)
			)
			(layer "B.SilkS")
		)
		(fp_line
			(start 0.498 1.401)
			(end -0.5 1.401)
			(stroke
				(width 0.15)
				(type solid)
			)
			(layer "B.SilkS")
		)
		(fp_circle
			(center -0.68 1.27)
			(end -0.63 1.27)
			(stroke
				(width 0.15)
				(type solid)
			)
			(fill yes)
			(layer "B.SilkS")
		)
		(fp_rect
			(start -0.8 1.5)
			(end 0.8 -1.499)
			(stroke
				(width 0.05)
				(type solid)
			)
			(fill no)
			(layer "B.CrtYd")
		)
		(fp_line
			(start -0.5 -1.249)
			(end 0.498 -1.249)
			(stroke
				(width 0.15)
				(type solid)
			)
			(layer "B.Fab")
		)
		(fp_line
			(start -0.5 1)
			(end -0.5 -1.249)
			(stroke
				(width 0.15)
				(type solid)
			)
			(layer "B.Fab")
		)
		(fp_line
			(start 0.498 1.25)
			(end 0.498 -1.249)
			(stroke
				(width 0.15)
				(type solid)
			)
			(layer "B.Fab")
		)
		(fp_line
			(start 0.498 1.25)
			(end -0.25 1.25)
			(stroke
				(width 0.15)
				(type solid)
			)
			(layer "B.Fab")
		)
		(fp_line
			(start -0.25 1.25)
			(end -0.5 1)
			(stroke
				(width 0.15)
				(type solid)
			)
			(layer "B.Fab")
		)
		(fp_text user "${REFERENCE}"
			(at -0.802 -4.498 90)
			(layer "B.Fab")
			(effects
				(font
					(size 0.7 0.7)
					(thickness 0.15)
				)
				(justify right top mirror)
			)
		)
		(fp_text user "Author: Antmicro"
			(at -0.802 -5.7 90)
			(layer "B.Fab")
			(effects
				(font
					(size 0.7 0.7)
					(thickness 0.15)
				)
				(justify right top mirror)
			)
		)
		(fp_text user "License: Apache-2.0"
			(at -0.802 -6.9 90)
			(layer "B.Fab")
			(effects
				(font
					(size 0.7 0.7)
					(thickness 0.15)
				)
				(justify right top mirror)
			)
		)
		(pad "1" smd roundrect
			(at -0.387 1 180)
			(size 0.25 0.55)
			(layers "B.Cu" "B.Mask" "B.Paste")
			(roundrect_rratio 0.25)
			(net 42 "/Peripherals/I2C_{CONN}.SCL")
			(pintype "passive")
		)
		(pad "2" smd roundrect
			(at -0.387 0.5 180)
			(size 0.25 0.55)
			(layers "B.Cu" "B.Mask" "B.Paste")
			(roundrect_rratio 0.25)
			(net 43 "/Peripherals/I2C_{CONN}.SDA")
			(pintype "passive")
		)
		(pad "3" smd roundrect
			(at -0.387 0 180)
			(size 0.4 0.55)
			(layers "B.Cu" "B.Mask" "B.Paste")
			(roundrect_rratio 0.25)
			(net 1 "GND")
			(pintype "power_in")
		)
		(pad "4" smd roundrect
			(at -0.387 -0.498 180)
			(size 0.25 0.55)
			(layers "B.Cu" "B.Mask" "B.Paste")
			(roundrect_rratio 0.25)
			(net 838 "/Peripherals/I2C_CONN1_3V3")
			(pintype "passive")
		)
		(pad "5" smd roundrect
			(at -0.387 -0.998 180)
			(size 0.25 0.55)
			(layers "B.Cu" "B.Mask" "B.Paste")
			(roundrect_rratio 0.25)
			(net 1 "GND")
			(pintype "passive")
		)
		(pad "6" smd roundrect
			(at 0.385 -0.998 180)
			(size 0.25 0.55)
			(layers "B.Cu" "B.Mask" "B.Paste")
			(roundrect_rratio 0.25)
			(net 1 "GND")
			(pintype "passive")
		)
		(pad "7" smd roundrect
			(at 0.385 -0.498 180)
			(size 0.25 0.55)
			(layers "B.Cu" "B.Mask" "B.Paste")
			(roundrect_rratio 0.25)
			(net 838 "/Peripherals/I2C_CONN1_3V3")
			(pintype "passive")
		)
		(pad "8" smd roundrect
			(at 0.385 0 180)
			(size 0.4 0.55)
			(layers "B.Cu" "B.Mask" "B.Paste")
			(roundrect_rratio 0.25)
			(net 1 "GND")
			(pintype "passive")
		)
		(pad "9" smd roundrect
			(at 0.385 0.5 180)
			(size 0.25 0.55)
			(layers "B.Cu" "B.Mask" "B.Paste")
			(roundrect_rratio 0.25)
			(net 43 "/Peripherals/I2C_{CONN}.SDA")
			(pintype "passive")
		)
		(pad "10" smd roundrect
			(at 0.385 1 180)
			(size 0.25 0.55)
			(layers "B.Cu" "B.Mask" "B.Paste")
			(roundrect_rratio 0.25)
			(net 42 "/Peripherals/I2C_{CONN}.SCL")
			(pintype "passive")
		)
	)
	(footprint "antmicro-footprints:C_0402_1005Metric"
		(layer "B.Cu")
		(at 119.78 70.59 180)
		(descr "Capacitor SMD 0402")
		(tags "capacitor SMD 0402")
		(property "Reference" "C17"
			(at -1.42 -3.11 0)
			(layer "B.SilkS")
			(effects
				(font
					(size 0.7 0.7)
					(thickness 0.15)
				)
				(justify left bottom mirror)
			)
		)
		(property "Value" "C_100n_0402"
			(at -1.022927 -2.155213 0)
			(layer "B.Fab")
			(effects
				(font
					(size 0.7 0.7)
					(thickness 0.15)
				)
				(justify left bottom mirror)
			)
		)
		(property "Datasheet" "https://www.murata.com/products/productdetail?partno=GRM155R61H104KE14%23"
			(at 0 0 0)
			(layer "B.Fab")
			(hide yes)
			(effects
				(font
					(size 1.27 1.27)
					(thickness 0.15)
				)
				(justify mirror)
			)
		)
		(property "Description" "SMD Multilayer Ceramic Capacitor, 0.1 µF, 50 V, 0402 [1005 Metric], ± 10%, X5R, GRM Series"
			(at 0 0 0)
			(layer "B.Fab")
			(hide yes)
			(effects
				(font
					(size 1.27 1.27)
					(thickness 0.15)
				)
				(justify mirror)
			)
		)
		(property "MPN" "GRM155R61H104KE14D"
			(at 0 0 0)
			(unlocked yes)
			(layer "B.Fab")
			(hide yes)
			(effects
				(font
					(size 1 1)
					(thickness 0.15)
				)
				(justify mirror)
			)
		)
		(property "Val" "100n"
			(at 0 0 0)
			(unlocked yes)
			(layer "B.Fab")
			(hide yes)
			(effects
				(font
					(size 1 1)
					(thickness 0.15)
				)
				(justify mirror)
			)
		)
		(property "Voltage" "50V"
			(at 0 0 0)
			(unlocked yes)
			(layer "B.Fab")
			(hide yes)
			(effects
				(font
					(size 1 1)
					(thickness 0.15)
				)
				(justify mirror)
			)
		)
		(property "Dielectric" "X5R"
			(at 0 0 0)
			(unlocked yes)
			(layer "B.Fab")
			(hide yes)
			(effects
				(font
					(size 1 1)
					(thickness 0.15)
				)
				(justify mirror)
			)
		)
		(property "Manufacturer" "Murata"
			(at 0 0 0)
			(unlocked yes)
			(layer "B.Fab")
			(hide yes)
			(effects
				(font
					(size 1 1)
					(thickness 0.15)
				)
				(justify mirror)
			)
		)
		(property "License" "Apache-2.0"
			(at 0 0 0)
			(unlocked yes)
			(layer "B.Fab")
			(hide yes)
			(effects
				(font
					(size 1 1)
					(thickness 0.15)
				)
				(justify mirror)
			)
		)
		(property "Author" "Antmicro"
			(at 0 0 0)
			(unlocked yes)
			(layer "B.Fab")
			(hide yes)
			(effects
				(font
					(size 1 1)
					(thickness 0.15)
				)
				(justify mirror)
			)
		)
		(sheetname "/SoM_Power/")
		(sheetfile "som_power.kicad_sch")
		(attr smd)
		(fp_rect
			(start -0.925 0.47)
			(end 0.925 -0.47)
			(stroke
				(width 0.05)
				(type default)
			)
			(fill no)
			(layer "B.CrtYd")
		)
		(fp_line
			(start 0.504 0.25)
			(end 0.504 -0.248)
			(stroke
				(width 0.15)
				(type solid)
			)
			(layer "B.Fab")
		)
		(fp_line
			(start 0.504 -0.248)
			(end -0.494 -0.248)
			(stroke
				(width 0.15)
				(type solid)
			)
			(layer "B.Fab")
		)
		(fp_line
			(start -0.494 0.25)
			(end 0.504 0.25)
			(stroke
				(width 0.15)
				(type solid)
			)
			(layer "B.Fab")
		)
		(fp_line
			(start -0.494 -0.248)
			(end -0.494 0.25)
			(stroke
				(width 0.15)
				(type solid)
			)
			(layer "B.Fab")
		)
		(fp_text user "License: Apache-2.0"
			(at -0.939 -5.799 0)
			(layer "B.Fab")
			(effects
				(font
					(size 0.7 0.7)
					(thickness 0.15)
				)
				(justify left bottom mirror)
			)
		)
		(fp_text user "${REFERENCE}"
			(at -0.939 -4.599 0)
			(layer "B.Fab")
			(effects
				(font
					(size 0.7 0.7)
					(thickness 0.15)
				)
				(justify left bottom mirror)
			)
		)
		(fp_text user "Author: Antmicro"
			(at -0.939 -3.399 0)
			(layer "B.Fab")
			(effects
				(font
					(size 0.7 0.7)
					(thickness 0.15)
				)
				(justify left bottom mirror)
			)
		)
		(pad "1" smd roundrect
			(at -0.48 0 180)
			(size 0.59 0.64)
			(layers "B.Cu" "B.Mask" "B.Paste")
			(roundrect_rratio 0.25)
			(net 1 "GND")
			(pintype "passive")
		)
		(pad "2" smd roundrect
			(at 0.48 0 180)
			(size 0.59 0.64)
			(layers "B.Cu" "B.Mask" "B.Paste")
			(roundrect_rratio 0.25)
			(net 213 "+5V_SOM")
			(pintype "passive")
		)
	)
	(footprint "antmicro-footprints:R_0402_1005Metric"
		(layer "B.Cu")
		(at 206.7 120 180)
		(descr "Resistor SMD 0402")
		(tags "resistor SMD 0402")
		(property "Reference" "R262"
			(at -3.86 -0.38 0)
			(layer "B.SilkS")
			(effects
				(font
					(size 0.7 0.7)
					(thickness 0.15)
				)
				(justify left bottom mirror)
			)
		)
		(property "Value" "R_49k9_0402"
			(at -1.011843 -1.772047 0)
			(layer "B.Fab")
			(effects
				(font
					(size 0.7 0.7)
					(thickness 0.15)
				)
				(justify left bottom mirror)
			)
		)
		(property "Datasheet" "https://www.bourns.com/docs/product-datasheets/cr.pdf"
			(at 0 0 0)
			(layer "B.Fab")
			(hide yes)
			(effects
				(font
					(size 1.27 1.27)
					(thickness 0.15)
				)
				(justify mirror)
			)
		)
		(property "Description" "SMD Chip Resistor, 49.9 kohm, ± 1%, 63 mW, 0402 [1005 Metric], Thick Film, General Purpose"
			(at 0 0 0)
			(layer "B.Fab")
			(hide yes)
			(effects
				(font
					(size 1.27 1.27)
					(thickness 0.15)
				)
				(justify mirror)
			)
		)
		(property "MPN" "CR0402-FX-4992GLF"
			(at 0 0 0)
			(unlocked yes)
			(layer "B.Fab")
			(hide yes)
			(effects
				(font
					(size 1 1)
					(thickness 0.15)
				)
				(justify mirror)
			)
		)
		(property "Manufacturer" "Bourns"
			(at 0 0 0)
			(unlocked yes)
			(layer "B.Fab")
			(hide yes)
			(effects
				(font
					(size 1 1)
					(thickness 0.15)
				)
				(justify mirror)
			)
		)
		(property "License" "Apache-2.0"
			(at 0 0 0)
			(unlocked yes)
			(layer "B.Fab")
			(hide yes)
			(effects
				(font
					(size 1 1)
					(thickness 0.15)
				)
				(justify mirror)
			)
		)
		(property "Author" "Antmicro"
			(at 0 0 0)
			(unlocked yes)
			(layer "B.Fab")
			(hide yes)
			(effects
				(font
					(size 1 1)
					(thickness 0.15)
				)
				(justify mirror)
			)
		)
		(property "Val" "49k9"
			(at 0 0 0)
			(unlocked yes)
			(layer "B.Fab")
			(hide yes)
			(effects
				(font
					(size 1 1)
					(thickness 0.15)
				)
				(justify mirror)
			)
		)
		(property "Tolerance" "1%"
			(at 0 0 0)
			(unlocked yes)
			(layer "B.Fab")
			(hide yes)
			(effects
				(font
					(size 1 1)
					(thickness 0.15)
				)
				(justify mirror)
			)
		)
		(sheetname "/USB Hub/")
		(sheetfile "usb_hub.kicad_sch")
		(attr smd)
		(fp_rect
			(start -0.925 0.47)
			(end 0.925 -0.47)
			(stroke
				(width 0.05)
				(type default)
			)
			(fill no)
			(layer "B.CrtYd")
		)
		(fp_rect
			(start -0.5 0.25)
			(end 0.5 -0.25)
			(stroke
				(width 0.15)
				(type solid)
			)
			(fill no)
			(layer "B.Fab")
		)
		(fp_text user "License: Apache-2.0"
			(at -0.95 -5.169 0)
			(layer "B.Fab")
			(effects
				(font
					(size 0.7 0.7)
					(thickness 0.15)
				)
				(justify left bottom mirror)
			)
		)
		(fp_text user "Author: Antmicro"
			(at -0.95 -4.169 0)
			(layer "B.Fab")
			(effects
				(font
					(size 0.7 0.7)
					(thickness 0.15)
				)
				(justify left bottom mirror)
			)
		)
		(fp_text user "${REFERENCE}"
			(at -0.95 -3.168 0)
			(layer "B.Fab")
			(effects
				(font
					(size 0.7 0.7)
					(thickness 0.15)
				)
				(justify left bottom mirror)
			)
		)
		(pad "1" smd roundrect
			(at -0.48 0 180)
			(size 0.59 0.64)
			(layers "B.Cu" "B.Mask" "B.Paste")
			(roundrect_rratio 0.25)
			(net 1 "GND")
			(pintype "passive")
		)
		(pad "2" smd roundrect
			(at 0.48 0 180)
			(size 0.59 0.64)
			(layers "B.Cu" "B.Mask" "B.Paste")
			(roundrect_rratio 0.25)
			(net 1016 "/USB Hub/USBC3_VBUS_MON")
			(pintype "passive")
		)
	)
	(footprint "antmicro-footprints:TP_SMD_0.75mm"
		(layer "B.Cu")
		(at 120.43 65.06 -90)
		(property "Reference" "TP85"
			(at 0.5 0.6 0)
			(layer "B.SilkS")
			(effects
				(font
					(size 0.7 0.7)
					(thickness 0.15)
				)
				(justify left bottom mirror)
			)
		)
		(property "Value" "TP_0.75mm_SMD"
			(at 0 -1.2 90)
			(layer "B.Fab")
			(effects
				(font
					(size 0.7 0.7)
					(thickness 0.15)
				)
				(justify left bottom mirror)
			)
		)
		(property "Description" "SMT test point"
			(at 0 0 90)
			(layer "B.Fab")
			(hide yes)
			(effects
				(font
					(size 1.27 1.27)
					(thickness 0.15)
				)
				(justify mirror)
			)
		)
		(property "MPN" ""
			(at 0 0 90)
			(unlocked yes)
			(layer "B.Fab")
			(hide yes)
			(effects
				(font
					(size 1 1)
					(thickness 0.15)
				)
				(justify mirror)
			)
		)
		(property "Manufacturer" ""
			(at 0 0 90)
			(unlocked yes)
			(layer "B.Fab")
			(hide yes)
			(effects
				(font
					(size 1 1)
					(thickness 0.15)
				)
				(justify mirror)
			)
		)
		(property "Author" "Antmicro"
			(at 0 0 90)
			(unlocked yes)
			(layer "B.Fab")
			(hide yes)
			(effects
				(font
					(size 1 1)
					(thickness 0.15)
				)
				(justify mirror)
			)
		)
		(property "License" "Apache-2.0"
			(at 0 0 90)
			(unlocked yes)
			(layer "B.Fab")
			(hide yes)
			(effects
				(font
					(size 1 1)
					(thickness 0.15)
				)
				(justify mirror)
			)
		)
		(sheetname "/SoM_Power/")
		(sheetfile "som_power.kicad_sch")
		(attr exclude_from_pos_files exclude_from_bom)
		(fp_circle
			(center 0 0)
			(end 0.475 0)
			(stroke
				(width 0.05)
				(type default)
			)
			(fill no)
			(layer "B.CrtYd")
		)
		(fp_text user "${REFERENCE}"
			(at -0.4 -2.7 90)
			(layer "B.Fab")
			(effects
				(font
					(size 0.7 0.7)
					(thickness 0.15)
				)
				(justify left bottom mirror)
			)
		)
		(fp_text user "License: Apache-2.0"
			(at -0.4 -5.101 90)
			(layer "B.Fab")
			(effects
				(font
					(size 0.7 0.7)
					(thickness 0.15)
				)
				(justify left bottom mirror)
			)
		)
		(fp_text user "Author: Antmicro"
			(at -0.4 -3.901 90)
			(layer "B.Fab")
			(effects
				(font
					(size 0.7 0.7)
					(thickness 0.15)
				)
				(justify left bottom mirror)
			)
		)
		(pad "1" smd circle
			(at 0 0 270)
			(size 0.75 0.75)
			(layers "B.Cu" "B.Mask")
			(net 246 "/SoM_Power/~{VDDIN_PWR_BAD}")
			(pinfunction "1")
			(pintype "passive")
		)
	)
	(footprint "antmicro-footprints:C_0402_1005Metric"
		(layer "B.Cu")
		(at 198.476 146.25 90)
		(descr "Capacitor SMD 0402")
		(tags "capacitor SMD 0402")
		(property "Reference" "C171"
			(at -1.55 -1.45 90)
			(layer "B.SilkS")
			(effects
				(font
					(size 0.7 0.7)
					(thickness 0.15)
				)
				(justify right top mirror)
			)
		)
		(property "Value" "C_100n_0402"
			(at -1.022927 -2.155213 90)
			(layer "B.Fab")
			(effects
				(font
					(size 0.7 0.7)
					(thickness 0.15)
				)
				(justify right top mirror)
			)
		)
		(property "Datasheet" "https://www.murata.com/products/productdetail?partno=GRM155R61H104KE14%23"
			(at 0 0 90)
			(layer "B.Fab")
			(hide yes)
			(effects
				(font
					(size 1.27 1.27)
					(thickness 0.15)
				)
				(justify mirror)
			)
		)
		(property "Description" "SMD Multilayer Ceramic Capacitor, 0.1 µF, 50 V, 0402 [1005 Metric], ± 10%, X5R, GRM Series"
			(at 0 0 90)
			(layer "B.Fab")
			(hide yes)
			(effects
				(font
					(size 1.27 1.27)
					(thickness 0.15)
				)
				(justify mirror)
			)
		)
		(property "MPN" "GRM155R61H104KE14D"
			(at 0 0 270)
			(unlocked yes)
			(layer "B.Fab")
			(hide yes)
			(effects
				(font
					(size 1 1)
					(thickness 0.15)
				)
				(justify mirror)
			)
		)
		(property "Manufacturer" "Murata"
			(at 0 0 270)
			(unlocked yes)
			(layer "B.Fab")
			(hide yes)
			(effects
				(font
					(size 1 1)
					(thickness 0.15)
				)
				(justify mirror)
			)
		)
		(property "License" "Apache-2.0"
			(at 0 0 270)
			(unlocked yes)
			(layer "B.Fab")
			(hide yes)
			(effects
				(font
					(size 1 1)
					(thickness 0.15)
				)
				(justify mirror)
			)
		)
		(property "Author" "Antmicro"
			(at 0 0 270)
			(unlocked yes)
			(layer "B.Fab")
			(hide yes)
			(effects
				(font
					(size 1 1)
					(thickness 0.15)
				)
				(justify mirror)
			)
		)
		(property "Val" "100n"
			(at 0 0 270)
			(unlocked yes)
			(layer "B.Fab")
			(hide yes)
			(effects
				(font
					(size 1 1)
					(thickness 0.15)
				)
				(justify mirror)
			)
		)
		(property "Voltage" "50V"
			(at 0 0 270)
			(unlocked yes)
			(layer "B.Fab")
			(hide yes)
			(effects
				(font
					(size 1 1)
					(thickness 0.15)
				)
				(justify mirror)
			)
		)
		(property "Dielectric" "X5R"
			(at 0 0 270)
			(unlocked yes)
			(layer "B.Fab")
			(hide yes)
			(effects
				(font
					(size 1 1)
					(thickness 0.15)
				)
				(justify mirror)
			)
		)
		(sheetname "/SFP/")
		(sheetfile "sfp.kicad_sch")
		(attr smd)
		(fp_poly
			(pts
				(xy -0.925 0.47) (xy 0.925 0.47) (xy 0.925 -0.47) (xy -0.925 -0.47)
			)
			(stroke
				(width 0.05)
				(type default)
			)
			(fill no)
			(layer "B.CrtYd")
		)
		(fp_line
			(start 0.504 -0.248)
			(end -0.494 -0.248)
			(stroke
				(width 0.15)
				(type solid)
			)
			(layer "B.Fab")
		)
		(fp_line
			(start -0.494 -0.248)
			(end -0.494 0.25)
			(stroke
				(width 0.15)
				(type solid)
			)
			(layer "B.Fab")
		)
		(fp_line
			(start 0.504 0.25)
			(end 0.504 -0.248)
			(stroke
				(width 0.15)
				(type solid)
			)
			(layer "B.Fab")
		)
		(fp_line
			(start -0.494 0.25)
			(end 0.504 0.25)
			(stroke
				(width 0.15)
				(type solid)
			)
			(layer "B.Fab")
		)
		(fp_text user "${REFERENCE}"
			(at -0.939 -4.599 90)
			(layer "B.Fab")
			(effects
				(font
					(size 0.7 0.7)
					(thickness 0.15)
				)
				(justify right top mirror)
			)
		)
		(fp_text user "Author: Antmicro"
			(at -0.939 -3.399 90)
			(layer "B.Fab")
			(effects
				(font
					(size 0.7 0.7)
					(thickness 0.15)
				)
				(justify right top mirror)
			)
		)
		(fp_text user "License: Apache-2.0"
			(at -0.939 -5.799 90)
			(layer "B.Fab")
			(effects
				(font
					(size 0.7 0.7)
					(thickness 0.15)
				)
				(justify right top mirror)
			)
		)
		(pad "1" smd roundrect
			(at -0.48 0 90)
			(size 0.59 0.64)
			(layers "B.Cu" "B.Mask" "B.Paste")
			(roundrect_rratio 0.25)
			(net 1 "GND")
			(pintype "passive")
		)
		(pad "2" smd roundrect
			(at 0.48 0 90)
			(size 0.59 0.64)
			(layers "B.Cu" "B.Mask" "B.Paste")
			(roundrect_rratio 0.25)
			(net 2 "+3V3")
			(pintype "passive")
		)
	)
	(footprint "antmicro-footprints:R_0402_1005Metric"
		(layer "B.Cu")
		(at 203.3 130.5 90)
		(descr "Resistor SMD 0402")
		(tags "resistor SMD 0402")
		(property "Reference" "R46"
			(at -3.1 -0.3 90)
			(layer "B.SilkS")
			(effects
				(font
					(size 0.7 0.7)
					(thickness 0.15)
				)
				(justify right top mirror)
			)
		)
		(property "Value" "R_0R_0402"
			(at -1.011843 -1.772047 90)
			(layer "B.Fab")
			(effects
				(font
					(size 0.7 0.7)
					(thickness 0.15)
				)
				(justify right top mirror)
			)
		)
		(property "Datasheet" "https://industrial.panasonic.com/cdbs/www-data/pdf/RDA0000/AOA0000C301.pdf"
			(at 0 0 90)
			(layer "B.Fab")
			(hide yes)
			(effects
				(font
					(size 1.27 1.27)
					(thickness 0.15)
				)
				(justify mirror)
			)
		)
		(property "Description" "SMD Chip Resistor, Jumper, 0 ohm, 100 mW, 0402 [1005 Metric], Thick Film, General Purpose"
			(at 0 0 90)
			(layer "B.Fab")
			(hide yes)
			(effects
				(font
					(size 1.27 1.27)
					(thickness 0.15)
				)
				(justify mirror)
			)
		)
		(property "Manufacturer" "Panasonic"
			(at 0 0 270)
			(unlocked yes)
			(layer "B.Fab")
			(hide yes)
			(effects
				(font
					(size 1 1)
					(thickness 0.15)
				)
				(justify mirror)
			)
		)
		(property "MPN" "ERJ2GE0R00X"
			(at 0 0 270)
			(unlocked yes)
			(layer "B.Fab")
			(hide yes)
			(effects
				(font
					(size 1 1)
					(thickness 0.15)
				)
				(justify mirror)
			)
		)
		(property "Val" "0R"
			(at 0 0 270)
			(unlocked yes)
			(layer "B.Fab")
			(hide yes)
			(effects
				(font
					(size 1 1)
					(thickness 0.15)
				)
				(justify mirror)
			)
		)
		(property "License" "Apache-2.0"
			(at 0 0 270)
			(unlocked yes)
			(layer "B.Fab")
			(hide yes)
			(effects
				(font
					(size 1 1)
					(thickness 0.15)
				)
				(justify mirror)
			)
		)
		(property "Author" "Antmicro"
			(at 0 0 270)
			(unlocked yes)
			(layer "B.Fab")
			(hide yes)
			(effects
				(font
					(size 1 1)
					(thickness 0.15)
				)
				(justify mirror)
			)
		)
		(property "Tolerance" "~"
			(at 0 0 270)
			(unlocked yes)
			(layer "B.Fab")
			(hide yes)
			(effects
				(font
					(size 1 1)
					(thickness 0.15)
				)
				(justify mirror)
			)
		)
		(property "Current" "1A"
			(at 0 0 270)
			(unlocked yes)
			(layer "B.Fab")
			(hide yes)
			(effects
				(font
					(size 1 1)
					(thickness 0.15)
				)
				(justify mirror)
			)
		)
		(sheetname "/USB Hub/")
		(sheetfile "usb_hub.kicad_sch")
		(attr smd)
		(fp_rect
			(start -0.925 0.47)
			(end 0.925 -0.47)
			(stroke
				(width 0.05)
				(type default)
			)
			(fill no)
			(layer "B.CrtYd")
		)
		(fp_rect
			(start -0.5 0.25)
			(end 0.5 -0.25)
			(stroke
				(width 0.15)
				(type solid)
			)
			(fill no)
			(layer "B.Fab")
		)
		(fp_text user "Author: Antmicro"
			(at -0.95 -4.169 90)
			(layer "B.Fab")
			(effects
				(font
					(size 0.7 0.7)
					(thickness 0.15)
				)
				(justify right top mirror)
			)
		)
		(fp_text user "License: Apache-2.0"
			(at -0.95 -5.169 90)
			(layer "B.Fab")
			(effects
				(font
					(size 0.7 0.7)
					(thickness 0.15)
				)
				(justify right top mirror)
			)
		)
		(fp_text user "${REFERENCE}"
			(at -0.95 -3.168 90)
			(layer "B.Fab")
			(effects
				(font
					(size 0.7 0.7)
					(thickness 0.15)
				)
				(justify right top mirror)
			)
		)
		(pad "1" smd roundrect
			(at -0.48 0 90)
			(size 0.59 0.64)
			(layers "B.Cu" "B.Mask" "B.Paste")
			(roundrect_rratio 0.25)
			(net 1126 "Net-(U21-USB2DN_DM3)")
			(pintype "passive")
		)
		(pad "2" smd roundrect
			(at 0.48 0 90)
			(size 0.59 0.64)
			(layers "B.Cu" "B.Mask" "B.Paste")
			(roundrect_rratio 0.25)
			(net 2 "+3V3")
			(pintype "passive")
		)
	)
	(footprint "antmicro-footprints:C_0402_1005Metric"
		(layer "B.Cu")
		(at 225.426 137.86)
		(descr "Capacitor SMD 0402")
		(tags "capacitor SMD 0402")
		(property "Reference" "C178"
			(at -1.8 0.74 0)
			(layer "B.SilkS")
			(effects
				(font
					(size 0.7 0.7)
					(thickness 0.15)
				)
				(justify right top mirror)
			)
		)
		(property "Value" "C_100n_0402"
			(at -1.022927 -2.155213 0)
			(layer "B.Fab")
			(effects
				(font
					(size 0.7 0.7)
					(thickness 0.15)
				)
				(justify right top mirror)
			)
		)
		(property "Datasheet" "https://www.murata.com/products/productdetail?partno=GRM155R61H104KE14%23"
			(at 0 0 0)
			(layer "B.Fab")
			(hide yes)
			(effects
				(font
					(size 1.27 1.27)
					(thickness 0.15)
				)
				(justify mirror)
			)
		)
		(property "Description" "SMD Multilayer Ceramic Capacitor, 0.1 µF, 50 V, 0402 [1005 Metric], ± 10%, X5R, GRM Series"
			(at 0 0 0)
			(layer "B.Fab")
			(hide yes)
			(effects
				(font
					(size 1.27 1.27)
					(thickness 0.15)
				)
				(justify mirror)
			)
		)
		(property "MPN" "GRM155R61H104KE14D"
			(at 0 0 180)
			(unlocked yes)
			(layer "B.Fab")
			(hide yes)
			(effects
				(font
					(size 1 1)
					(thickness 0.15)
				)
				(justify mirror)
			)
		)
		(property "Manufacturer" "Murata"
			(at 0 0 180)
			(unlocked yes)
			(layer "B.Fab")
			(hide yes)
			(effects
				(font
					(size 1 1)
					(thickness 0.15)
				)
				(justify mirror)
			)
		)
		(property "License" "Apache-2.0"
			(at 0 0 180)
			(unlocked yes)
			(layer "B.Fab")
			(hide yes)
			(effects
				(font
					(size 1 1)
					(thickness 0.15)
				)
				(justify mirror)
			)
		)
		(property "Author" "Antmicro"
			(at 0 0 180)
			(unlocked yes)
			(layer "B.Fab")
			(hide yes)
			(effects
				(font
					(size 1 1)
					(thickness 0.15)
				)
				(justify mirror)
			)
		)
		(property "Val" "100n"
			(at 0 0 180)
			(unlocked yes)
			(layer "B.Fab")
			(hide yes)
			(effects
				(font
					(size 1 1)
					(thickness 0.15)
				)
				(justify mirror)
			)
		)
		(property "Voltage" "50V"
			(at 0 0 180)
			(unlocked yes)
			(layer "B.Fab")
			(hide yes)
			(effects
				(font
					(size 1 1)
					(thickness 0.15)
				)
				(justify mirror)
			)
		)
		(property "Dielectric" "X5R"
			(at 0 0 180)
			(unlocked yes)
			(layer "B.Fab")
			(hide yes)
			(effects
				(font
					(size 1 1)
					(thickness 0.15)
				)
				(justify mirror)
			)
		)
		(sheetname "/SFP/")
		(sheetfile "sfp.kicad_sch")
		(attr smd)
		(fp_rect
			(start -0.925 0.47)
			(end 0.925 -0.47)
			(stroke
				(width 0.05)
				(type default)
			)
			(fill no)
			(layer "B.CrtYd")
		)
		(fp_line
			(start -0.494 -0.248)
			(end -0.494 0.25)
			(stroke
				(width 0.15)
				(type solid)
			)
			(layer "B.Fab")
		)
		(fp_line
			(start -0.494 0.25)
			(end 0.504 0.25)
			(stroke
				(width 0.15)
				(type solid)
			)
			(layer "B.Fab")
		)
		(fp_line
			(start 0.504 -0.248)
			(end -0.494 -0.248)
			(stroke
				(width 0.15)
				(type solid)
			)
			(layer "B.Fab")
		)
		(fp_line
			(start 0.504 0.25)
			(end 0.504 -0.248)
			(stroke
				(width 0.15)
				(type solid)
			)
			(layer "B.Fab")
		)
		(fp_text user "${REFERENCE}"
			(at -0.939 -4.599 0)
			(layer "B.Fab")
			(effects
				(font
					(size 0.7 0.7)
					(thickness 0.15)
				)
				(justify right top mirror)
			)
		)
		(fp_text user "License: Apache-2.0"
			(at -0.939 -5.799 0)
			(layer "B.Fab")
			(effects
				(font
					(size 0.7 0.7)
					(thickness 0.15)
				)
				(justify right top mirror)
			)
		)
		(fp_text user "Author: Antmicro"
			(at -0.939 -3.399 0)
			(layer "B.Fab")
			(effects
				(font
					(size 0.7 0.7)
					(thickness 0.15)
				)
				(justify right top mirror)
			)
		)
		(pad "1" smd roundrect
			(at -0.48 0)
			(size 0.59 0.64)
			(layers "B.Cu" "B.Mask" "B.Paste")
			(roundrect_rratio 0.25)
			(net 1 "GND")
			(pintype "passive")
		)
		(pad "2" smd roundrect
			(at 0.48 0)
			(size 0.59 0.64)
			(layers "B.Cu" "B.Mask" "B.Paste")
			(roundrect_rratio 0.25)
			(net 379 "/SFP/SH")
			(pintype "passive")
		)
	)
	(footprint "antmicro-footprints:R_0402_1005Metric"
		(layer "B.Cu")
		(at 223.06 119.9)
		(descr "Resistor SMD 0402")
		(tags "resistor SMD 0402")
		(property "Reference" "R332"
			(at -1.66 -1.5 0)
			(layer "B.SilkS")
			(effects
				(font
					(size 0.7 0.7)
					(thickness 0.15)
				)
				(justify right top mirror)
			)
		)
		(property "Value" "R_10k_0402"
			(at -1.011843 -1.772047 0)
			(layer "B.Fab")
			(effects
				(font
					(size 0.7 0.7)
					(thickness 0.15)
				)
				(justify right top mirror)
			)
		)
		(property "Datasheet" "https://www.bourns.com/docs/product-datasheets/cr.pdf"
			(at 0 0 0)
			(layer "B.Fab")
			(hide yes)
			(effects
				(font
					(size 1.27 1.27)
					(thickness 0.15)
				)
				(justify mirror)
			)
		)
		(property "Description" "SMD Chip Resistor, 10 kohm, ± 1%, 62.5 mW, 0402 [1005 Metric], Thick Film, General Purpose"
			(at 0 0 0)
			(layer "B.Fab")
			(hide yes)
			(effects
				(font
					(size 1.27 1.27)
					(thickness 0.15)
				)
				(justify mirror)
			)
		)
		(property "MPN" "CR0402-FX-1002GLF"
			(at 0 0 180)
			(unlocked yes)
			(layer "B.Fab")
			(hide yes)
			(effects
				(font
					(size 1 1)
					(thickness 0.15)
				)
				(justify mirror)
			)
		)
		(property "Manufacturer" "Bourns"
			(at 0 0 180)
			(unlocked yes)
			(layer "B.Fab")
			(hide yes)
			(effects
				(font
					(size 1 1)
					(thickness 0.15)
				)
				(justify mirror)
			)
		)
		(property "License" "Apache-2.0"
			(at 0 0 180)
			(unlocked yes)
			(layer "B.Fab")
			(hide yes)
			(effects
				(font
					(size 1 1)
					(thickness 0.15)
				)
				(justify mirror)
			)
		)
		(property "Author" "Antmicro"
			(at 0 0 180)
			(unlocked yes)
			(layer "B.Fab")
			(hide yes)
			(effects
				(font
					(size 1 1)
					(thickness 0.15)
				)
				(justify mirror)
			)
		)
		(property "Val" "10k"
			(at 0 0 180)
			(unlocked yes)
			(layer "B.Fab")
			(hide yes)
			(effects
				(font
					(size 1 1)
					(thickness 0.15)
				)
				(justify mirror)
			)
		)
		(property "Tolerance" "1%"
			(at 0 0 180)
			(unlocked yes)
			(layer "B.Fab")
			(hide yes)
			(effects
				(font
					(size 1 1)
					(thickness 0.15)
				)
				(justify mirror)
			)
		)
		(sheetname "/USB Hub/")
		(sheetfile "usb_hub.kicad_sch")
		(attr smd)
		(fp_rect
			(start -0.925 0.47)
			(end 0.925 -0.47)
			(stroke
				(width 0.05)
				(type default)
			)
			(fill no)
			(layer "B.CrtYd")
		)
		(fp_rect
			(start -0.5 0.25)
			(end 0.5 -0.25)
			(stroke
				(width 0.15)
				(type solid)
			)
			(fill no)
			(layer "B.Fab")
		)
		(fp_text user "Author: Antmicro"
			(at -0.95 -4.169 0)
			(layer "B.Fab")
			(effects
				(font
					(size 0.7 0.7)
					(thickness 0.15)
				)
				(justify right top mirror)
			)
		)
		(fp_text user "${REFERENCE}"
			(at -0.95 -3.168 0)
			(layer "B.Fab")
			(effects
				(font
					(size 0.7 0.7)
					(thickness 0.15)
				)
				(justify right top mirror)
			)
		)
		(fp_text user "License: Apache-2.0"
			(at -0.95 -5.169 0)
			(layer "B.Fab")
			(effects
				(font
					(size 0.7 0.7)
					(thickness 0.15)
				)
				(justify right top mirror)
			)
		)
		(pad "1" smd roundrect
			(at -0.48 0)
			(size 0.59 0.64)
			(layers "B.Cu" "B.Mask" "B.Paste")
			(roundrect_rratio 0.25)
			(net 5 "+5V")
			(pintype "passive")
		)
		(pad "2" smd roundrect
			(at 0.48 0)
			(size 0.59 0.64)
			(layers "B.Cu" "B.Mask" "B.Paste")
			(roundrect_rratio 0.25)
			(net 1332 "Net-(Q27-D1)")
			(pintype "passive")
		)
	)
	(footprint "antmicro-footprints:R_0402_1005Metric"
		(layer "B.Cu")
		(at 203.4 102.8)
		(descr "Resistor SMD 0402")
		(tags "resistor SMD 0402")
		(property "Reference" "R254"
			(at 1 -0.4 0)
			(layer "B.SilkS")
			(effects
				(font
					(size 0.7 0.7)
					(thickness 0.15)
				)
				(justify right top mirror)
			)
		)
		(property "Value" "R_10k_0402"
			(at -1.011843 -1.772046 0)
			(layer "B.Fab")
			(effects
				(font
					(size 0.7 0.7)
					(thickness 0.15)
				)
				(justify right top mirror)
			)
		)
		(property "Datasheet" "https://www.bourns.com/docs/product-datasheets/cr.pdf"
			(at 0 0 0)
			(layer "B.Fab")
			(hide yes)
			(effects
				(font
					(size 1.27 1.27)
					(thickness 0.15)
				)
				(justify mirror)
			)
		)
		(property "Description" "SMD Chip Resistor, 10 kohm, ± 1%, 62.5 mW, 0402 [1005 Metric], Thick Film, General Purpose"
			(at 0 0 0)
			(layer "B.Fab")
			(hide yes)
			(effects
				(font
					(size 1.27 1.27)
					(thickness 0.15)
				)
				(justify mirror)
			)
		)
		(property "Manufacturer" "Bourns"
			(at 0 0 180)
			(unlocked yes)
			(layer "B.Fab")
			(hide yes)
			(effects
				(font
					(size 1 1)
					(thickness 0.15)
				)
				(justify mirror)
			)
		)
		(property "MPN" "CR0402-FX-1002GLF"
			(at 0 0 180)
			(unlocked yes)
			(layer "B.Fab")
			(hide yes)
			(effects
				(font
					(size 1 1)
					(thickness 0.15)
				)
				(justify mirror)
			)
		)
		(property "Val" "10k"
			(at 0 0 180)
			(unlocked yes)
			(layer "B.Fab")
			(hide yes)
			(effects
				(font
					(size 1 1)
					(thickness 0.15)
				)
				(justify mirror)
			)
		)
		(property "License" "Apache-2.0"
			(at 0 0 180)
			(unlocked yes)
			(layer "B.Fab")
			(hide yes)
			(effects
				(font
					(size 1 1)
					(thickness 0.15)
				)
				(justify mirror)
			)
		)
		(property "Author" "Antmicro"
			(at 0 0 180)
			(unlocked yes)
			(layer "B.Fab")
			(hide yes)
			(effects
				(font
					(size 1 1)
					(thickness 0.15)
				)
				(justify mirror)
			)
		)
		(property "Tolerance" "1%"
			(at 0 0 180)
			(unlocked yes)
			(layer "B.Fab")
			(hide yes)
			(effects
				(font
					(size 1 1)
					(thickness 0.15)
				)
				(justify mirror)
			)
		)
		(sheetname "/Recovery USB/")
		(sheetfile "recovery_usb.kicad_sch")
		(attr smd exclude_from_pos_files exclude_from_bom dnp)
		(fp_poly
			(pts
				(xy -0.925 0.47) (xy 0.925 0.47) (xy 0.925 -0.47) (xy -0.925 -0.47)
			)
			(stroke
				(width 0.05)
				(type default)
			)
			(fill no)
			(layer "B.CrtYd")
		)
		(fp_poly
			(pts
				(xy -0.5 0.25) (xy 0.5 0.25) (xy 0.5 -0.25) (xy -0.5 -0.25)
			)
			(stroke
				(width 0.15)
				(type solid)
			)
			(fill no)
			(layer "B.Fab")
		)
		(fp_text user "Author: Antmicro"
			(at -0.95 -4.169 0)
			(layer "B.Fab")
			(effects
				(font
					(size 0.7 0.7)
					(thickness 0.15)
				)
				(justify right top mirror)
			)
		)
		(fp_text user "License: Apache-2.0"
			(at -0.949999 -5.169 0)
			(layer "B.Fab")
			(effects
				(font
					(size 0.7 0.7)
					(thickness 0.15)
				)
				(justify right top mirror)
			)
		)
		(fp_text user "${REFERENCE}"
			(at -0.95 -3.168 0)
			(layer "B.Fab")
			(effects
				(font
					(size 0.7 0.7)
					(thickness 0.15)
				)
				(justify right top mirror)
			)
		)
		(pad "1" smd roundrect
			(at -0.48 0)
			(size 0.59 0.64)
			(layers "B.Cu" "B.Mask" "B.Paste")
			(roundrect_rratio 0.25)
			(net 5 "+5V")
			(pintype "passive")
		)
		(pad "2" smd roundrect
			(at 0.48 0)
			(size 0.59 0.64)
			(layers "B.Cu" "B.Mask" "B.Paste")
			(roundrect_rratio 0.25)
			(net 1012 "/Recovery USB/USBC2_PORT")
			(pintype "passive")
		)
	)
	(footprint "antmicro-footprints:LED_0603_1608Metric_G"
		(layer "B.Cu")
		(at 61.5 82.51)
		(descr "LED SMD 0603 Green")
		(tags "LED SMD 0603 Green")
		(property "Reference" "D29"
			(at -1.02 -2.6 0)
			(layer "B.SilkS")
			(effects
				(font
					(size 0.7 0.7)
					(thickness 0.15)
				)
				(justify right top mirror)
			)
		)
		(property "Value" "LED_G_0603_LTST-C190GKT"
			(at -0.001 -1.599 0)
			(layer "B.Fab")
			(effects
				(font
					(size 0.7 0.7)
					(thickness 0.15)
				)
				(justify right top mirror)
			)
		)
		(property "Datasheet" "https://media.digikey.com/pdf/Data%20Sheets/Lite-On%20PDFs/LTST-C190GKT.pdf"
			(at 0 0 0)
			(layer "B.Fab")
			(hide yes)
			(effects
				(font
					(size 1.27 1.27)
					(thickness 0.15)
				)
				(justify mirror)
			)
		)
		(property "Description" "LED, Green, SMD, 0603, 20 mA, 2.1 V, 569 nm"
			(at 0 0 0)
			(layer "B.Fab")
			(hide yes)
			(effects
				(font
					(size 1.27 1.27)
					(thickness 0.15)
				)
				(justify mirror)
			)
		)
		(property "MPN" "LTST-C190GKT"
			(at 0 0 180)
			(unlocked yes)
			(layer "B.Fab")
			(hide yes)
			(effects
				(font
					(size 1 1)
					(thickness 0.15)
				)
				(justify mirror)
			)
		)
		(property "Manufacturer" "Lite-On"
			(at 0 0 180)
			(unlocked yes)
			(layer "B.Fab")
			(hide yes)
			(effects
				(font
					(size 1 1)
					(thickness 0.15)
				)
				(justify mirror)
			)
		)
		(property "Author" "Antmicro"
			(at 0 0 180)
			(unlocked yes)
			(layer "B.Fab")
			(hide yes)
			(effects
				(font
					(size 1 1)
					(thickness 0.15)
				)
				(justify mirror)
			)
		)
		(property "License" "Apache-2.0"
			(at 0 0 180)
			(unlocked yes)
			(layer "B.Fab")
			(hide yes)
			(effects
				(font
					(size 1 1)
					(thickness 0.15)
				)
				(justify mirror)
			)
		)
		(property "Color" "Green"
			(at 0 0 180)
			(unlocked yes)
			(layer "B.Fab")
			(hide yes)
			(effects
				(font
					(size 1 1)
					(thickness 0.15)
				)
				(justify mirror)
			)
		)
		(sheetname "/CSI/")
		(sheetfile "csi.kicad_sch")
		(attr smd)
		(fp_line
			(start -1.18 0.319)
			(end -1.18 -0.321)
			(stroke
				(width 0.15)
				(type solid)
			)
			(layer "B.SilkS")
		)
		(fp_line
			(start -0.094672 -0.201008)
			(end -0.094672 0.198992)
			(stroke
				(width 0.1)
				(type solid)
			)
			(layer "B.SilkS")
		)
		(fp_line
			(start -0.094672 -0.001008)
			(end -0.24 -0.001008)
			(stroke
				(width 0.1)
				(type solid)
			)
			(layer "B.SilkS")
		)
		(fp_line
			(start -0.094672 -0.001008)
			(end 0.105328 0.198992)
			(stroke
				(width 0.1)
				(type solid)
			)
			(layer "B.SilkS")
		)
		(fp_line
			(start 0.105328 -0.201008)
			(end -0.094672 -0.001008)
			(stroke
				(width 0.1)
				(type solid)
			)
			(layer "B.SilkS")
		)
		(fp_line
			(start 0.105328 -0.201008)
			(end 0.105328 0.198992)
			(stroke
				(width 0.1)
				(type solid)
			)
			(layer "B.SilkS")
		)
		(fp_line
			(start 0.105328 -0.001008)
			(end 0.24 -0.001)
			(stroke
				(width 0.1)
				(type solid)
			)
			(layer "B.SilkS")
		)
		(fp_line
			(start 0.22 -0.35)
			(end -0.22 -0.35)
			(stroke
				(width 0.15)
				(type solid)
			)
			(layer "B.SilkS")
		)
		(fp_line
			(start 0.22 0.35)
			(end -0.22 0.35)
			(stroke
				(width 0.15)
				(type solid)
			)
			(layer "B.SilkS")
		)
		(fp_rect
			(start 1.25 -0.65)
			(end -1.25 0.65)
			(stroke
				(width 0.05)
				(type solid)
			)
			(fill no)
			(layer "B.CrtYd")
		)
		(fp_line
			(start -0.199 -0.2)
			(end -0.199 -0.1)
			(stroke
				(width 0.15)
				(type solid)
			)
			(layer "B.Fab")
		)
		(fp_line
			(start -0.199 0)
			(end -0.597 0)
			(stroke
				(width 0.15)
				(type solid)
			)
			(layer "B.Fab")
		)
		(fp_line
			(start -0.199 0.202)
			(end -0.199 -0.1)
			(stroke
				(width 0.15)
				(type solid)
			)
			(layer "B.Fab")
		)
		(fp_line
			(start -0.101 0)
			(end 0.201 -0.2)
			(stroke
				(width 0.15)
				(type solid)
			)
			(layer "B.Fab")
		)
		(fp_line
			(start 0.201 -0.2)
			(end 0.201 0)
			(stroke
				(width 0.15)
				(type solid)
			)
			(layer "B.Fab")
		)
		(fp_line
			(start 0.201 0)
			(end 0.201 0.202)
			(stroke
				(width 0.15)
				(type solid)
			)
			(layer "B.Fab")
		)
		(fp_line
			(start 0.201 0.202)
			(end -0.101 0)
			(stroke
				(width 0.15)
				(type solid)
			)
			(layer "B.Fab")
		)
		(fp_line
			(start 0.599 0)
			(end 0.201 0)
			(stroke
				(width 0.15)
				(type solid)
			)
			(layer "B.Fab")
		)
		(fp_rect
			(start 0.848 -0.4)
			(end -0.85 0.402)
			(stroke
				(width 0.15)
				(type solid)
			)
			(fill no)
			(layer "B.Fab")
		)
		(fp_text user "${REFERENCE}"
			(at -1.4224 -5.999 0)
			(layer "B.Fab")
			(effects
				(font
					(size 0.7 0.7)
					(thickness 0.15)
				)
				(justify right top mirror)
			)
		)
		(fp_text user "License: Apache-2.0"
			(at -1.4224 -3.599 0)
			(layer "B.Fab")
			(effects
				(font
					(size 0.7 0.7)
					(thickness 0.15)
				)
				(justify right top mirror)
			)
		)
		(fp_text user "Author: Antmicro"
			(at -1.4224 -4.799 0)
			(layer "B.Fab")
			(effects
				(font
					(size 0.7 0.7)
					(thickness 0.15)
				)
				(justify right top mirror)
			)
		)
		(pad "1" smd roundrect
			(at -0.7 0 180)
			(size 0.8 1)
			(layers "B.Cu" "B.Mask" "B.Paste")
			(roundrect_rratio 0.2)
			(net 1 "GND")
			(pinfunction "C")
			(pintype "passive")
		)
		(pad "2" smd roundrect
			(at 0.7 0 180)
			(size 0.8 1)
			(layers "B.Cu" "B.Mask" "B.Paste")
			(roundrect_rratio 0.2)
			(net 542 "Net-(D29-A)")
			(pinfunction "A")
			(pintype "passive")
		)
	)
	(footprint "antmicro-footprints:R_0402_1005Metric"
		(layer "B.Cu")
		(at 197 87.8 90)
		(descr "Resistor SMD 0402")
		(tags "resistor SMD 0402")
		(property "Reference" "R381"
			(at -3.7 -0.4 90)
			(layer "B.SilkS")
			(effects
				(font
					(size 0.7 0.7)
					(thickness 0.15)
				)
				(justify right top mirror)
			)
		)
		(property "Value" "R_0R_0402"
			(at -1.011843 -1.772047 90)
			(layer "B.Fab")
			(effects
				(font
					(size 0.7 0.7)
					(thickness 0.15)
				)
				(justify right top mirror)
			)
		)
		(property "Datasheet" "https://industrial.panasonic.com/cdbs/www-data/pdf/RDA0000/AOA0000C301.pdf"
			(at 0 0 90)
			(layer "B.Fab")
			(hide yes)
			(effects
				(font
					(size 1.27 1.27)
					(thickness 0.15)
				)
				(justify mirror)
			)
		)
		(property "Description" "SMD Chip Resistor, Jumper, 0 ohm, 100 mW, 0402 [1005 Metric], Thick Film, General Purpose"
			(at 0 0 90)
			(layer "B.Fab")
			(hide yes)
			(effects
				(font
					(size 1.27 1.27)
					(thickness 0.15)
				)
				(justify mirror)
			)
		)
		(property "MPN" "ERJ2GE0R00X"
			(at 0 0 270)
			(unlocked yes)
			(layer "B.Fab")
			(hide yes)
			(effects
				(font
					(size 1 1)
					(thickness 0.15)
				)
				(justify mirror)
			)
		)
		(property "Manufacturer" "Panasonic"
			(at 0 0 270)
			(unlocked yes)
			(layer "B.Fab")
			(hide yes)
			(effects
				(font
					(size 1 1)
					(thickness 0.15)
				)
				(justify mirror)
			)
		)
		(property "License" "Apache-2.0"
			(at 0 0 270)
			(unlocked yes)
			(layer "B.Fab")
			(hide yes)
			(effects
				(font
					(size 1 1)
					(thickness 0.15)
				)
				(justify mirror)
			)
		)
		(property "Author" "Antmicro"
			(at 0 0 270)
			(unlocked yes)
			(layer "B.Fab")
			(hide yes)
			(effects
				(font
					(size 1 1)
					(thickness 0.15)
				)
				(justify mirror)
			)
		)
		(property "Val" "0R"
			(at 0 0 270)
			(unlocked yes)
			(layer "B.Fab")
			(hide yes)
			(effects
				(font
					(size 1 1)
					(thickness 0.15)
				)
				(justify mirror)
			)
		)
		(property "Tolerance" "~"
			(at 0 0 270)
			(unlocked yes)
			(layer "B.Fab")
			(hide yes)
			(effects
				(font
					(size 1 1)
					(thickness 0.15)
				)
				(justify mirror)
			)
		)
		(property "Current" "1A"
			(at 0 0 270)
			(unlocked yes)
			(layer "B.Fab")
			(hide yes)
			(effects
				(font
					(size 1 1)
					(thickness 0.15)
				)
				(justify mirror)
			)
		)
		(sheetname "/USB Debug, PD/")
		(sheetfile "usb_debug_pd.kicad_sch")
		(attr smd)
		(fp_rect
			(start -0.925 0.47)
			(end 0.925 -0.47)
			(stroke
				(width 0.05)
				(type default)
			)
			(fill no)
			(layer "B.CrtYd")
		)
		(fp_rect
			(start -0.5 0.25)
			(end 0.5 -0.25)
			(stroke
				(width 0.15)
				(type solid)
			)
			(fill no)
			(layer "B.Fab")
		)
		(fp_text user "${REFERENCE}"
			(at -0.95 -3.168 90)
			(layer "B.Fab")
			(effects
				(font
					(size 0.7 0.7)
					(thickness 0.15)
				)
				(justify right top mirror)
			)
		)
		(fp_text user "Author: Antmicro"
			(at -0.95 -4.169 90)
			(layer "B.Fab")
			(effects
				(font
					(size 0.7 0.7)
					(thickness 0.15)
				)
				(justify right top mirror)
			)
		)
		(fp_text user "License: Apache-2.0"
			(at -0.95 -5.169 90)
			(layer "B.Fab")
			(effects
				(font
					(size 0.7 0.7)
					(thickness 0.15)
				)
				(justify right top mirror)
			)
		)
		(pad "1" smd roundrect
			(at -0.48 0 90)
			(size 0.59 0.64)
			(layers "B.Cu" "B.Mask" "B.Paste")
			(roundrect_rratio 0.25)
			(net 812 "/USB Debug, PD/~{CS}")
			(pintype "passive")
		)
		(pad "2" smd roundrect
			(at 0.48 0 90)
			(size 0.59 0.64)
			(layers "B.Cu" "B.Mask" "B.Paste")
			(roundrect_rratio 0.25)
			(net 939 "/USB Debug, PD/~{PDC_CS}")
			(pintype "passive")
		)
	)
	(footprint "antmicro-footprints:R_0402_1005Metric"
		(layer "B.Cu")
		(at 235.694 108.825 180)
		(descr "Resistor SMD 0402")
		(tags "resistor SMD 0402")
		(property "Reference" "R270"
			(at 0.094 -4.475 0)
			(layer "B.SilkS")
			(effects
				(font
					(size 0.7 0.7)
					(thickness 0.15)
				)
				(justify left bottom mirror)
			)
		)
		(property "Value" "R_2k2_0402"
			(at -1.011843 -1.772046 0)
			(layer "B.Fab")
			(effects
				(font
					(size 0.7 0.7)
					(thickness 0.15)
				)
				(justify left bottom mirror)
			)
		)
		(property "Datasheet" "https://www.bourns.com/docs/product-datasheets/cr.pdf"
			(at 0 0 0)
			(layer "B.Fab")
			(hide yes)
			(effects
				(font
					(size 1.27 1.27)
					(thickness 0.15)
				)
				(justify mirror)
			)
		)
		(property "Description" "SMD Chip Resistor, 2.2 kohm, ± 1%, 62.5 mW, 0402 [1005 Metric], Thick Film, General Purpose"
			(at 0 0 0)
			(layer "B.Fab")
			(hide yes)
			(effects
				(font
					(size 1.27 1.27)
					(thickness 0.15)
				)
				(justify mirror)
			)
		)
		(property "Manufacturer" "Bourns"
			(at 0 0 0)
			(unlocked yes)
			(layer "B.Fab")
			(hide yes)
			(effects
				(font
					(size 1 1)
					(thickness 0.15)
				)
				(justify mirror)
			)
		)
		(property "MPN" "CR0402-FX-2201GLF"
			(at 0 0 0)
			(unlocked yes)
			(layer "B.Fab")
			(hide yes)
			(effects
				(font
					(size 1 1)
					(thickness 0.15)
				)
				(justify mirror)
			)
		)
		(property "Val" "2k2"
			(at 0 0 0)
			(unlocked yes)
			(layer "B.Fab")
			(hide yes)
			(effects
				(font
					(size 1 1)
					(thickness 0.15)
				)
				(justify mirror)
			)
		)
		(property "License" "Apache-2.0"
			(at 0 0 0)
			(unlocked yes)
			(layer "B.Fab")
			(hide yes)
			(effects
				(font
					(size 1 1)
					(thickness 0.15)
				)
				(justify mirror)
			)
		)
		(property "Author" "Antmicro"
			(at 0 0 0)
			(unlocked yes)
			(layer "B.Fab")
			(hide yes)
			(effects
				(font
					(size 1 1)
					(thickness 0.15)
				)
				(justify mirror)
			)
		)
		(property "Tolerance" "1%"
			(at 0 0 0)
			(unlocked yes)
			(layer "B.Fab")
			(hide yes)
			(effects
				(font
					(size 1 1)
					(thickness 0.15)
				)
				(justify mirror)
			)
		)
		(sheetname "/Recovery USB/")
		(sheetfile "recovery_usb.kicad_sch")
		(attr smd)
		(fp_poly
			(pts
				(xy -0.925 0.47) (xy -0.925 -0.47) (xy 0.925 -0.47) (xy 0.925 0.47)
			)
			(stroke
				(width 0.05)
				(type default)
			)
			(fill no)
			(layer "B.CrtYd")
		)
		(fp_poly
			(pts
				(xy -0.5 0.25) (xy -0.5 -0.25) (xy 0.5 -0.25) (xy 0.5 0.25)
			)
			(stroke
				(width 0.15)
				(type solid)
			)
			(fill no)
			(layer "B.Fab")
		)
		(fp_text user "License: Apache-2.0"
			(at -0.949999 -5.169 0)
			(layer "B.Fab")
			(effects
				(font
					(size 0.7 0.7)
					(thickness 0.15)
				)
				(justify left bottom mirror)
			)
		)
		(fp_text user "Author: Antmicro"
			(at -0.95 -4.169 0)
			(layer "B.Fab")
			(effects
				(font
					(size 0.7 0.7)
					(thickness 0.15)
				)
				(justify left bottom mirror)
			)
		)
		(fp_text user "${REFERENCE}"
			(at -0.95 -3.168 0)
			(layer "B.Fab")
			(effects
				(font
					(size 0.7 0.7)
					(thickness 0.15)
				)
				(justify left bottom mirror)
			)
		)
		(pad "1" smd roundrect
			(at -0.48 0 180)
			(size 0.59 0.64)
			(layers "B.Cu" "B.Mask" "B.Paste")
			(roundrect_rratio 0.25)
			(net 1 "GND")
			(pintype "passive")
		)
		(pad "2" smd roundrect
			(at 0.48 0 180)
			(size 0.59 0.64)
			(layers "B.Cu" "B.Mask" "B.Paste")
			(roundrect_rratio 0.25)
			(net 1020 "/Recovery USB/USBC2_ISET")
			(pintype "passive")
		)
	)
	(footprint "antmicro-footprints:TP_SMD_0.75mm"
		(layer "B.Cu")
		(at 85.25 58.55 180)
		(property "Reference" "TP120"
			(at 0.56 -0.44 180)
			(layer "B.SilkS")
			(effects
				(font
					(size 0.7 0.7)
					(thickness 0.15)
				)
				(justify left bottom mirror)
			)
		)
		(property "Value" "TP_0.75mm_SMD"
			(at 0 -1.2 0)
			(layer "B.Fab")
			(effects
				(font
					(size 0.7 0.7)
					(thickness 0.15)
				)
				(justify left bottom mirror)
			)
		)
		(property "Description" "SMT test point"
			(at 0 0 0)
			(layer "B.Fab")
			(hide yes)
			(effects
				(font
					(size 1.27 1.27)
					(thickness 0.15)
				)
				(justify mirror)
			)
		)
		(property "MPN" ""
			(at 0 0 0)
			(unlocked yes)
			(layer "B.Fab")
			(hide yes)
			(effects
				(font
					(size 1 1)
					(thickness 0.15)
				)
				(justify mirror)
			)
		)
		(property "Manufacturer" ""
			(at 0 0 0)
			(unlocked yes)
			(layer "B.Fab")
			(hide yes)
			(effects
				(font
					(size 1 1)
					(thickness 0.15)
				)
				(justify mirror)
			)
		)
		(property "Author" "Antmicro"
			(at 0 0 0)
			(unlocked yes)
			(layer "B.Fab")
			(hide yes)
			(effects
				(font
					(size 1 1)
					(thickness 0.15)
				)
				(justify mirror)
			)
		)
		(property "License" "Apache-2.0"
			(at 0 0 0)
			(unlocked yes)
			(layer "B.Fab")
			(hide yes)
			(effects
				(font
					(size 1 1)
					(thickness 0.15)
				)
				(justify mirror)
			)
		)
		(sheetname "/SoM_Power/")
		(sheetfile "som_power.kicad_sch")
		(attr exclude_from_pos_files exclude_from_bom)
		(fp_circle
			(center 0 0)
			(end 0.475 0)
			(stroke
				(width 0.05)
				(type default)
			)
			(fill no)
			(layer "B.CrtYd")
		)
		(fp_text user "Author: Antmicro"
			(at -0.4 -3.901 0)
			(layer "B.Fab")
			(effects
				(font
					(size 0.7 0.7)
					(thickness 0.15)
				)
				(justify left bottom mirror)
			)
		)
		(fp_text user "${REFERENCE}"
			(at -0.4 -2.7 0)
			(layer "B.Fab")
			(effects
				(font
					(size 0.7 0.7)
					(thickness 0.15)
				)
				(justify left bottom mirror)
			)
		)
		(fp_text user "License: Apache-2.0"
			(at -0.4 -5.101 0)
			(layer "B.Fab")
			(effects
				(font
					(size 0.7 0.7)
					(thickness 0.15)
				)
				(justify left bottom mirror)
			)
		)
		(pad "1" smd circle
			(at 0 0 180)
			(size 0.75 0.75)
			(layers "B.Cu" "B.Mask")
			(net 1382 "Net-(R300-Pad2)")
			(pinfunction "1")
			(pintype "passive")
		)
	)
	(footprint "antmicro-footprints:C_0402_1005Metric"
		(layer "B.Cu")
		(at 215.026 152.2 180)
		(descr "Capacitor SMD 0402")
		(tags "capacitor SMD 0402")
		(property "Reference" "C175"
			(at -1.6 0.81 0)
			(layer "B.SilkS")
			(effects
				(font
					(size 0.7 0.7)
					(thickness 0.15)
				)
				(justify left bottom mirror)
			)
		)
		(property "Value" "C_100n_0402"
			(at -1.022927 -2.155213 0)
			(layer "B.Fab")
			(effects
				(font
					(size 0.7 0.7)
					(thickness 0.15)
				)
				(justify left bottom mirror)
			)
		)
		(property "Datasheet" "https://www.murata.com/products/productdetail?partno=GRM155R61H104KE14%23"
			(at 0 0 0)
			(layer "B.Fab")
			(hide yes)
			(effects
				(font
					(size 1.27 1.27)
					(thickness 0.15)
				)
				(justify mirror)
			)
		)
		(property "Description" "SMD Multilayer Ceramic Capacitor, 0.1 µF, 50 V, 0402 [1005 Metric], ± 10%, X5R, GRM Series"
			(at 0 0 0)
			(layer "B.Fab")
			(hide yes)
			(effects
				(font
					(size 1.27 1.27)
					(thickness 0.15)
				)
				(justify mirror)
			)
		)
		(property "MPN" "GRM155R61H104KE14D"
			(at 0 0 0)
			(unlocked yes)
			(layer "B.Fab")
			(hide yes)
			(effects
				(font
					(size 1 1)
					(thickness 0.15)
				)
				(justify mirror)
			)
		)
		(property "Manufacturer" "Murata"
			(at 0 0 0)
			(unlocked yes)
			(layer "B.Fab")
			(hide yes)
			(effects
				(font
					(size 1 1)
					(thickness 0.15)
				)
				(justify mirror)
			)
		)
		(property "License" "Apache-2.0"
			(at 0 0 0)
			(unlocked yes)
			(layer "B.Fab")
			(hide yes)
			(effects
				(font
					(size 1 1)
					(thickness 0.15)
				)
				(justify mirror)
			)
		)
		(property "Author" "Antmicro"
			(at 0 0 0)
			(unlocked yes)
			(layer "B.Fab")
			(hide yes)
			(effects
				(font
					(size 1 1)
					(thickness 0.15)
				)
				(justify mirror)
			)
		)
		(property "Val" "100n"
			(at 0 0 0)
			(unlocked yes)
			(layer "B.Fab")
			(hide yes)
			(effects
				(font
					(size 1 1)
					(thickness 0.15)
				)
				(justify mirror)
			)
		)
		(property "Voltage" "50V"
			(at 0 0 0)
			(unlocked yes)
			(layer "B.Fab")
			(hide yes)
			(effects
				(font
					(size 1 1)
					(thickness 0.15)
				)
				(justify mirror)
			)
		)
		(property "Dielectric" "X5R"
			(at 0 0 0)
			(unlocked yes)
			(layer "B.Fab")
			(hide yes)
			(effects
				(font
					(size 1 1)
					(thickness 0.15)
				)
				(justify mirror)
			)
		)
		(sheetname "/SFP/")
		(sheetfile "sfp.kicad_sch")
		(attr smd)
		(fp_poly
			(pts
				(xy -0.925 0.47) (xy -0.925 -0.47) (xy 0.925 -0.47) (xy 0.925 0.47)
			)
			(stroke
				(width 0.05)
				(type default)
			)
			(fill no)
			(layer "B.CrtYd")
		)
		(fp_line
			(start 0.504 0.25)
			(end 0.504 -0.248)
			(stroke
				(width 0.15)
				(type solid)
			)
			(layer "B.Fab")
		)
		(fp_line
			(start 0.504 -0.248)
			(end -0.494 -0.248)
			(stroke
				(width 0.15)
				(type solid)
			)
			(layer "B.Fab")
		)
		(fp_line
			(start -0.494 0.25)
			(end 0.504 0.25)
			(stroke
				(width 0.15)
				(type solid)
			)
			(layer "B.Fab")
		)
		(fp_line
			(start -0.494 -0.248)
			(end -0.494 0.25)
			(stroke
				(width 0.15)
				(type solid)
			)
			(layer "B.Fab")
		)
		(fp_text user "License: Apache-2.0"
			(at -0.939 -5.799 0)
			(layer "B.Fab")
			(effects
				(font
					(size 0.7 0.7)
					(thickness 0.15)
				)
				(justify left bottom mirror)
			)
		)
		(fp_text user "${REFERENCE}"
			(at -0.939 -4.599 0)
			(layer "B.Fab")
			(effects
				(font
					(size 0.7 0.7)
					(thickness 0.15)
				)
				(justify left bottom mirror)
			)
		)
		(fp_text user "Author: Antmicro"
			(at -0.939 -3.399 0)
			(layer "B.Fab")
			(effects
				(font
					(size 0.7 0.7)
					(thickness 0.15)
				)
				(justify left bottom mirror)
			)
		)
		(pad "1" smd roundrect
			(at -0.48 0 180)
			(size 0.59 0.64)
			(layers "B.Cu" "B.Mask" "B.Paste")
			(roundrect_rratio 0.25)
			(net 1 "GND")
			(pintype "passive")
		)
		(pad "2" smd roundrect
			(at 0.48 0 180)
			(size 0.59 0.64)
			(layers "B.Cu" "B.Mask" "B.Paste")
			(roundrect_rratio 0.25)
			(net 379 "/SFP/SH")
			(pintype "passive")
		)
	)
	(footprint "antmicro-footprints:TP_SMD_0.75mm"
		(layer "B.Cu")
		(at 233 89.2 180)
		(property "Reference" "TP20"
			(at -3 0.5 0)
			(layer "B.SilkS")
			(effects
				(font
					(size 0.7 0.7)
					(thickness 0.15)
				)
				(justify left bottom mirror)
			)
		)
		(property "Value" "TP_0.75mm_SMD"
			(at 0 -1.2 0)
			(layer "B.Fab")
			(effects
				(font
					(size 0.7 0.7)
					(thickness 0.15)
				)
				(justify left bottom mirror)
			)
		)
		(property "Description" "SMT test point"
			(at 0 0 0)
			(layer "B.Fab")
			(hide yes)
			(effects
				(font
					(size 1.27 1.27)
					(thickness 0.15)
				)
				(justify mirror)
			)
		)
		(property "MPN" ""
			(at 0 0 0)
			(unlocked yes)
			(layer "B.Fab")
			(hide yes)
			(effects
				(font
					(size 1 1)
					(thickness 0.15)
				)
				(justify mirror)
			)
		)
		(property "Manufacturer" ""
			(at 0 0 0)
			(unlocked yes)
			(layer "B.Fab")
			(hide yes)
			(effects
				(font
					(size 1 1)
					(thickness 0.15)
				)
				(justify mirror)
			)
		)
		(property "Author" "Antmicro"
			(at 0 0 0)
			(unlocked yes)
			(layer "B.Fab")
			(hide yes)
			(effects
				(font
					(size 1 1)
					(thickness 0.15)
				)
				(justify mirror)
			)
		)
		(property "License" "Apache-2.0"
			(at 0 0 0)
			(unlocked yes)
			(layer "B.Fab")
			(hide yes)
			(effects
				(font
					(size 1 1)
					(thickness 0.15)
				)
				(justify mirror)
			)
		)
		(sheetname "/USB DP Alt mode/")
		(sheetfile "usb_dp.kicad_sch")
		(attr exclude_from_pos_files exclude_from_bom)
		(fp_circle
			(center 0 0)
			(end 0.475 0)
			(stroke
				(width 0.05)
				(type default)
			)
			(fill no)
			(layer "B.CrtYd")
		)
		(fp_text user "${REFERENCE}"
			(at -0.4 -2.7 0)
			(layer "B.Fab")
			(effects
				(font
					(size 0.7 0.7)
					(thickness 0.15)
				)
				(justify left bottom mirror)
			)
		)
		(fp_text user "License: Apache-2.0"
			(at -0.4 -5.101 0)
			(layer "B.Fab")
			(effects
				(font
					(size 0.7 0.7)
					(thickness 0.15)
				)
				(justify left bottom mirror)
			)
		)
		(fp_text user "Author: Antmicro"
			(at -0.4 -3.901 0)
			(layer "B.Fab")
			(effects
				(font
					(size 0.7 0.7)
					(thickness 0.15)
				)
				(justify left bottom mirror)
			)
		)
		(pad "1" smd circle
			(at 0 0 180)
			(size 0.75 0.75)
			(layers "B.Cu" "B.Mask")
			(net 376 "/USB DP Alt mode/USBC1_VBUS")
			(pinfunction "1")
			(pintype "passive")
		)
	)
	(footprint "antmicro-footprints:R_0402_1005Metric"
		(layer "B.Cu")
		(at 221.3 95.392 180)
		(descr "Resistor SMD 0402")
		(tags "resistor SMD 0402")
		(property "Reference" "R272"
			(at -1.122484 0.592 0)
			(layer "B.SilkS")
			(effects
				(font
					(size 0.7 0.7)
					(thickness 0.15)
				)
				(justify left bottom mirror)
			)
		)
		(property "Value" "R_100k_0402"
			(at -1.011843 -1.772047 0)
			(layer "B.Fab")
			(effects
				(font
					(size 0.7 0.7)
					(thickness 0.15)
				)
				(justify left bottom mirror)
			)
		)
		(property "Datasheet" "https://www.bourns.com/docs/product-datasheets/cr.pdf"
			(at 0 0 0)
			(layer "B.Fab")
			(hide yes)
			(effects
				(font
					(size 1.27 1.27)
					(thickness 0.15)
				)
				(justify mirror)
			)
		)
		(property "Description" "SMD Chip Resistor, 100 kohm, ± 1%, 62.5 mW, 0402 [1005 Metric], Thick Film, General Purpose"
			(at 0 0 0)
			(layer "B.Fab")
			(hide yes)
			(effects
				(font
					(size 1.27 1.27)
					(thickness 0.15)
				)
				(justify mirror)
			)
		)
		(property "Manufacturer" "Bourns"
			(at 0 0 0)
			(unlocked yes)
			(layer "B.Fab")
			(hide yes)
			(effects
				(font
					(size 1 1)
					(thickness 0.15)
				)
				(justify mirror)
			)
		)
		(property "MPN" "CR0402-FX-1003GLF"
			(at 0 0 0)
			(unlocked yes)
			(layer "B.Fab")
			(hide yes)
			(effects
				(font
					(size 1 1)
					(thickness 0.15)
				)
				(justify mirror)
			)
		)
		(property "Val" "100k"
			(at 0 0 0)
			(unlocked yes)
			(layer "B.Fab")
			(hide yes)
			(effects
				(font
					(size 1 1)
					(thickness 0.15)
				)
				(justify mirror)
			)
		)
		(property "License" "Apache-2.0"
			(at 0 0 0)
			(unlocked yes)
			(layer "B.Fab")
			(hide yes)
			(effects
				(font
					(size 1 1)
					(thickness 0.15)
				)
				(justify mirror)
			)
		)
		(property "Author" "Antmicro"
			(at 0 0 0)
			(unlocked yes)
			(layer "B.Fab")
			(hide yes)
			(effects
				(font
					(size 1 1)
					(thickness 0.15)
				)
				(justify mirror)
			)
		)
		(property "Tolerance" "1%"
			(at 0 0 0)
			(unlocked yes)
			(layer "B.Fab")
			(hide yes)
			(effects
				(font
					(size 1 1)
					(thickness 0.15)
				)
				(justify mirror)
			)
		)
		(sheetname "/USB DP Alt mode/")
		(sheetfile "usb_dp.kicad_sch")
		(attr smd)
		(fp_rect
			(start -0.925 0.47)
			(end 0.925 -0.47)
			(stroke
				(width 0.05)
				(type default)
			)
			(fill no)
			(layer "B.CrtYd")
		)
		(fp_rect
			(start -0.5 0.25)
			(end 0.5 -0.25)
			(stroke
				(width 0.15)
				(type solid)
			)
			(fill no)
			(layer "B.Fab")
		)
		(fp_text user "License: Apache-2.0"
			(at -0.95 -5.169 0)
			(layer "B.Fab")
			(effects
				(font
					(size 0.7 0.7)
					(thickness 0.15)
				)
				(justify left bottom mirror)
			)
		)
		(fp_text user "${REFERENCE}"
			(at -0.95 -3.168 0)
			(layer "B.Fab")
			(effects
				(font
					(size 0.7 0.7)
					(thickness 0.15)
				)
				(justify left bottom mirror)
			)
		)
		(fp_text user "Author: Antmicro"
			(at -0.95 -4.169 0)
			(layer "B.Fab")
			(effects
				(font
					(size 0.7 0.7)
					(thickness 0.15)
				)
				(justify left bottom mirror)
			)
		)
		(pad "1" smd roundrect
			(at -0.48 0 180)
			(size 0.59 0.64)
			(layers "B.Cu" "B.Mask" "B.Paste")
			(roundrect_rratio 0.25)
			(net 957 "/USB DP Alt mode/HPDIN")
			(pintype "passive")
		)
		(pad "2" smd roundrect
			(at 0.48 0 180)
			(size 0.59 0.64)
			(layers "B.Cu" "B.Mask" "B.Paste")
			(roundrect_rratio 0.25)
			(net 1 "GND")
			(pintype "passive")
		)
	)
	(footprint "antmicro-footprints:C_0603_1608Metric_EIA"
		(layer "B.Cu")
		(at 107.08 69.48 180)
		(descr "Capacitor SMD 0603, IPC-7351 Density Level A")
		(tags "Capacitor 0603")
		(property "Reference" "C7"
			(at -0.92 0.88 0)
			(layer "B.SilkS")
			(effects
				(font
					(size 0.7 0.7)
					(thickness 0.15)
				)
				(justify left bottom mirror)
			)
		)
		(property "Value" "C_22u_16V_0603"
			(at -1.42757 -1.770288 0)
			(layer "B.Fab")
			(effects
				(font
					(size 0.7 0.7)
					(thickness 0.15)
				)
				(justify left bottom mirror)
			)
		)
		(property "Datasheet" "https://product.samsungsem.com/mlcc/CL10A226MO7JZN.do"
			(at 0 0 0)
			(layer "B.Fab")
			(hide yes)
			(effects
				(font
					(size 1.27 1.27)
					(thickness 0.15)
				)
				(justify mirror)
			)
		)
		(property "Description" "SMD Multilayer Ceramic Capacitor"
			(at 0 0 0)
			(layer "B.Fab")
			(hide yes)
			(effects
				(font
					(size 1.27 1.27)
					(thickness 0.15)
				)
				(justify mirror)
			)
		)
		(property "MPN" "CL10A226MO7JZNC"
			(at 0 0 0)
			(unlocked yes)
			(layer "B.Fab")
			(hide yes)
			(effects
				(font
					(size 1 1)
					(thickness 0.15)
				)
				(justify mirror)
			)
		)
		(property "Manufacturer" "Samsung Electro-Mechanics"
			(at 0 0 0)
			(unlocked yes)
			(layer "B.Fab")
			(hide yes)
			(effects
				(font
					(size 1 1)
					(thickness 0.15)
				)
				(justify mirror)
			)
		)
		(property "License" "Apache-2.0"
			(at 0 0 0)
			(unlocked yes)
			(layer "B.Fab")
			(hide yes)
			(effects
				(font
					(size 1 1)
					(thickness 0.15)
				)
				(justify mirror)
			)
		)
		(property "Author" "Antmicro"
			(at 0 0 0)
			(unlocked yes)
			(layer "B.Fab")
			(hide yes)
			(effects
				(font
					(size 1 1)
					(thickness 0.15)
				)
				(justify mirror)
			)
		)
		(property "Val" "22u"
			(at 0 0 0)
			(unlocked yes)
			(layer "B.Fab")
			(hide yes)
			(effects
				(font
					(size 1 1)
					(thickness 0.15)
				)
				(justify mirror)
			)
		)
		(property "Voltage" "16V"
			(at 0 0 0)
			(unlocked yes)
			(layer "B.Fab")
			(hide yes)
			(effects
				(font
					(size 1 1)
					(thickness 0.15)
				)
				(justify mirror)
			)
		)
		(property "Dielectric" "X7R"
			(at 0 0 0)
			(unlocked yes)
			(layer "B.Fab")
			(hide yes)
			(effects
				(font
					(size 1 1)
					(thickness 0.15)
				)
				(justify mirror)
			)
		)
		(property "Public" "False"
			(at 0 0 0)
			(unlocked yes)
			(layer "B.Fab")
			(hide yes)
			(effects
				(font
					(size 1 1)
					(thickness 0.15)
				)
				(justify mirror)
			)
		)
		(sheetname "/SoM_Power/")
		(sheetfile "som_power.kicad_sch")
		(attr smd)
		(fp_line
			(start -0.15 0.55)
			(end 0.15 0.55)
			(stroke
				(width 0.15)
				(type solid)
			)
			(layer "B.SilkS")
		)
		(fp_line
			(start -0.15 -0.55)
			(end 0.15 -0.55)
			(stroke
				(width 0.15)
				(type solid)
			)
			(layer "B.SilkS")
		)
		(fp_rect
			(start -1.25 0.65)
			(end 1.25 -0.65)
			(stroke
				(width 0.05)
				(type solid)
			)
			(fill no)
			(layer "B.CrtYd")
		)
		(fp_rect
			(start -0.8 0.45)
			(end 0.8 -0.45)
			(stroke
				(width 0.15)
				(type solid)
			)
			(fill no)
			(layer "B.Fab")
		)
		(fp_text user "${REFERENCE}"
			(at -1.682 -3.895 0)
			(layer "B.Fab")
			(effects
				(font
					(size 0.7 0.7)
					(thickness 0.15)
				)
				(justify left bottom mirror)
			)
		)
		(fp_text user "Author: Antmicro"
			(at -1.682 -4.894 0)
			(layer "B.Fab")
			(effects
				(font
					(size 0.7 0.7)
					(thickness 0.15)
				)
				(justify left bottom mirror)
			)
		)
		(fp_text user "License: Apache-2.0"
			(at -1.682 -5.895 0)
			(layer "B.Fab")
			(effects
				(font
					(size 0.7 0.7)
					(thickness 0.15)
				)
				(justify left bottom mirror)
			)
		)
		(pad "1" smd roundrect
			(at -0.7 0 180)
			(size 0.8 1.1)
			(layers "B.Cu" "B.Mask" "B.Paste")
			(roundrect_rratio 0.2)
			(net 1 "GND")
			(pintype "passive")
		)
		(pad "2" smd roundrect
			(at 0.7 0 180)
			(size 0.8 1.1)
			(layers "B.Cu" "B.Mask" "B.Paste")
			(roundrect_rratio 0.2)
			(net 213 "+5V_SOM")
			(pintype "passive")
		)
	)
	(footprint "antmicro-footprints:R_0402_1005Metric"
		(layer "B.Cu")
		(at 212.8 91.8)
		(descr "Resistor SMD 0402")
		(tags "resistor SMD 0402")
		(property "Reference" "R129"
			(at -3.9 -0.3 0)
			(layer "B.SilkS")
			(effects
				(font
					(size 0.7 0.7)
					(thickness 0.15)
				)
				(justify right top mirror)
			)
		)
		(property "Value" "R_1k_0402"
			(at -1.011843 -1.772046 0)
			(layer "B.Fab")
			(effects
				(font
					(size 0.7 0.7)
					(thickness 0.15)
				)
				(justify right top mirror)
			)
		)
		(property "Datasheet" "https://www.bourns.com/docs/product-datasheets/cr.pdf"
			(at 0 0 0)
			(layer "B.Fab")
			(hide yes)
			(effects
				(font
					(size 1.27 1.27)
					(thickness 0.15)
				)
				(justify mirror)
			)
		)
		(property "Description" "SMD Chip Resistor, 1 kohm, ± 1%, 63 mW, 0402 [1005 Metric], Thick Film, General Purpose"
			(at 0 0 0)
			(layer "B.Fab")
			(hide yes)
			(effects
				(font
					(size 1.27 1.27)
					(thickness 0.15)
				)
				(justify mirror)
			)
		)
		(property "Manufacturer" "Bourns"
			(at 0 0 180)
			(unlocked yes)
			(layer "B.Fab")
			(hide yes)
			(effects
				(font
					(size 1 1)
					(thickness 0.15)
				)
				(justify mirror)
			)
		)
		(property "MPN" "CR0402-FX-1001GLF"
			(at 0 0 180)
			(unlocked yes)
			(layer "B.Fab")
			(hide yes)
			(effects
				(font
					(size 1 1)
					(thickness 0.15)
				)
				(justify mirror)
			)
		)
		(property "Val" "1k"
			(at 0 0 180)
			(unlocked yes)
			(layer "B.Fab")
			(hide yes)
			(effects
				(font
					(size 1 1)
					(thickness 0.15)
				)
				(justify mirror)
			)
		)
		(property "License" "Apache-2.0"
			(at 0 0 180)
			(unlocked yes)
			(layer "B.Fab")
			(hide yes)
			(effects
				(font
					(size 1 1)
					(thickness 0.15)
				)
				(justify mirror)
			)
		)
		(property "Author" "Antmicro"
			(at 0 0 180)
			(unlocked yes)
			(layer "B.Fab")
			(hide yes)
			(effects
				(font
					(size 1 1)
					(thickness 0.15)
				)
				(justify mirror)
			)
		)
		(property "Tolerance" "1%"
			(at 0 0 180)
			(unlocked yes)
			(layer "B.Fab")
			(hide yes)
			(effects
				(font
					(size 1 1)
					(thickness 0.15)
				)
				(justify mirror)
			)
		)
		(sheetname "/USB DP Alt mode/")
		(sheetfile "usb_dp.kicad_sch")
		(attr smd)
		(fp_poly
			(pts
				(xy -0.925 0.47) (xy 0.925 0.47) (xy 0.925 -0.47) (xy -0.925 -0.47)
			)
			(stroke
				(width 0.05)
				(type default)
			)
			(fill no)
			(layer "B.CrtYd")
		)
		(fp_poly
			(pts
				(xy -0.5 0.25) (xy 0.5 0.25) (xy 0.5 -0.25) (xy -0.5 -0.25)
			)
			(stroke
				(width 0.15)
				(type solid)
			)
			(fill no)
			(layer "B.Fab")
		)
		(fp_text user "Author: Antmicro"
			(at -0.95 -4.169 0)
			(layer "B.Fab")
			(effects
				(font
					(size 0.7 0.7)
					(thickness 0.15)
				)
				(justify right top mirror)
			)
		)
		(fp_text user "License: Apache-2.0"
			(at -0.949999 -5.169 0)
			(layer "B.Fab")
			(effects
				(font
					(size 0.7 0.7)
					(thickness 0.15)
				)
				(justify right top mirror)
			)
		)
		(fp_text user "${REFERENCE}"
			(at -0.95 -3.168 0)
			(layer "B.Fab")
			(effects
				(font
					(size 0.7 0.7)
					(thickness 0.15)
				)
				(justify right top mirror)
			)
		)
		(pad "1" smd roundrect
			(at -0.48 0)
			(size 0.59 0.64)
			(layers "B.Cu" "B.Mask" "B.Paste")
			(roundrect_rratio 0.25)
			(net 963 "/USB DP Alt mode/USBC1_I2C_EN")
			(pintype "passive")
		)
		(pad "2" smd roundrect
			(at 0.48 0)
			(size 0.59 0.64)
			(layers "B.Cu" "B.Mask" "B.Paste")
			(roundrect_rratio 0.25)
			(net 1 "GND")
			(pintype "passive")
		)
	)
	(footprint "antmicro-footprints:R_0402_1005Metric"
		(layer "B.Cu")
		(at 220.4 124.4)
		(descr "Resistor SMD 0402")
		(tags "resistor SMD 0402")
		(property "Reference" "R337"
			(at -0.9 1.708302 0)
			(layer "B.SilkS")
			(effects
				(font
					(size 0.7 0.7)
					(thickness 0.15)
				)
				(justify right top mirror)
			)
		)
		(property "Value" "R_2R2_0402"
			(at -1.011843 -1.772047 0)
			(layer "B.Fab")
			(effects
				(font
					(size 0.7 0.7)
					(thickness 0.15)
				)
				(justify right top mirror)
			)
		)
		(property "Datasheet" "https://www.bourns.com/docs/product-datasheets/cr.pdf"
			(at 0 0 0)
			(layer "B.Fab")
			(hide yes)
			(effects
				(font
					(size 1.27 1.27)
					(thickness 0.15)
				)
				(justify mirror)
			)
		)
		(property "Description" "SMD Chip Resistor, 2.2 ohm, ± 1%, 62.5 mW, 0402 [1005 Metric], Thick Film, General Purpose"
			(at 0 0 0)
			(layer "B.Fab")
			(hide yes)
			(effects
				(font
					(size 1.27 1.27)
					(thickness 0.15)
				)
				(justify mirror)
			)
		)
		(property "MPN" "CR0402-FX-2R20GLF"
			(at 0 0 180)
			(unlocked yes)
			(layer "B.Fab")
			(hide yes)
			(effects
				(font
					(size 1 1)
					(thickness 0.15)
				)
				(justify mirror)
			)
		)
		(property "Manufacturer" "Bourns"
			(at 0 0 180)
			(unlocked yes)
			(layer "B.Fab")
			(hide yes)
			(effects
				(font
					(size 1 1)
					(thickness 0.15)
				)
				(justify mirror)
			)
		)
		(property "License" "Apache-2.0"
			(at 0 0 180)
			(unlocked yes)
			(layer "B.Fab")
			(hide yes)
			(effects
				(font
					(size 1 1)
					(thickness 0.15)
				)
				(justify mirror)
			)
		)
		(property "Author" "Antmicro"
			(at 0 0 180)
			(unlocked yes)
			(layer "B.Fab")
			(hide yes)
			(effects
				(font
					(size 1 1)
					(thickness 0.15)
				)
				(justify mirror)
			)
		)
		(property "Val" "2R2"
			(at 0 0 180)
			(unlocked yes)
			(layer "B.Fab")
			(hide yes)
			(effects
				(font
					(size 1 1)
					(thickness 0.15)
				)
				(justify mirror)
			)
		)
		(property "Tolerance" "1%"
			(at 0 0 180)
			(unlocked yes)
			(layer "B.Fab")
			(hide yes)
			(effects
				(font
					(size 1 1)
					(thickness 0.15)
				)
				(justify mirror)
			)
		)
		(sheetname "/USB Hub/")
		(sheetfile "usb_hub.kicad_sch")
		(attr smd)
		(fp_rect
			(start -0.925 0.47)
			(end 0.925 -0.47)
			(stroke
				(width 0.05)
				(type default)
			)
			(fill no)
			(layer "B.CrtYd")
		)
		(fp_rect
			(start -0.5 0.25)
			(end 0.5 -0.25)
			(stroke
				(width 0.15)
				(type solid)
			)
			(fill no)
			(layer "B.Fab")
		)
		(fp_text user "License: Apache-2.0"
			(at -0.95 -5.169 0)
			(layer "B.Fab")
			(effects
				(font
					(size 0.7 0.7)
					(thickness 0.15)
				)
				(justify right top mirror)
			)
		)
		(fp_text user "Author: Antmicro"
			(at -0.95 -4.169 0)
			(layer "B.Fab")
			(effects
				(font
					(size 0.7 0.7)
					(thickness 0.15)
				)
				(justify right top mirror)
			)
		)
		(fp_text user "${REFERENCE}"
			(at -0.95 -3.168 0)
			(layer "B.Fab")
			(effects
				(font
					(size 0.7 0.7)
					(thickness 0.15)
				)
				(justify right top mirror)
			)
		)
		(pad "1" smd roundrect
			(at -0.48 0)
			(size 0.59 0.64)
			(layers "B.Cu" "B.Mask" "B.Paste")
			(roundrect_rratio 0.25)
			(net 1241 "Net-(D60-C)")
			(pintype "passive")
		)
		(pad "2" smd roundrect
			(at 0.48 0)
			(size 0.59 0.64)
			(layers "B.Cu" "B.Mask" "B.Paste")
			(roundrect_rratio 0.25)
			(net 502 "/USB Hub/USBC4_CC_{2}")
			(pintype "passive")
		)
	)
	(footprint "antmicro-footprints:TP_SMD_0.75mm"
		(layer "B.Cu")
		(at 134 150.1 -90)
		(property "Reference" "TP95"
			(at -3.3 -0.5 90)
			(layer "B.SilkS")
			(effects
				(font
					(size 0.7 0.7)
					(thickness 0.15)
				)
				(justify left bottom mirror)
			)
		)
		(property "Value" "TP_0.75mm_SMD"
			(at 0 -1.2 90)
			(layer "B.Fab")
			(effects
				(font
					(size 0.7 0.7)
					(thickness 0.15)
				)
				(justify left bottom mirror)
			)
		)
		(property "Description" "SMT test point"
			(at 0 0 90)
			(layer "B.Fab")
			(hide yes)
			(effects
				(font
					(size 1.27 1.27)
					(thickness 0.15)
				)
				(justify mirror)
			)
		)
		(property "MPN" ""
			(at 0 0 90)
			(unlocked yes)
			(layer "B.Fab")
			(hide yes)
			(effects
				(font
					(size 1 1)
					(thickness 0.15)
				)
				(justify mirror)
			)
		)
		(property "Manufacturer" ""
			(at 0 0 90)
			(unlocked yes)
			(layer "B.Fab")
			(hide yes)
			(effects
				(font
					(size 1 1)
					(thickness 0.15)
				)
				(justify mirror)
			)
		)
		(property "Author" "Antmicro"
			(at 0 0 90)
			(unlocked yes)
			(layer "B.Fab")
			(hide yes)
			(effects
				(font
					(size 1 1)
					(thickness 0.15)
				)
				(justify mirror)
			)
		)
		(property "License" "Apache-2.0"
			(at 0 0 90)
			(unlocked yes)
			(layer "B.Fab")
			(hide yes)
			(effects
				(font
					(size 1 1)
					(thickness 0.15)
				)
				(justify mirror)
			)
		)
		(sheetname "/Peripherals/")
		(sheetfile "peripherals.kicad_sch")
		(attr exclude_from_pos_files exclude_from_bom)
		(fp_circle
			(center 0 0)
			(end 0.475 0)
			(stroke
				(width 0.05)
				(type default)
			)
			(fill no)
			(layer "B.CrtYd")
		)
		(fp_text user "Author: Antmicro"
			(at -0.4 -3.901 90)
			(layer "B.Fab")
			(effects
				(font
					(size 0.7 0.7)
					(thickness 0.15)
				)
				(justify left bottom mirror)
			)
		)
		(fp_text user "${REFERENCE}"
			(at -0.4 -2.7 90)
			(layer "B.Fab")
			(effects
				(font
					(size 0.7 0.7)
					(thickness 0.15)
				)
				(justify left bottom mirror)
			)
		)
		(fp_text user "License: Apache-2.0"
			(at -0.4 -5.101 90)
			(layer "B.Fab")
			(effects
				(font
					(size 0.7 0.7)
					(thickness 0.15)
				)
				(justify left bottom mirror)
			)
		)
		(pad "1" smd circle
			(at 0 0 270)
			(size 0.75 0.75)
			(layers "B.Cu" "B.Mask")
			(net 1100 "/Peripherals/TPM_RST")
			(pinfunction "1")
			(pintype "passive")
		)
	)
	(footprint "antmicro-footprints:R_0402_1005Metric"
		(layer "B.Cu")
		(at 220.66 113.03)
		(descr "Resistor SMD 0402")
		(tags "resistor SMD 0402")
		(property "Reference" "R328"
			(at -1.06 1.77 0)
			(layer "B.SilkS")
			(effects
				(font
					(size 0.7 0.7)
					(thickness 0.15)
				)
				(justify right top mirror)
			)
		)
		(property "Value" "R_10k_0402"
			(at -1.011843 -1.772047 0)
			(layer "B.Fab")
			(effects
				(font
					(size 0.7 0.7)
					(thickness 0.15)
				)
				(justify right top mirror)
			)
		)
		(property "Datasheet" "https://www.bourns.com/docs/product-datasheets/cr.pdf"
			(at 0 0 0)
			(layer "B.Fab")
			(hide yes)
			(effects
				(font
					(size 1.27 1.27)
					(thickness 0.15)
				)
				(justify mirror)
			)
		)
		(property "Description" "SMD Chip Resistor, 10 kohm, ± 1%, 62.5 mW, 0402 [1005 Metric], Thick Film, General Purpose"
			(at 0 0 0)
			(layer "B.Fab")
			(hide yes)
			(effects
				(font
					(size 1.27 1.27)
					(thickness 0.15)
				)
				(justify mirror)
			)
		)
		(property "MPN" "CR0402-FX-1002GLF"
			(at 0 0 180)
			(unlocked yes)
			(layer "B.Fab")
			(hide yes)
			(effects
				(font
					(size 1 1)
					(thickness 0.15)
				)
				(justify mirror)
			)
		)
		(property "Manufacturer" "Bourns"
			(at 0 0 180)
			(unlocked yes)
			(layer "B.Fab")
			(hide yes)
			(effects
				(font
					(size 1 1)
					(thickness 0.15)
				)
				(justify mirror)
			)
		)
		(property "License" "Apache-2.0"
			(at 0 0 180)
			(unlocked yes)
			(layer "B.Fab")
			(hide yes)
			(effects
				(font
					(size 1 1)
					(thickness 0.15)
				)
				(justify mirror)
			)
		)
		(property "Author" "Antmicro"
			(at 0 0 180)
			(unlocked yes)
			(layer "B.Fab")
			(hide yes)
			(effects
				(font
					(size 1 1)
					(thickness 0.15)
				)
				(justify mirror)
			)
		)
		(property "Val" "10k"
			(at 0 0 180)
			(unlocked yes)
			(layer "B.Fab")
			(hide yes)
			(effects
				(font
					(size 1 1)
					(thickness 0.15)
				)
				(justify mirror)
			)
		)
		(property "Tolerance" "1%"
			(at 0 0 180)
			(unlocked yes)
			(layer "B.Fab")
			(hide yes)
			(effects
				(font
					(size 1 1)
					(thickness 0.15)
				)
				(justify mirror)
			)
		)
		(sheetname "/USB Hub/")
		(sheetfile "usb_hub.kicad_sch")
		(attr smd)
		(fp_rect
			(start -0.925 0.47)
			(end 0.925 -0.47)
			(stroke
				(width 0.05)
				(type default)
			)
			(fill no)
			(layer "B.CrtYd")
		)
		(fp_rect
			(start -0.5 0.25)
			(end 0.5 -0.25)
			(stroke
				(width 0.15)
				(type solid)
			)
			(fill no)
			(layer "B.Fab")
		)
		(fp_text user "${REFERENCE}"
			(at -0.95 -3.168 0)
			(layer "B.Fab")
			(effects
				(font
					(size 0.7 0.7)
					(thickness 0.15)
				)
				(justify right top mirror)
			)
		)
		(fp_text user "Author: Antmicro"
			(at -0.95 -4.169 0)
			(layer "B.Fab")
			(effects
				(font
					(size 0.7 0.7)
					(thickness 0.15)
				)
				(justify right top mirror)
			)
		)
		(fp_text user "License: Apache-2.0"
			(at -0.95 -5.169 0)
			(layer "B.Fab")
			(effects
				(font
					(size 0.7 0.7)
					(thickness 0.15)
				)
				(justify right top mirror)
			)
		)
		(pad "1" smd roundrect
			(at -0.48 0)
			(size 0.59 0.64)
			(layers "B.Cu" "B.Mask" "B.Paste")
			(roundrect_rratio 0.25)
			(net 1099 "/USB Hub/DP2_VCONN1")
			(pintype "passive")
		)
		(pad "2" smd roundrect
			(at 0.48 0)
			(size 0.59 0.64)
			(layers "B.Cu" "B.Mask" "B.Paste")
			(roundrect_rratio 0.25)
			(net 1 "GND")
			(pintype "passive")
		)
	)
	(footprint "antmicro-footprints:C_0402_1005Metric"
		(layer "B.Cu")
		(at 109.92 70.63)
		(descr "Capacitor SMD 0402")
		(tags "capacitor SMD 0402")
		(property "Reference" "C12"
			(at -1.02 0.67 0)
			(layer "B.SilkS")
			(effects
				(font
					(size 0.7 0.7)
					(thickness 0.15)
				)
				(justify right top mirror)
			)
		)
		(property "Value" "C_10u_0402"
			(at -1.022927 -2.155213 0)
			(layer "B.Fab")
			(effects
				(font
					(size 0.7 0.7)
					(thickness 0.15)
				)
				(justify right top mirror)
			)
		)
		(property "Datasheet" "https://www.yageo.com/en/Chart/Download/pdf/CC0402MRX5R5BB106"
			(at 0 0 0)
			(layer "B.Fab")
			(hide yes)
			(effects
				(font
					(size 1.27 1.27)
					(thickness 0.15)
				)
				(justify mirror)
			)
		)
		(property "Description" "SMD Multilayer Ceramic Capacitor, 10 µF, 6.3 V, 0402 [1005 Metric], ± 20%, X5R, CC Series"
			(at 0 0 0)
			(layer "B.Fab")
			(hide yes)
			(effects
				(font
					(size 1.27 1.27)
					(thickness 0.15)
				)
				(justify mirror)
			)
		)
		(property "MPN" "CC0402MRX5R5BB106"
			(at 0 0 0)
			(unlocked yes)
			(layer "B.Fab")
			(hide yes)
			(effects
				(font
					(size 1 1)
					(thickness 0.15)
				)
				(justify mirror)
			)
		)
		(property "Manufacturer" "YAGEO"
			(at 0 0 0)
			(unlocked yes)
			(layer "B.Fab")
			(hide yes)
			(effects
				(font
					(size 1 1)
					(thickness 0.15)
				)
				(justify mirror)
			)
		)
		(property "License" "Apache-2.0"
			(at 0 0 0)
			(unlocked yes)
			(layer "B.Fab")
			(hide yes)
			(effects
				(font
					(size 1 1)
					(thickness 0.15)
				)
				(justify mirror)
			)
		)
		(property "Author" "Antmicro"
			(at 0 0 0)
			(unlocked yes)
			(layer "B.Fab")
			(hide yes)
			(effects
				(font
					(size 1 1)
					(thickness 0.15)
				)
				(justify mirror)
			)
		)
		(property "Val" "10u"
			(at 0 0 0)
			(unlocked yes)
			(layer "B.Fab")
			(hide yes)
			(effects
				(font
					(size 1 1)
					(thickness 0.15)
				)
				(justify mirror)
			)
		)
		(property "Voltage" ""
			(at 0 0 0)
			(unlocked yes)
			(layer "B.Fab")
			(hide yes)
			(effects
				(font
					(size 1 1)
					(thickness 0.15)
				)
				(justify mirror)
			)
		)
		(property "Dielectric" "template_dielectric"
			(at 0 0 0)
			(unlocked yes)
			(layer "B.Fab")
			(hide yes)
			(effects
				(font
					(size 1 1)
					(thickness 0.15)
				)
				(justify mirror)
			)
		)
		(sheetname "/SoM_Power/")
		(sheetfile "som_power.kicad_sch")
		(attr smd)
		(fp_rect
			(start -0.925 0.47)
			(end 0.925 -0.47)
			(stroke
				(width 0.05)
				(type default)
			)
			(fill no)
			(layer "B.CrtYd")
		)
		(fp_line
			(start -0.494 -0.248)
			(end -0.494 0.25)
			(stroke
				(width 0.15)
				(type solid)
			)
			(layer "B.Fab")
		)
		(fp_line
			(start -0.494 0.25)
			(end 0.504 0.25)
			(stroke
				(width 0.15)
				(type solid)
			)
			(layer "B.Fab")
		)
		(fp_line
			(start 0.504 -0.248)
			(end -0.494 -0.248)
			(stroke
				(width 0.15)
				(type solid)
			)
			(layer "B.Fab")
		)
		(fp_line
			(start 0.504 0.25)
			(end 0.504 -0.248)
			(stroke
				(width 0.15)
				(type solid)
			)
			(layer "B.Fab")
		)
		(fp_text user "${REFERENCE}"
			(at -0.939 -4.599 0)
			(layer "B.Fab")
			(effects
				(font
					(size 0.7 0.7)
					(thickness 0.15)
				)
				(justify right top mirror)
			)
		)
		(fp_text user "Author: Antmicro"
			(at -0.939 -3.399 0)
			(layer "B.Fab")
			(effects
				(font
					(size 0.7 0.7)
					(thickness 0.15)
				)
				(justify right top mirror)
			)
		)
		(fp_text user "License: Apache-2.0"
			(at -0.939 -5.799 0)
			(layer "B.Fab")
			(effects
				(font
					(size 0.7 0.7)
					(thickness 0.15)
				)
				(justify right top mirror)
			)
		)
		(pad "1" smd roundrect
			(at -0.48 0)
			(size 0.59 0.64)
			(layers "B.Cu" "B.Mask" "B.Paste")
			(roundrect_rratio 0.25)
			(net 1 "GND")
			(pintype "passive")
		)
		(pad "2" smd roundrect
			(at 0.48 0)
			(size 0.59 0.64)
			(layers "B.Cu" "B.Mask" "B.Paste")
			(roundrect_rratio 0.25)
			(net 213 "+5V_SOM")
			(pintype "passive")
		)
	)
	(footprint "antmicro-footprints:TP_SMD_0.75mm"
		(layer "B.Cu")
		(at 122.86 55.29 -90)
		(property "Reference" "TP79"
			(at 0.5 0.6 0)
			(layer "B.SilkS")
			(effects
				(font
					(size 0.7 0.7)
					(thickness 0.15)
				)
				(justify left bottom mirror)
			)
		)
		(property "Value" "TP_0.75mm_SMD"
			(at 0 -1.2 90)
			(layer "B.Fab")
			(effects
				(font
					(size 0.7 0.7)
					(thickness 0.15)
				)
				(justify left bottom mirror)
			)
		)
		(property "Description" "SMT test point"
			(at 0 0 90)
			(layer "B.Fab")
			(hide yes)
			(effects
				(font
					(size 1.27 1.27)
					(thickness 0.15)
				)
				(justify mirror)
			)
		)
		(property "MPN" ""
			(at 0 0 90)
			(unlocked yes)
			(layer "B.Fab")
			(hide yes)
			(effects
				(font
					(size 1 1)
					(thickness 0.15)
				)
				(justify mirror)
			)
		)
		(property "Manufacturer" ""
			(at 0 0 90)
			(unlocked yes)
			(layer "B.Fab")
			(hide yes)
			(effects
				(font
					(size 1 1)
					(thickness 0.15)
				)
				(justify mirror)
			)
		)
		(property "Author" "Antmicro"
			(at 0 0 90)
			(unlocked yes)
			(layer "B.Fab")
			(hide yes)
			(effects
				(font
					(size 1 1)
					(thickness 0.15)
				)
				(justify mirror)
			)
		)
		(property "License" "Apache-2.0"
			(at 0 0 90)
			(unlocked yes)
			(layer "B.Fab")
			(hide yes)
			(effects
				(font
					(size 1 1)
					(thickness 0.15)
				)
				(justify mirror)
			)
		)
		(sheetname "/SoM_Power/")
		(sheetfile "som_power.kicad_sch")
		(attr exclude_from_pos_files exclude_from_bom)
		(fp_circle
			(center 0 0)
			(end 0.475 0)
			(stroke
				(width 0.05)
				(type default)
			)
			(fill no)
			(layer "B.CrtYd")
		)
		(fp_text user "License: Apache-2.0"
			(at -0.4 -5.101 90)
			(layer "B.Fab")
			(effects
				(font
					(size 0.7 0.7)
					(thickness 0.15)
				)
				(justify left bottom mirror)
			)
		)
		(fp_text user "${REFERENCE}"
			(at -0.4 -2.7 90)
			(layer "B.Fab")
			(effects
				(font
					(size 0.7 0.7)
					(thickness 0.15)
				)
				(justify left bottom mirror)
			)
		)
		(fp_text user "Author: Antmicro"
			(at -0.4 -3.901 90)
			(layer "B.Fab")
			(effects
				(font
					(size 0.7 0.7)
					(thickness 0.15)
				)
				(justify left bottom mirror)
			)
		)
		(pad "1" smd circle
			(at 0 0 270)
			(size 0.75 0.75)
			(layers "B.Cu" "B.Mask")
			(net 1287 "/SoM_Power/MODULE_POWER_ON")
			(pinfunction "1")
			(pintype "passive")
		)
	)
	(footprint "antmicro-footprints:C_0805_2012Metric"
		(layer "B.Cu")
		(at 229.4 121.6 90)
		(descr "Capacitor SMD 0805")
		(tags "capacitor SMD 0805")
		(property "Reference" "C78"
			(at -1 -1.9 90)
			(layer "B.SilkS")
			(effects
				(font
					(size 0.7 0.7)
					(thickness 0.15)
				)
				(justify right top mirror)
			)
		)
		(property "Value" "C_22u_25V_0805"
			(at -2.055717 -1.963153 90)
			(layer "B.Fab")
			(effects
				(font
					(size 0.7 0.7)
					(thickness 0.15)
				)
				(justify right top mirror)
			)
		)
		(property "Datasheet" "https://product.samsungsem.com/mlcc/CL21A226MAYNNN.do"
			(at 0 0 90)
			(layer "B.Fab")
			(hide yes)
			(effects
				(font
					(size 1.27 1.27)
					(thickness 0.15)
				)
				(justify mirror)
			)
		)
		(property "Description" "SMT Multilayer Ceramic Capacitor, 22uF, +/-20%, 25V, X5R, 0805 [2012 Metric]"
			(at 0 0 90)
			(layer "B.Fab")
			(hide yes)
			(effects
				(font
					(size 1.27 1.27)
					(thickness 0.15)
				)
				(justify mirror)
			)
		)
		(property "Manufacturer" "Samsung Electro-Mechanics"
			(at 0 0 90)
			(unlocked yes)
			(layer "B.Fab")
			(hide yes)
			(effects
				(font
					(size 1 1)
					(thickness 0.15)
				)
				(justify mirror)
			)
		)
		(property "MPN" "CL21A226MAYNNNE"
			(at 0 0 90)
			(unlocked yes)
			(layer "B.Fab")
			(hide yes)
			(effects
				(font
					(size 1 1)
					(thickness 0.15)
				)
				(justify mirror)
			)
		)
		(property "Val" "22u"
			(at 0 0 90)
			(unlocked yes)
			(layer "B.Fab")
			(hide yes)
			(effects
				(font
					(size 1 1)
					(thickness 0.15)
				)
				(justify mirror)
			)
		)
		(property "License" "Apache-2.0"
			(at 0 0 90)
			(unlocked yes)
			(layer "B.Fab")
			(hide yes)
			(effects
				(font
					(size 1 1)
					(thickness 0.15)
				)
				(justify mirror)
			)
		)
		(property "Author" "Antmicro"
			(at 0 0 90)
			(unlocked yes)
			(layer "B.Fab")
			(hide yes)
			(effects
				(font
					(size 1 1)
					(thickness 0.15)
				)
				(justify mirror)
			)
		)
		(property "Voltage" "25V"
			(at 0 0 90)
			(unlocked yes)
			(layer "B.Fab")
			(hide yes)
			(effects
				(font
					(size 1 1)
					(thickness 0.15)
				)
				(justify mirror)
			)
		)
		(property "Dielectric" "X5R"
			(at 0 0 90)
			(unlocked yes)
			(layer "B.Fab")
			(hide yes)
			(effects
				(font
					(size 1 1)
					(thickness 0.15)
				)
				(justify mirror)
			)
		)
		(property "Public" "False"
			(at 0 0 90)
			(unlocked yes)
			(layer "B.Fab")
			(hide yes)
			(effects
				(font
					(size 1 1)
					(thickness 0.15)
				)
				(justify mirror)
			)
		)
		(sheetname "/USB Hub/")
		(sheetfile "usb_hub.kicad_sch")
		(attr smd)
		(fp_line
			(start -0.3 -0.7)
			(end 0.3 -0.7)
			(stroke
				(width 0.15)
				(type solid)
			)
			(layer "B.SilkS")
		)
		(fp_line
			(start -0.3 0.7)
			(end 0.3 0.7)
			(stroke
				(width 0.15)
				(type solid)
			)
			(layer "B.SilkS")
		)
		(fp_poly
			(pts
				(xy 1.95 0.9) (xy -1.95 0.9) (xy -1.95 -0.9) (xy 1.95 -0.9)
			)
			(stroke
				(width 0.05)
				(type default)
			)
			(fill no)
			(layer "B.CrtYd")
		)
		(fp_poly
			(pts
				(xy -0.95 0.675001) (xy 0.95 0.675001) (xy 0.95 -0.675001) (xy -0.95 -0.675001)
			)
			(stroke
				(width 0.15)
				(type solid)
			)
			(fill no)
			(layer "B.Fab")
		)
		(fp_text user "License: Apache-2.0"
			(at -1.9 -4.947 90)
			(layer "B.Fab")
			(effects
				(font
					(size 0.7 0.7)
					(thickness 0.15)
				)
				(justify right top mirror)
			)
		)
		(fp_text user "Author: Antmicro"
			(at -1.9 -5.947 90)
			(layer "B.Fab")
			(effects
				(font
					(size 0.7 0.7)
					(thickness 0.15)
				)
				(justify right top mirror)
			)
		)
		(fp_text user "${REFERENCE}"
			(at -1.899999 -3.947 90)
			(layer "B.Fab")
			(effects
				(font
					(size 0.7 0.7)
					(thickness 0.15)
				)
				(justify right top mirror)
			)
		)
		(pad "1" smd roundrect
			(at -1.099999 0 90)
			(size 1.2 1.3)
			(layers "B.Cu" "B.Mask" "B.Paste")
			(roundrect_rratio 0.25)
			(net 71 "/USB Hub/USBC3_VBUS")
			(pintype "passive")
		)
		(pad "2" smd roundrect
			(at 1.099999 0 90)
			(size 1.2 1.3)
			(layers "B.Cu" "B.Mask" "B.Paste")
			(roundrect_rratio 0.25)
			(net 1 "GND")
			(pintype "passive")
		)
	)
	(footprint "antmicro-footprints:C_0603_1608Metric_EIA"
		(layer "B.Cu")
		(at 123.47 69.52 180)
		(descr "Capacitor SMD 0603, IPC-7351 Density Level A")
		(tags "Capacitor 0603")
		(property "Reference" "C20"
			(at -1.13 0.82 0)
			(layer "B.SilkS")
			(effects
				(font
					(size 0.7 0.7)
					(thickness 0.15)
				)
				(justify left bottom mirror)
			)
		)
		(property "Value" "C_22u_16V_0603"
			(at -1.42757 -1.770288 0)
			(layer "B.Fab")
			(effects
				(font
					(size 0.7 0.7)
					(thickness 0.15)
				)
				(justify left bottom mirror)
			)
		)
		(property "Datasheet" "https://product.samsungsem.com/mlcc/CL10A226MO7JZN.do"
			(at 0 0 0)
			(layer "B.Fab")
			(hide yes)
			(effects
				(font
					(size 1.27 1.27)
					(thickness 0.15)
				)
				(justify mirror)
			)
		)
		(property "Description" "SMD Multilayer Ceramic Capacitor"
			(at 0 0 0)
			(layer "B.Fab")
			(hide yes)
			(effects
				(font
					(size 1.27 1.27)
					(thickness 0.15)
				)
				(justify mirror)
			)
		)
		(property "MPN" "CL10A226MO7JZNC"
			(at 0 0 0)
			(unlocked yes)
			(layer "B.Fab")
			(hide yes)
			(effects
				(font
					(size 1 1)
					(thickness 0.15)
				)
				(justify mirror)
			)
		)
		(property "Manufacturer" "Samsung Electro-Mechanics"
			(at 0 0 0)
			(unlocked yes)
			(layer "B.Fab")
			(hide yes)
			(effects
				(font
					(size 1 1)
					(thickness 0.15)
				)
				(justify mirror)
			)
		)
		(property "License" "Apache-2.0"
			(at 0 0 0)
			(unlocked yes)
			(layer "B.Fab")
			(hide yes)
			(effects
				(font
					(size 1 1)
					(thickness 0.15)
				)
				(justify mirror)
			)
		)
		(property "Author" "Antmicro"
			(at 0 0 0)
			(unlocked yes)
			(layer "B.Fab")
			(hide yes)
			(effects
				(font
					(size 1 1)
					(thickness 0.15)
				)
				(justify mirror)
			)
		)
		(property "Val" "22u"
			(at 0 0 0)
			(unlocked yes)
			(layer "B.Fab")
			(hide yes)
			(effects
				(font
					(size 1 1)
					(thickness 0.15)
				)
				(justify mirror)
			)
		)
		(property "Voltage" "16V"
			(at 0 0 0)
			(unlocked yes)
			(layer "B.Fab")
			(hide yes)
			(effects
				(font
					(size 1 1)
					(thickness 0.15)
				)
				(justify mirror)
			)
		)
		(property "Dielectric" "X7R"
			(at 0 0 0)
			(unlocked yes)
			(layer "B.Fab")
			(hide yes)
			(effects
				(font
					(size 1 1)
					(thickness 0.15)
				)
				(justify mirror)
			)
		)
		(property "Public" "False"
			(at 0 0 0)
			(unlocked yes)
			(layer "B.Fab")
			(hide yes)
			(effects
				(font
					(size 1 1)
					(thickness 0.15)
				)
				(justify mirror)
			)
		)
		(sheetname "/SoM_Power/")
		(sheetfile "som_power.kicad_sch")
		(attr smd)
		(fp_line
			(start -0.15 0.55)
			(end 0.15 0.55)
			(stroke
				(width 0.15)
				(type solid)
			)
			(layer "B.SilkS")
		)
		(fp_line
			(start -0.15 -0.55)
			(end 0.15 -0.55)
			(stroke
				(width 0.15)
				(type solid)
			)
			(layer "B.SilkS")
		)
		(fp_rect
			(start -1.25 0.65)
			(end 1.25 -0.65)
			(stroke
				(width 0.05)
				(type solid)
			)
			(fill no)
			(layer "B.CrtYd")
		)
		(fp_rect
			(start -0.8 0.45)
			(end 0.8 -0.45)
			(stroke
				(width 0.15)
				(type solid)
			)
			(fill no)
			(layer "B.Fab")
		)
		(fp_text user "License: Apache-2.0"
			(at -1.682 -5.895 0)
			(layer "B.Fab")
			(effects
				(font
					(size 0.7 0.7)
					(thickness 0.15)
				)
				(justify left bottom mirror)
			)
		)
		(fp_text user "Author: Antmicro"
			(at -1.682 -4.894 0)
			(layer "B.Fab")
			(effects
				(font
					(size 0.7 0.7)
					(thickness 0.15)
				)
				(justify left bottom mirror)
			)
		)
		(fp_text user "${REFERENCE}"
			(at -1.682 -3.895 0)
			(layer "B.Fab")
			(effects
				(font
					(size 0.7 0.7)
					(thickness 0.15)
				)
				(justify left bottom mirror)
			)
		)
		(pad "1" smd roundrect
			(at -0.7 0 180)
			(size 0.8 1.1)
			(layers "B.Cu" "B.Mask" "B.Paste")
			(roundrect_rratio 0.2)
			(net 1 "GND")
			(pintype "passive")
		)
		(pad "2" smd roundrect
			(at 0.7 0 180)
			(size 0.8 1.1)
			(layers "B.Cu" "B.Mask" "B.Paste")
			(roundrect_rratio 0.2)
			(net 213 "+5V_SOM")
			(pintype "passive")
		)
	)
	(footprint "antmicro-footprints:R_0402_1005Metric"
		(layer "B.Cu")
		(at 200.3 130.5 90)
		(descr "Resistor SMD 0402")
		(tags "resistor SMD 0402")
		(property "Reference" "R62"
			(at -3.1 -0.3 90)
			(layer "B.SilkS")
			(effects
				(font
					(size 0.7 0.7)
					(thickness 0.15)
				)
				(justify right top mirror)
			)
		)
		(property "Value" "R_0R_0402"
			(at -1.011843 -1.772047 90)
			(layer "B.Fab")
			(effects
				(font
					(size 0.7 0.7)
					(thickness 0.15)
				)
				(justify right top mirror)
			)
		)
		(property "Datasheet" "https://industrial.panasonic.com/cdbs/www-data/pdf/RDA0000/AOA0000C301.pdf"
			(at 0 0 90)
			(layer "B.Fab")
			(hide yes)
			(effects
				(font
					(size 1.27 1.27)
					(thickness 0.15)
				)
				(justify mirror)
			)
		)
		(property "Description" "SMD Chip Resistor, Jumper, 0 ohm, 100 mW, 0402 [1005 Metric], Thick Film, General Purpose"
			(at 0 0 90)
			(layer "B.Fab")
			(hide yes)
			(effects
				(font
					(size 1.27 1.27)
					(thickness 0.15)
				)
				(justify mirror)
			)
		)
		(property "Manufacturer" "Panasonic"
			(at 0 0 270)
			(unlocked yes)
			(layer "B.Fab")
			(hide yes)
			(effects
				(font
					(size 1 1)
					(thickness 0.15)
				)
				(justify mirror)
			)
		)
		(property "MPN" "ERJ2GE0R00X"
			(at 0 0 270)
			(unlocked yes)
			(layer "B.Fab")
			(hide yes)
			(effects
				(font
					(size 1 1)
					(thickness 0.15)
				)
				(justify mirror)
			)
		)
		(property "Val" "0R"
			(at 0 0 270)
			(unlocked yes)
			(layer "B.Fab")
			(hide yes)
			(effects
				(font
					(size 1 1)
					(thickness 0.15)
				)
				(justify mirror)
			)
		)
		(property "License" "Apache-2.0"
			(at 0 0 270)
			(unlocked yes)
			(layer "B.Fab")
			(hide yes)
			(effects
				(font
					(size 1 1)
					(thickness 0.15)
				)
				(justify mirror)
			)
		)
		(property "Author" "Antmicro"
			(at 0 0 270)
			(unlocked yes)
			(layer "B.Fab")
			(hide yes)
			(effects
				(font
					(size 1 1)
					(thickness 0.15)
				)
				(justify mirror)
			)
		)
		(property "Tolerance" "~"
			(at 0 0 270)
			(unlocked yes)
			(layer "B.Fab")
			(hide yes)
			(effects
				(font
					(size 1 1)
					(thickness 0.15)
				)
				(justify mirror)
			)
		)
		(property "Current" "1A"
			(at 0 0 270)
			(unlocked yes)
			(layer "B.Fab")
			(hide yes)
			(effects
				(font
					(size 1 1)
					(thickness 0.15)
				)
				(justify mirror)
			)
		)
		(sheetname "/USB Hub/")
		(sheetfile "usb_hub.kicad_sch")
		(attr smd)
		(fp_rect
			(start -0.925 0.47)
			(end 0.925 -0.47)
			(stroke
				(width 0.05)
				(type default)
			)
			(fill no)
			(layer "B.CrtYd")
		)
		(fp_rect
			(start -0.5 0.25)
			(end 0.5 -0.25)
			(stroke
				(width 0.15)
				(type solid)
			)
			(fill no)
			(layer "B.Fab")
		)
		(fp_text user "${REFERENCE}"
			(at -0.95 -3.168 90)
			(layer "B.Fab")
			(effects
				(font
					(size 0.7 0.7)
					(thickness 0.15)
				)
				(justify right top mirror)
			)
		)
		(fp_text user "Author: Antmicro"
			(at -0.95 -4.169 90)
			(layer "B.Fab")
			(effects
				(font
					(size 0.7 0.7)
					(thickness 0.15)
				)
				(justify right top mirror)
			)
		)
		(fp_text user "License: Apache-2.0"
			(at -0.95 -5.169 90)
			(layer "B.Fab")
			(effects
				(font
					(size 0.7 0.7)
					(thickness 0.15)
				)
				(justify right top mirror)
			)
		)
		(pad "1" smd roundrect
			(at -0.48 0 90)
			(size 0.59 0.64)
			(layers "B.Cu" "B.Mask" "B.Paste")
			(roundrect_rratio 0.25)
			(net 1163 "Net-(U21-USB3DN_RXDM3)")
			(pintype "passive")
		)
		(pad "2" smd roundrect
			(at 0.48 0 90)
			(size 0.59 0.64)
			(layers "B.Cu" "B.Mask" "B.Paste")
			(roundrect_rratio 0.25)
			(net 1 "GND")
			(pintype "passive")
		)
	)
	(footprint "antmicro-footprints:C_0805_2012Metric"
		(layer "B.Cu")
		(at 73 141.75 90)
		(descr "Capacitor SMD 0805")
		(tags "capacitor SMD 0805")
		(property "Reference" "C227"
			(at -2.10551 1.198678 90)
			(layer "B.SilkS")
			(effects
				(font
					(size 0.7 0.7)
					(thickness 0.15)
				)
				(justify right top mirror)
			)
		)
		(property "Value" "C_22u_25V_0805"
			(at -2.055717 -1.963153 90)
			(layer "B.Fab")
			(effects
				(font
					(size 0.7 0.7)
					(thickness 0.15)
				)
				(justify right top mirror)
			)
		)
		(property "Datasheet" "https://product.samsungsem.com/mlcc/CL21A226MAYNNN.do"
			(at 0 0 90)
			(layer "B.Fab")
			(hide yes)
			(effects
				(font
					(size 1.27 1.27)
					(thickness 0.15)
				)
				(justify mirror)
			)
		)
		(property "Description" "SMT Multilayer Ceramic Capacitor, 22uF, +/-20%, 25V, X5R, 0805 [2012 Metric]"
			(at 0 0 90)
			(layer "B.Fab")
			(hide yes)
			(effects
				(font
					(size 1.27 1.27)
					(thickness 0.15)
				)
				(justify mirror)
			)
		)
		(property "MPN" "CL21A226MAYNNNE"
			(at 0 0 270)
			(unlocked yes)
			(layer "B.Fab")
			(hide yes)
			(effects
				(font
					(size 1 1)
					(thickness 0.15)
				)
				(justify mirror)
			)
		)
		(property "Val" "22u"
			(at 0 0 270)
			(unlocked yes)
			(layer "B.Fab")
			(hide yes)
			(effects
				(font
					(size 1 1)
					(thickness 0.15)
				)
				(justify mirror)
			)
		)
		(property "Voltage" "25V"
			(at 0 0 270)
			(unlocked yes)
			(layer "B.Fab")
			(hide yes)
			(effects
				(font
					(size 1 1)
					(thickness 0.15)
				)
				(justify mirror)
			)
		)
		(property "Dielectric" "X5R"
			(at 0 0 270)
			(unlocked yes)
			(layer "B.Fab")
			(hide yes)
			(effects
				(font
					(size 1 1)
					(thickness 0.15)
				)
				(justify mirror)
			)
		)
		(property "Manufacturer" "Samsung Electro-Mechanics"
			(at 0 0 270)
			(unlocked yes)
			(layer "B.Fab")
			(hide yes)
			(effects
				(font
					(size 1 1)
					(thickness 0.15)
				)
				(justify mirror)
			)
		)
		(property "License" "Apache-2.0"
			(at 0 0 270)
			(unlocked yes)
			(layer "B.Fab")
			(hide yes)
			(effects
				(font
					(size 1 1)
					(thickness 0.15)
				)
				(justify mirror)
			)
		)
		(property "Author" "Antmicro"
			(at 0 0 270)
			(unlocked yes)
			(layer "B.Fab")
			(hide yes)
			(effects
				(font
					(size 1 1)
					(thickness 0.15)
				)
				(justify mirror)
			)
		)
		(property "Public" "False"
			(at 0 0 270)
			(unlocked yes)
			(layer "B.Fab")
			(hide yes)
			(effects
				(font
					(size 1 1)
					(thickness 0.15)
				)
				(justify mirror)
			)
		)
		(sheetname "/Expansion connector/")
		(sheetfile "expansion_connector.kicad_sch")
		(attr smd)
		(fp_line
			(start -0.3 -0.7)
			(end 0.3 -0.7)
			(stroke
				(width 0.15)
				(type solid)
			)
			(layer "B.SilkS")
		)
		(fp_line
			(start -0.3 0.7)
			(end 0.3 0.7)
			(stroke
				(width 0.15)
				(type solid)
			)
			(layer "B.SilkS")
		)
		(fp_poly
			(pts
				(xy 1.95 0.9) (xy 1.95 -0.9) (xy -1.95 -0.9) (xy -1.95 0.9)
			)
			(stroke
				(width 0.05)
				(type default)
			)
			(fill no)
			(layer "B.CrtYd")
		)
		(fp_poly
			(pts
				(xy -0.95 0.675001) (xy -0.95 -0.675001) (xy 0.95 -0.675001) (xy 0.95 0.675001)
			)
			(stroke
				(width 0.15)
				(type solid)
			)
			(fill no)
			(layer "B.Fab")
		)
		(fp_text user "License: Apache-2.0"
			(at -1.9 -4.947 90)
			(layer "B.Fab")
			(effects
				(font
					(size 0.7 0.7)
					(thickness 0.15)
				)
				(justify right top mirror)
			)
		)
		(fp_text user "Author: Antmicro"
			(at -1.9 -5.947 90)
			(layer "B.Fab")
			(effects
				(font
					(size 0.7 0.7)
					(thickness 0.15)
				)
				(justify right top mirror)
			)
		)
		(fp_text user "${REFERENCE}"
			(at -1.899999 -3.947 90)
			(layer "B.Fab")
			(effects
				(font
					(size 0.7 0.7)
					(thickness 0.15)
				)
				(justify right top mirror)
			)
		)
		(pad "1" smd roundrect
			(at -1.099999 0 90)
			(size 1.2 1.3)
			(layers "B.Cu" "B.Mask" "B.Paste")
			(roundrect_rratio 0.25)
			(net 1 "GND")
			(pintype "passive")
		)
		(pad "2" smd roundrect
			(at 1.099999 0 90)
			(size 1.2 1.3)
			(layers "B.Cu" "B.Mask" "B.Paste")
			(roundrect_rratio 0.25)
			(net 289 "/Expansion connector/+12V_FMC")
			(pintype "passive")
		)
	)
	(footprint "antmicro-footprints:TSOT23-6"
		(layer "B.Cu")
		(at 143.6 62.08 -90)
		(property "Reference" "U55"
			(at -0.18 -2.6 90)
			(layer "B.SilkS")
			(effects
				(font
					(size 0.7 0.7)
					(thickness 0.15)
				)
				(justify left bottom mirror)
			)
		)
		(property "Value" "AP22615A_TSOT26"
			(at 0 -2.6 90)
			(layer "B.Fab")
			(effects
				(font
					(size 0.7 0.7)
					(thickness 0.15)
				)
				(justify left bottom mirror)
			)
		)
		(property "Datasheet" "https://www.mouser.com/datasheet/2/115/DIOD_S_A0008958405_1-2543193.pdf"
			(at 0 0 90)
			(layer "B.Fab")
			(hide yes)
			(effects
				(font
					(size 1.27 1.27)
					(thickness 0.15)
				)
				(justify mirror)
			)
		)
		(property "Description" "Power Load Distribution Switch, High Side, Active High, 1 Output, 5.5 V, 3.6 A, 0.04 ohm, TSOT-26-6"
			(at 0 0 90)
			(layer "B.Fab")
			(hide yes)
			(effects
				(font
					(size 1.27 1.27)
					(thickness 0.15)
				)
				(justify mirror)
			)
		)
		(property "MPN" "AP22615AWU-7"
			(at 0 0 270)
			(unlocked yes)
			(layer "B.Fab")
			(hide yes)
			(effects
				(font
					(size 1 1)
					(thickness 0.15)
				)
				(justify mirror)
			)
		)
		(property "Manufacturer" "Diodes Incorporated"
			(at 0 0 270)
			(unlocked yes)
			(layer "B.Fab")
			(hide yes)
			(effects
				(font
					(size 1 1)
					(thickness 0.15)
				)
				(justify mirror)
			)
		)
		(property "Author" "Antmicro"
			(at 0 0 270)
			(unlocked yes)
			(layer "B.Fab")
			(hide yes)
			(effects
				(font
					(size 1 1)
					(thickness 0.15)
				)
				(justify mirror)
			)
		)
		(property "License" "Apache-2.0"
			(at 0 0 270)
			(unlocked yes)
			(layer "B.Fab")
			(hide yes)
			(effects
				(font
					(size 1 1)
					(thickness 0.15)
				)
				(justify mirror)
			)
		)
		(sheetname "/Peripherals/")
		(sheetfile "peripherals.kicad_sch")
		(attr smd)
		(fp_line
			(start -1 1.5)
			(end -1 1.375)
			(stroke
				(width 0.15)
				(type solid)
			)
			(layer "B.SilkS")
		)
		(fp_line
			(start 1 1.497)
			(end -1 1.5)
			(stroke
				(width 0.15)
				(type solid)
			)
			(layer "B.SilkS")
		)
		(fp_line
			(start 1 1.497)
			(end 1 1.375)
			(stroke
				(width 0.15)
				(type solid)
			)
			(layer "B.SilkS")
		)
		(fp_line
			(start -1 -1.55)
			(end -1 -1.4)
			(stroke
				(width 0.15)
				(type solid)
			)
			(layer "B.SilkS")
		)
		(fp_line
			(start 1 -1.55)
			(end 1 -1.4)
			(stroke
				(width 0.15)
				(type solid)
			)
			(layer "B.SilkS")
		)
		(fp_line
			(start 1 -1.55)
			(end -1 -1.55)
			(stroke
				(width 0.15)
				(type solid)
			)
			(layer "B.SilkS")
		)
		(fp_circle
			(center -1.44 1.5)
			(end -1.39 1.5)
			(stroke
				(width 0.15)
				(type solid)
			)
			(fill yes)
			(layer "B.SilkS")
		)
		(fp_rect
			(start 1.93 1.7)
			(end -1.93 -1.7)
			(stroke
				(width 0.05)
				(type solid)
			)
			(fill no)
			(layer "B.CrtYd")
		)
		(fp_line
			(start -0.45 1.521)
			(end -0.876 1.096)
			(stroke
				(width 0.15)
				(type solid)
			)
			(layer "B.Fab")
		)
		(fp_rect
			(start 0.875 -1.528)
			(end -0.875 1.525)
			(stroke
				(width 0.15)
				(type solid)
			)
			(fill no)
			(layer "B.Fab")
		)
		(fp_text user "License: Apache-2.0"
			(at -1.93 -6.199 90)
			(layer "B.Fab")
			(effects
				(font
					(size 0.7 0.7)
					(thickness 0.15)
				)
				(justify left bottom mirror)
			)
		)
		(fp_text user "${REFERENCE}"
			(at -1.93 -3.8 90)
			(layer "B.Fab")
			(effects
				(font
					(size 0.7 0.7)
					(thickness 0.15)
				)
				(justify left bottom mirror)
			)
		)
		(fp_text user "Author: Antmicro"
			(at -1.93 -5 90)
			(layer "B.Fab")
			(effects
				(font
					(size 0.7 0.7)
					(thickness 0.15)
				)
				(justify left bottom mirror)
			)
		)
		(pad "1" smd rect
			(at -1.301 0.947)
			(size 0.7 1.2)
			(layers "B.Cu" "B.Mask" "B.Paste")
			(net 839 "/Peripherals/I2C_CONN2_3V3")
			(pinfunction "OUT")
			(pintype "power_out")
		)
		(pad "2" smd rect
			(at -1.301 -0.004)
			(size 0.7 1.2)
			(layers "B.Cu" "B.Mask" "B.Paste")
			(net 1 "GND")
			(pinfunction "GND")
			(pintype "power_in")
		)
		(pad "3" smd rect
			(at -1.301 -0.954)
			(size 0.7 1.2)
			(layers "B.Cu" "B.Mask" "B.Paste")
			(net 1122 "unconnected-(U55-FLG-Pad3)")
			(pinfunction "FLG")
			(pintype "output+no_connect")
		)
		(pad "4" smd rect
			(at 1.299 -0.954)
			(size 0.7 1.2)
			(layers "B.Cu" "B.Mask" "B.Paste")
			(net 90 "/Peripherals/I2C_CONN_PEN")
			(pinfunction "EN")
			(pintype "input")
		)
		(pad "5" smd rect
			(at 1.299 -0.004)
			(size 0.7 1.2)
			(layers "B.Cu" "B.Mask" "B.Paste")
			(net 1010 "Net-(U55-ISET)")
			(pinfunction "ISET")
			(pintype "passive")
		)
		(pad "6" smd rect
			(at 1.299 0.947)
			(size 0.7 1.2)
			(layers "B.Cu" "B.Mask" "B.Paste")
			(net 2 "+3V3")
			(pinfunction "IN")
			(pintype "power_in")
		)
	)
	(footprint "antmicro-footprints:C_0603_1608Metric_EIA"
		(layer "B.Cu")
		(at 124.6 137.6 180)
		(descr "Capacitor SMD 0603, IPC-7351 Density Level A")
		(tags "Capacitor 0603")
		(property "Reference" "C170"
			(at -4.6 -0.4 0)
			(layer "B.SilkS")
			(effects
				(font
					(size 0.7 0.7)
					(thickness 0.15)
				)
				(justify left bottom mirror)
			)
		)
		(property "Value" "C_22u_16V_0603"
			(at -1.42757 -1.770288 0)
			(layer "B.Fab")
			(effects
				(font
					(size 0.7 0.7)
					(thickness 0.15)
				)
				(justify left bottom mirror)
			)
		)
		(property "Datasheet" "https://product.samsungsem.com/mlcc/CL10A226MO7JZN.do"
			(at 0 0 0)
			(layer "B.Fab")
			(hide yes)
			(effects
				(font
					(size 1.27 1.27)
					(thickness 0.15)
				)
				(justify mirror)
			)
		)
		(property "Description" "SMD Multilayer Ceramic Capacitor"
			(at 0 0 0)
			(layer "B.Fab")
			(hide yes)
			(effects
				(font
					(size 1.27 1.27)
					(thickness 0.15)
				)
				(justify mirror)
			)
		)
		(property "MPN" "CL10A226MO7JZNC"
			(at 0 0 180)
			(unlocked yes)
			(layer "B.Fab")
			(hide yes)
			(effects
				(font
					(size 1 1)
					(thickness 0.15)
				)
				(justify mirror)
			)
		)
		(property "Manufacturer" "Samsung Electro-Mechanics"
			(at 0 0 180)
			(unlocked yes)
			(layer "B.Fab")
			(hide yes)
			(effects
				(font
					(size 1 1)
					(thickness 0.15)
				)
				(justify mirror)
			)
		)
		(property "License" "Apache-2.0"
			(at 0 0 180)
			(unlocked yes)
			(layer "B.Fab")
			(hide yes)
			(effects
				(font
					(size 1 1)
					(thickness 0.15)
				)
				(justify mirror)
			)
		)
		(property "Author" "Antmicro"
			(at 0 0 180)
			(unlocked yes)
			(layer "B.Fab")
			(hide yes)
			(effects
				(font
					(size 1 1)
					(thickness 0.15)
				)
				(justify mirror)
			)
		)
		(property "Val" "22u"
			(at 0 0 180)
			(unlocked yes)
			(layer "B.Fab")
			(hide yes)
			(effects
				(font
					(size 1 1)
					(thickness 0.15)
				)
				(justify mirror)
			)
		)
		(property "Voltage" "16V"
			(at 0 0 180)
			(unlocked yes)
			(layer "B.Fab")
			(hide yes)
			(effects
				(font
					(size 1 1)
					(thickness 0.15)
				)
				(justify mirror)
			)
		)
		(property "Dielectric" ""
			(at 0 0 180)
			(unlocked yes)
			(layer "B.Fab")
			(hide yes)
			(effects
				(font
					(size 1 1)
					(thickness 0.15)
				)
				(justify mirror)
			)
		)
		(sheetname "/M.2/")
		(sheetfile "m2.kicad_sch")
		(attr smd)
		(fp_line
			(start -0.15 0.55)
			(end 0.15 0.55)
			(stroke
				(width 0.15)
				(type solid)
			)
			(layer "B.SilkS")
		)
		(fp_line
			(start -0.15 -0.55)
			(end 0.15 -0.55)
			(stroke
				(width 0.15)
				(type solid)
			)
			(layer "B.SilkS")
		)
		(fp_rect
			(start -1.25 0.65)
			(end 1.25 -0.65)
			(stroke
				(width 0.05)
				(type solid)
			)
			(fill no)
			(layer "B.CrtYd")
		)
		(fp_rect
			(start -0.8 0.45)
			(end 0.8 -0.45)
			(stroke
				(width 0.15)
				(type solid)
			)
			(fill no)
			(layer "B.Fab")
		)
		(fp_text user "${REFERENCE}"
			(at -1.682 -3.895 0)
			(layer "B.Fab")
			(effects
				(font
					(size 0.7 0.7)
					(thickness 0.15)
				)
				(justify left bottom mirror)
			)
		)
		(fp_text user "License: Apache-2.0"
			(at -1.682 -5.895 0)
			(layer "B.Fab")
			(effects
				(font
					(size 0.7 0.7)
					(thickness 0.15)
				)
				(justify left bottom mirror)
			)
		)
		(fp_text user "Author: Antmicro"
			(at -1.682 -4.894 0)
			(layer "B.Fab")
			(effects
				(font
					(size 0.7 0.7)
					(thickness 0.15)
				)
				(justify left bottom mirror)
			)
		)
		(pad "1" smd roundrect
			(at -0.7 0 180)
			(size 0.8 1.1)
			(layers "B.Cu" "B.Mask" "B.Paste")
			(roundrect_rratio 0.2)
			(net 1 "GND")
			(pintype "passive")
		)
		(pad "2" smd roundrect
			(at 0.7 0 180)
			(size 0.8 1.1)
			(layers "B.Cu" "B.Mask" "B.Paste")
			(roundrect_rratio 0.2)
			(net 2 "+3V3")
			(pintype "passive")
		)
	)
	(footprint "antmicro-footprints:R_0603_1608Metric"
		(layer "B.Cu")
		(at 100.1 130.7 180)
		(descr "Resistor SMD 0603")
		(tags "resistor SMD 0603")
		(property "Reference" "R250"
			(at -4.1 -0.45 0)
			(layer "B.SilkS")
			(effects
				(font
					(size 0.7 0.7)
					(thickness 0.15)
				)
				(justify left bottom mirror)
			)
		)
		(property "Value" "R_0R_22.4A_0603"
			(at 0 -1.6 0)
			(layer "B.Fab")
			(effects
				(font
					(size 0.7 0.7)
					(thickness 0.15)
				)
				(justify left bottom mirror)
			)
		)
		(property "Datasheet" "https://fscdn.rohm.com/en/products/databook/datasheet/passive/resistor/chip_resistor/pmr-jpw-e.pdf"
			(at 0 0 0)
			(layer "B.Fab")
			(hide yes)
			(effects
				(font
					(size 1.27 1.27)
					(thickness 0.15)
				)
				(justify mirror)
			)
		)
		(property "Description" "SMD Chip Resistor"
			(at 0 0 0)
			(layer "B.Fab")
			(hide yes)
			(effects
				(font
					(size 1.27 1.27)
					(thickness 0.15)
				)
				(justify mirror)
			)
		)
		(property "MPN" "PMR03EZPJ000"
			(at 0 0 0)
			(unlocked yes)
			(layer "B.Fab")
			(hide yes)
			(effects
				(font
					(size 1 1)
					(thickness 0.15)
				)
				(justify mirror)
			)
		)
		(property "Manufacturer" "ROHM Semiconductor"
			(at 0 0 0)
			(unlocked yes)
			(layer "B.Fab")
			(hide yes)
			(effects
				(font
					(size 1 1)
					(thickness 0.15)
				)
				(justify mirror)
			)
		)
		(property "Val" "0R"
			(at 0 0 0)
			(unlocked yes)
			(layer "B.Fab")
			(hide yes)
			(effects
				(font
					(size 1 1)
					(thickness 0.15)
				)
				(justify mirror)
			)
		)
		(property "Max. Curr." "22.4A"
			(at 0 0 0)
			(unlocked yes)
			(layer "B.Fab")
			(hide yes)
			(effects
				(font
					(size 1 1)
					(thickness 0.15)
				)
				(justify mirror)
			)
		)
		(property "Author" "Antmicro"
			(at 0 0 0)
			(unlocked yes)
			(layer "B.Fab")
			(hide yes)
			(effects
				(font
					(size 1 1)
					(thickness 0.15)
				)
				(justify mirror)
			)
		)
		(property "License" "Apache-2.0"
			(at 0 0 0)
			(unlocked yes)
			(layer "B.Fab")
			(hide yes)
			(effects
				(font
					(size 1 1)
					(thickness 0.15)
				)
				(justify mirror)
			)
		)
		(property "Tolerance" "template_tolerance"
			(at 0 0 0)
			(unlocked yes)
			(layer "B.Fab")
			(hide yes)
			(effects
				(font
					(size 1 1)
					(thickness 0.15)
				)
				(justify mirror)
			)
		)
		(sheetname "/Expansion connector/")
		(sheetfile "expansion_connector.kicad_sch")
		(attr smd exclude_from_pos_files exclude_from_bom dnp)
		(fp_line
			(start -0.15 0.4)
			(end 0.15 0.4)
			(stroke
				(width 0.15)
				(type solid)
			)
			(layer "B.SilkS")
		)
		(fp_line
			(start -0.15 -0.4)
			(end 0.15 -0.4)
			(stroke
				(width 0.15)
				(type solid)
			)
			(layer "B.SilkS")
		)
		(fp_rect
			(start -1.25 0.65)
			(end 1.25 -0.65)
			(stroke
				(width 0.05)
				(type solid)
			)
			(fill no)
			(layer "B.CrtYd")
		)
		(fp_rect
			(start -0.8 0.4)
			(end 0.8 -0.4)
			(stroke
				(width 0.15)
				(type solid)
			)
			(fill no)
			(layer "B.Fab")
		)
		(fp_text user "${REFERENCE}"
			(at -1.25 -3.898 0)
			(layer "B.Fab")
			(effects
				(font
					(size 0.7 0.7)
					(thickness 0.15)
				)
				(justify left bottom mirror)
			)
		)
		(fp_text user "License: Apache-2.0"
			(at -1.25 -5.9 0)
			(layer "B.Fab")
			(effects
				(font
					(size 0.7 0.7)
					(thickness 0.15)
				)
				(justify left bottom mirror)
			)
		)
		(fp_text user "Author: Antmicro"
			(at -1.25 -4.9 0)
			(layer "B.Fab")
			(effects
				(font
					(size 0.7 0.7)
					(thickness 0.15)
				)
				(justify left bottom mirror)
			)
		)
		(pad "1" smd roundrect
			(at -0.7 0 180)
			(size 0.8 1)
			(layers "B.Cu" "B.Mask" "B.Paste")
			(roundrect_rratio 0.2)
			(net 5 "+5V")
			(pintype "passive")
		)
		(pad "2" smd roundrect
			(at 0.7 0 180)
			(size 0.8 1)
			(layers "B.Cu" "B.Mask" "B.Paste")
			(roundrect_rratio 0.2)
			(net 307 "/Expansion connector/+5V_FMC")
			(pintype "passive")
		)
	)
	(footprint "antmicro-footprints:R_0402_1005Metric"
		(layer "B.Cu")
		(at 124.6 132.9 180)
		(descr "Resistor SMD 0402")
		(tags "resistor SMD 0402")
		(property "Reference" "R214"
			(at -1.65 4.65 0)
			(layer "B.SilkS")
			(effects
				(font
					(size 0.7 0.7)
					(thickness 0.15)
				)
				(justify left bottom mirror)
			)
		)
		(property "Value" "R_0R_0402"
			(at -1.011843 -1.772046 0)
			(layer "B.Fab")
			(effects
				(font
					(size 0.7 0.7)
					(thickness 0.15)
				)
				(justify left bottom mirror)
			)
		)
		(property "Datasheet" "https://industrial.panasonic.com/cdbs/www-data/pdf/RDA0000/AOA0000C301.pdf"
			(at 0 0 0)
			(layer "B.Fab")
			(hide yes)
			(effects
				(font
					(size 1.27 1.27)
					(thickness 0.15)
				)
				(justify mirror)
			)
		)
		(property "Description" "SMD Chip Resistor, Jumper, 0 ohm, 100 mW, 0402 [1005 Metric], Thick Film, General Purpose"
			(at 0 0 0)
			(layer "B.Fab")
			(hide yes)
			(effects
				(font
					(size 1.27 1.27)
					(thickness 0.15)
				)
				(justify mirror)
			)
		)
		(property "MPN" "ERJ2GE0R00X"
			(at 0 0 0)
			(unlocked yes)
			(layer "B.Fab")
			(hide yes)
			(effects
				(font
					(size 1 1)
					(thickness 0.15)
				)
				(justify mirror)
			)
		)
		(property "Manufacturer" "Panasonic"
			(at 0 0 0)
			(unlocked yes)
			(layer "B.Fab")
			(hide yes)
			(effects
				(font
					(size 1 1)
					(thickness 0.15)
				)
				(justify mirror)
			)
		)
		(property "License" "Apache-2.0"
			(at 0 0 0)
			(unlocked yes)
			(layer "B.Fab")
			(hide yes)
			(effects
				(font
					(size 1 1)
					(thickness 0.15)
				)
				(justify mirror)
			)
		)
		(property "Author" "Antmicro"
			(at 0 0 0)
			(unlocked yes)
			(layer "B.Fab")
			(hide yes)
			(effects
				(font
					(size 1 1)
					(thickness 0.15)
				)
				(justify mirror)
			)
		)
		(property "Val" "0R"
			(at 0 0 0)
			(unlocked yes)
			(layer "B.Fab")
			(hide yes)
			(effects
				(font
					(size 1 1)
					(thickness 0.15)
				)
				(justify mirror)
			)
		)
		(property "Tolerance" "~"
			(at 0 0 0)
			(unlocked yes)
			(layer "B.Fab")
			(hide yes)
			(effects
				(font
					(size 1 1)
					(thickness 0.15)
				)
				(justify mirror)
			)
		)
		(property "Current" "1A"
			(at 0 0 0)
			(unlocked yes)
			(layer "B.Fab")
			(hide yes)
			(effects
				(font
					(size 1 1)
					(thickness 0.15)
				)
				(justify mirror)
			)
		)
		(sheetname "/M.2/")
		(sheetfile "m2.kicad_sch")
		(attr smd)
		(fp_poly
			(pts
				(xy -0.925 0.47) (xy 0.925 0.47) (xy 0.925 -0.47) (xy -0.925 -0.47)
			)
			(stroke
				(width 0.05)
				(type default)
			)
			(fill no)
			(layer "B.CrtYd")
		)
		(fp_poly
			(pts
				(xy -0.5 0.25) (xy 0.5 0.25) (xy 0.5 -0.25) (xy -0.5 -0.25)
			)
			(stroke
				(width 0.15)
				(type solid)
			)
			(fill no)
			(layer "B.Fab")
		)
		(fp_text user "Author: Antmicro"
			(at -0.95 -4.169 0)
			(layer "B.Fab")
			(effects
				(font
					(size 0.7 0.7)
					(thickness 0.15)
				)
				(justify left bottom mirror)
			)
		)
		(fp_text user "${REFERENCE}"
			(at -0.95 -3.168 0)
			(layer "B.Fab")
			(effects
				(font
					(size 0.7 0.7)
					(thickness 0.15)
				)
				(justify left bottom mirror)
			)
		)
		(fp_text user "License: Apache-2.0"
			(at -0.949999 -5.169 0)
			(layer "B.Fab")
			(effects
				(font
					(size 0.7 0.7)
					(thickness 0.15)
				)
				(justify left bottom mirror)
			)
		)
		(pad "1" smd roundrect
			(at -0.48 0 180)
			(size 0.59 0.64)
			(layers "B.Cu" "B.Mask" "B.Paste")
			(roundrect_rratio 0.25)
			(net 679 "/M.2/PCIe_{C1x1}.~{RST}")
			(pintype "passive")
		)
		(pad "2" smd roundrect
			(at 0.48 0 180)
			(size 0.59 0.64)
			(layers "B.Cu" "B.Mask" "B.Paste")
			(roundrect_rratio 0.25)
			(net 831 "/M.2/~{PERST_E}")
			(pintype "passive")
		)
	)
	(footprint "antmicro-footprints:C_0402_1005Metric"
		(layer "B.Cu")
		(at 110.25 106.5)
		(descr "Capacitor SMD 0402")
		(tags "capacitor SMD 0402")
		(property "Reference" "C185"
			(at -0.95 0.5 180)
			(layer "B.SilkS")
			(effects
				(font
					(size 0.7 0.7)
					(thickness 0.15)
				)
				(justify left bottom mirror)
			)
		)
		(property "Value" "C_220n_0402"
			(at -1.022927 -2.155213 180)
			(layer "B.Fab")
			(effects
				(font
					(size 0.7 0.7)
					(thickness 0.15)
				)
				(justify left bottom mirror)
			)
		)
		(property "Datasheet" "https://www.yageo.com/en/Chart/Download/pdf/CC0402KRX5R6BB224"
			(at 0 0 180)
			(layer "B.Fab")
			(hide yes)
			(effects
				(font
					(size 1.27 1.27)
					(thickness 0.15)
				)
				(justify mirror)
			)
		)
		(property "Description" "SMD Multilayer Ceramic Capacitor, 0.22 µF, 10 V, 0402 [1005 Metric], ± 10%, X5R, CC Series"
			(at 0 0 180)
			(layer "B.Fab")
			(hide yes)
			(effects
				(font
					(size 1.27 1.27)
					(thickness 0.15)
				)
				(justify mirror)
			)
		)
		(property "MPN" "CC0402KRX5R6BB224"
			(at 0 0 0)
			(unlocked yes)
			(layer "B.Fab")
			(hide yes)
			(effects
				(font
					(size 1 1)
					(thickness 0.15)
				)
				(justify mirror)
			)
		)
		(property "Val" "220n"
			(at 0 0 0)
			(unlocked yes)
			(layer "B.Fab")
			(hide yes)
			(effects
				(font
					(size 1 1)
					(thickness 0.15)
				)
				(justify mirror)
			)
		)
		(property "Voltage" "25V"
			(at 0 0 0)
			(unlocked yes)
			(layer "B.Fab")
			(hide yes)
			(effects
				(font
					(size 1 1)
					(thickness 0.15)
				)
				(justify mirror)
			)
		)
		(property "Dielectric" "X7R"
			(at 0 0 0)
			(unlocked yes)
			(layer "B.Fab")
			(hide yes)
			(effects
				(font
					(size 1 1)
					(thickness 0.15)
				)
				(justify mirror)
			)
		)
		(property "Manufacturer" "YAGEO"
			(at 0 0 0)
			(unlocked yes)
			(layer "B.Fab")
			(hide yes)
			(effects
				(font
					(size 1 1)
					(thickness 0.15)
				)
				(justify mirror)
			)
		)
		(property "License" "Apache-2.0"
			(at 0 0 0)
			(unlocked yes)
			(layer "B.Fab")
			(hide yes)
			(effects
				(font
					(size 1 1)
					(thickness 0.15)
				)
				(justify mirror)
			)
		)
		(property "Author" "Antmicro"
			(at 0 0 0)
			(unlocked yes)
			(layer "B.Fab")
			(hide yes)
			(effects
				(font
					(size 1 1)
					(thickness 0.15)
				)
				(justify mirror)
			)
		)
		(property "Public" "False"
			(at 0 0 0)
			(unlocked yes)
			(layer "B.Fab")
			(hide yes)
			(effects
				(font
					(size 1 1)
					(thickness 0.15)
				)
				(justify mirror)
			)
		)
		(sheetname "/M.2/")
		(sheetfile "m2.kicad_sch")
		(attr smd)
		(fp_rect
			(start -0.925 0.47)
			(end 0.925 -0.47)
			(stroke
				(width 0.05)
				(type default)
			)
			(fill no)
			(layer "B.CrtYd")
		)
		(fp_line
			(start -0.494 -0.248)
			(end -0.494 0.25)
			(stroke
				(width 0.15)
				(type solid)
			)
			(layer "B.Fab")
		)
		(fp_line
			(start -0.494 0.25)
			(end 0.504 0.25)
			(stroke
				(width 0.15)
				(type solid)
			)
			(layer "B.Fab")
		)
		(fp_line
			(start 0.504 -0.248)
			(end -0.494 -0.248)
			(stroke
				(width 0.15)
				(type solid)
			)
			(layer "B.Fab")
		)
		(fp_line
			(start 0.504 0.25)
			(end 0.504 -0.248)
			(stroke
				(width 0.15)
				(type solid)
			)
			(layer "B.Fab")
		)
		(fp_text user "License: Apache-2.0"
			(at -0.939 -5.799 180)
			(layer "B.Fab")
			(effects
				(font
					(size 0.7 0.7)
					(thickness 0.15)
				)
				(justify left bottom mirror)
			)
		)
		(fp_text user "Author: Antmicro"
			(at -0.939 -3.399 180)
			(layer "B.Fab")
			(effects
				(font
					(size 0.7 0.7)
					(thickness 0.15)
				)
				(justify left bottom mirror)
			)
		)
		(fp_text user "${REFERENCE}"
			(at -0.939 -4.599 180)
			(layer "B.Fab")
			(effects
				(font
					(size 0.7 0.7)
					(thickness 0.15)
				)
				(justify left bottom mirror)
			)
		)
		(pad "1" smd roundrect
			(at -0.48 0)
			(size 0.59 0.64)
			(layers "B.Cu" "B.Mask" "B.Paste")
			(roundrect_rratio 0.25)
			(net 411 "/M.2/PCIe_{C5x4}.TX0-")
			(pintype "passive")
		)
		(pad "2" smd roundrect
			(at 0.48 0)
			(size 0.59 0.64)
			(layers "B.Cu" "B.Mask" "B.Paste")
			(roundrect_rratio 0.25)
			(net 415 "/M.2/M2_M_PET0_N")
			(pintype "passive")
		)
	)
	(footprint "antmicro-footprints:R_0402_1005Metric"
		(layer "B.Cu")
		(at 136.8 65.2 -90)
		(descr "Resistor SMD 0402")
		(tags "resistor SMD 0402")
		(property "Reference" "R235"
			(at 0.9 -0.4 90)
			(layer "B.SilkS")
			(effects
				(font
					(size 0.7 0.7)
					(thickness 0.15)
				)
				(justify left bottom mirror)
			)
		)
		(property "Value" "R_10k_0402"
			(at -1.011843 -1.772046 90)
			(layer "B.Fab")
			(effects
				(font
					(size 0.7 0.7)
					(thickness 0.15)
				)
				(justify left bottom mirror)
			)
		)
		(property "Datasheet" "https://www.bourns.com/docs/product-datasheets/cr.pdf"
			(at 0 0 90)
			(layer "B.Fab")
			(hide yes)
			(effects
				(font
					(size 1.27 1.27)
					(thickness 0.15)
				)
				(justify mirror)
			)
		)
		(property "Description" "SMD Chip Resistor, 10 kohm, ± 1%, 62.5 mW, 0402 [1005 Metric], Thick Film, General Purpose"
			(at 0 0 90)
			(layer "B.Fab")
			(hide yes)
			(effects
				(font
					(size 1.27 1.27)
					(thickness 0.15)
				)
				(justify mirror)
			)
		)
		(property "Manufacturer" "Bourns"
			(at 0 0 90)
			(unlocked yes)
			(layer "B.Fab")
			(hide yes)
			(effects
				(font
					(size 1 1)
					(thickness 0.15)
				)
				(justify mirror)
			)
		)
		(property "MPN" "CR0402-FX-1002GLF"
			(at 0 0 90)
			(unlocked yes)
			(layer "B.Fab")
			(hide yes)
			(effects
				(font
					(size 1 1)
					(thickness 0.15)
				)
				(justify mirror)
			)
		)
		(property "Val" "10k"
			(at 0 0 90)
			(unlocked yes)
			(layer "B.Fab")
			(hide yes)
			(effects
				(font
					(size 1 1)
					(thickness 0.15)
				)
				(justify mirror)
			)
		)
		(property "License" "Apache-2.0"
			(at 0 0 90)
			(unlocked yes)
			(layer "B.Fab")
			(hide yes)
			(effects
				(font
					(size 1 1)
					(thickness 0.15)
				)
				(justify mirror)
			)
		)
		(property "Author" "Antmicro"
			(at 0 0 90)
			(unlocked yes)
			(layer "B.Fab")
			(hide yes)
			(effects
				(font
					(size 1 1)
					(thickness 0.15)
				)
				(justify mirror)
			)
		)
		(property "Tolerance" "1%"
			(at 0 0 90)
			(unlocked yes)
			(layer "B.Fab")
			(hide yes)
			(effects
				(font
					(size 1 1)
					(thickness 0.15)
				)
				(justify mirror)
			)
		)
		(sheetname "/Peripherals/")
		(sheetfile "peripherals.kicad_sch")
		(attr smd)
		(fp_poly
			(pts
				(xy -0.925 0.47) (xy 0.925 0.47) (xy 0.925 -0.47) (xy -0.925 -0.47)
			)
			(stroke
				(width 0.05)
				(type default)
			)
			(fill no)
			(layer "B.CrtYd")
		)
		(fp_poly
			(pts
				(xy -0.5 0.25) (xy 0.5 0.25) (xy 0.5 -0.25) (xy -0.5 -0.25)
			)
			(stroke
				(width 0.15)
				(type solid)
			)
			(fill no)
			(layer "B.Fab")
		)
		(fp_text user "${REFERENCE}"
			(at -0.95 -3.168 90)
			(layer "B.Fab")
			(effects
				(font
					(size 0.7 0.7)
					(thickness 0.15)
				)
				(justify left bottom mirror)
			)
		)
		(fp_text user "License: Apache-2.0"
			(at -0.949999 -5.169 90)
			(layer "B.Fab")
			(effects
				(font
					(size 0.7 0.7)
					(thickness 0.15)
				)
				(justify left bottom mirror)
			)
		)
		(fp_text user "Author: Antmicro"
			(at -0.95 -4.169 90)
			(layer "B.Fab")
			(effects
				(font
					(size 0.7 0.7)
					(thickness 0.15)
				)
				(justify left bottom mirror)
			)
		)
		(pad "1" smd roundrect
			(at -0.48 0 270)
			(size 0.59 0.64)
			(layers "B.Cu" "B.Mask" "B.Paste")
			(roundrect_rratio 0.25)
			(net 90 "/Peripherals/I2C_CONN_PEN")
			(pintype "passive")
		)
		(pad "2" smd roundrect
			(at 0.48 0 270)
			(size 0.59 0.64)
			(layers "B.Cu" "B.Mask" "B.Paste")
			(roundrect_rratio 0.25)
			(net 2 "+3V3")
			(pintype "passive")
		)
	)
	(footprint "antmicro-footprints:SOT-523"
		(layer "B.Cu")
		(at 95.88 65.5 -90)
		(property "Reference" "Q8"
			(at 1.1 0.28 90)
			(layer "B.SilkS")
			(effects
				(font
					(size 0.7 0.7)
					(thickness 0.15)
				)
				(justify left bottom mirror)
			)
		)
		(property "Value" "DMG1012T-7"
			(at 0.1 -1.824 90)
			(layer "B.Fab")
			(effects
				(font
					(size 0.7 0.7)
					(thickness 0.15)
				)
				(justify left bottom mirror)
			)
		)
		(property "Datasheet" "https://www.diodes.com/assets/Datasheets/ds31783.pdf"
			(at 0 0 90)
			(layer "B.Fab")
			(hide yes)
			(effects
				(font
					(size 1.27 1.27)
					(thickness 0.15)
				)
				(justify mirror)
			)
		)
		(property "Description" "Power MOSFET, N Channel, 20 V, 630 mA, 0.3 ohm, SOT-523, Surface Mount"
			(at 0 0 90)
			(layer "B.Fab")
			(hide yes)
			(effects
				(font
					(size 1.27 1.27)
					(thickness 0.15)
				)
				(justify mirror)
			)
		)
		(property "MPN" "DMG1012T-7"
			(at 0 0 270)
			(unlocked yes)
			(layer "B.Fab")
			(hide yes)
			(effects
				(font
					(size 1 1)
					(thickness 0.15)
				)
				(justify mirror)
			)
		)
		(property "Manufacturer" "Diodes Incorporated"
			(at 0 0 270)
			(unlocked yes)
			(layer "B.Fab")
			(hide yes)
			(effects
				(font
					(size 1 1)
					(thickness 0.15)
				)
				(justify mirror)
			)
		)
		(property "Author" "Antmicro"
			(at 0 0 270)
			(unlocked yes)
			(layer "B.Fab")
			(hide yes)
			(effects
				(font
					(size 1 1)
					(thickness 0.15)
				)
				(justify mirror)
			)
		)
		(property "License" "Apache-2.0"
			(at 0 0 270)
			(unlocked yes)
			(layer "B.Fab")
			(hide yes)
			(effects
				(font
					(size 1 1)
					(thickness 0.15)
				)
				(justify mirror)
			)
		)
		(sheetname "/SoM_Power/")
		(sheetfile "som_power.kicad_sch")
		(attr smd)
		(fp_line
			(start -0.725 0.551)
			(end -0.277 0.551)
			(stroke
				(width 0.15)
				(type solid)
			)
			(layer "B.SilkS")
		)
		(fp_line
			(start -0.277 0.551)
			(end -0.277 0.75)
			(stroke
				(width 0.15)
				(type solid)
			)
			(layer "B.SilkS")
		)
		(fp_line
			(start -0.927 0.351)
			(end -0.725 0.551)
			(stroke
				(width 0.15)
				(type solid)
			)
			(layer "B.SilkS")
		)
		(fp_line
			(start -0.927 0.051)
			(end -0.927 0.351)
			(stroke
				(width 0.15)
				(type solid)
			)
			(layer "B.SilkS")
		)
		(fp_circle
			(center -0.9652 -0.9652)
			(end -0.9152 -0.9652)
			(stroke
				(width 0.15)
				(type solid)
			)
			(fill yes)
			(layer "B.SilkS")
		)
		(fp_line
			(start -1.12 1.16)
			(end 1.1 1.16)
			(stroke
				(width 0.05)
				(type solid)
			)
			(layer "B.CrtYd")
		)
		(fp_line
			(start -1.12 1.16)
			(end -1.12 -1.15)
			(stroke
				(width 0.05)
				(type solid)
			)
			(layer "B.CrtYd")
		)
		(fp_line
			(start 1.1 1.16)
			(end 1.1 -1.15)
			(stroke
				(width 0.05)
				(type solid)
			)
			(layer "B.CrtYd")
		)
		(fp_line
			(start -1.12 -1.15)
			(end 1.1 -1.15)
			(stroke
				(width 0.05)
				(type solid)
			)
			(layer "B.CrtYd")
		)
		(fp_line
			(start -0.652 0.425)
			(end -0.802 0.276)
			(stroke
				(width 0.15)
				(type solid)
			)
			(layer "B.Fab")
		)
		(fp_line
			(start 0.8 0.425)
			(end -0.652 0.425)
			(stroke
				(width 0.15)
				(type solid)
			)
			(layer "B.Fab")
		)
		(fp_line
			(start 0.8 0.425)
			(end 0.8 -0.424)
			(stroke
				(width 0.15)
				(type solid)
			)
			(layer "B.Fab")
		)
		(fp_line
			(start -0.802 0.276)
			(end -0.802 -0.424)
			(stroke
				(width 0.15)
				(type solid)
			)
			(layer "B.Fab")
		)
		(fp_line
			(start 0.8 -0.424)
			(end -0.802 -0.424)
			(stroke
				(width 0.15)
				(type solid)
			)
			(layer "B.Fab")
		)
		(fp_circle
			(center -0.9652 -0.9652)
			(end -0.9144 -0.9652)
			(stroke
				(width 0.15)
				(type solid)
			)
			(fill no)
			(layer "B.Fab")
		)
		(fp_text user "${REFERENCE}"
			(at -1.12 -3.824 90)
			(layer "B.Fab")
			(effects
				(font
					(size 0.7 0.7)
					(thickness 0.15)
				)
				(justify left bottom mirror)
			)
		)
		(fp_text user "Author: Antmicro"
			(at -1.12 -6.224 90)
			(layer "B.Fab")
			(effects
				(font
					(size 0.7 0.7)
					(thickness 0.15)
				)
				(justify left bottom mirror)
			)
		)
		(fp_text user "License: Apache-2.0"
			(at -1.12 -5.024 90)
			(layer "B.Fab")
			(effects
				(font
					(size 0.7 0.7)
					(thickness 0.15)
				)
				(justify left bottom mirror)
			)
		)
		(pad "1" smd rect
			(at -0.5 -0.65 270)
			(size 0.4 0.51)
			(layers "B.Cu" "B.Mask" "B.Paste")
			(net 1298 "Net-(Q37-G)")
			(pinfunction "G")
			(pintype "input")
		)
		(pad "2" smd rect
			(at 0.498 -0.65 270)
			(size 0.4 0.51)
			(layers "B.Cu" "B.Mask" "B.Paste")
			(net 1 "GND")
			(pinfunction "S")
			(pintype "passive")
		)
		(pad "3" smd rect
			(at 0 0.652 270)
			(size 0.4 0.51)
			(layers "B.Cu" "B.Mask" "B.Paste")
			(net 884 "Net-(Q8-D)")
			(pinfunction "D")
			(pintype "passive")
		)
	)
	(footprint "antmicro-footprints:R_0402_1005Metric"
		(layer "B.Cu")
		(at 141.3 61.1 -90)
		(descr "Resistor SMD 0402")
		(tags "resistor SMD 0402")
		(property "Reference" "R246"
			(at 0.9 -0.4 90)
			(layer "B.SilkS")
			(effects
				(font
					(size 0.7 0.7)
					(thickness 0.15)
				)
				(justify left bottom mirror)
			)
		)
		(property "Value" "R_200R_0402"
			(at -1.011843 -1.772047 90)
			(layer "B.Fab")
			(effects
				(font
					(size 0.7 0.7)
					(thickness 0.15)
				)
				(justify left bottom mirror)
			)
		)
		(property "Datasheet" "https://www.bourns.com/docs/product-datasheets/cr.pdf"
			(at 0 0 90)
			(layer "B.Fab")
			(hide yes)
			(effects
				(font
					(size 1.27 1.27)
					(thickness 0.15)
				)
				(justify mirror)
			)
		)
		(property "Description" "SMD Chip Resistor, 200 ohm, ± 1%, 62.5 mW, 0402 [1005 Metric], Thick Film, General Purpose"
			(at 0 0 90)
			(layer "B.Fab")
			(hide yes)
			(effects
				(font
					(size 1.27 1.27)
					(thickness 0.15)
				)
				(justify mirror)
			)
		)
		(property "Manufacturer" "Bourns"
			(at 0 0 90)
			(unlocked yes)
			(layer "B.Fab")
			(hide yes)
			(effects
				(font
					(size 1 1)
					(thickness 0.15)
				)
				(justify mirror)
			)
		)
		(property "MPN" "CR0402-FX-2000GLF"
			(at 0 0 90)
			(unlocked yes)
			(layer "B.Fab")
			(hide yes)
			(effects
				(font
					(size 1 1)
					(thickness 0.15)
				)
				(justify mirror)
			)
		)
		(property "Val" "200R"
			(at 0 0 90)
			(unlocked yes)
			(layer "B.Fab")
			(hide yes)
			(effects
				(font
					(size 1 1)
					(thickness 0.15)
				)
				(justify mirror)
			)
		)
		(property "License" "Apache-2.0"
			(at 0 0 90)
			(unlocked yes)
			(layer "B.Fab")
			(hide yes)
			(effects
				(font
					(size 1 1)
					(thickness 0.15)
				)
				(justify mirror)
			)
		)
		(property "Author" "Antmicro"
			(at 0 0 90)
			(unlocked yes)
			(layer "B.Fab")
			(hide yes)
			(effects
				(font
					(size 1 1)
					(thickness 0.15)
				)
				(justify mirror)
			)
		)
		(property "Tolerance" "1%"
			(at 0 0 90)
			(unlocked yes)
			(layer "B.Fab")
			(hide yes)
			(effects
				(font
					(size 1 1)
					(thickness 0.15)
				)
				(justify mirror)
			)
		)
		(sheetname "/Peripherals/")
		(sheetfile "peripherals.kicad_sch")
		(attr smd)
		(fp_rect
			(start -0.925 0.47)
			(end 0.925 -0.47)
			(stroke
				(width 0.05)
				(type default)
			)
			(fill no)
			(layer "B.CrtYd")
		)
		(fp_rect
			(start -0.5 0.25)
			(end 0.5 -0.25)
			(stroke
				(width 0.15)
				(type solid)
			)
			(fill no)
			(layer "B.Fab")
		)
		(fp_text user "Author: Antmicro"
			(at -0.95 -4.169 90)
			(layer "B.Fab")
			(effects
				(font
					(size 0.7 0.7)
					(thickness 0.15)
				)
				(justify left bottom mirror)
			)
		)
		(fp_text user "${REFERENCE}"
			(at -0.95 -3.168 90)
			(layer "B.Fab")
			(effects
				(font
					(size 0.7 0.7)
					(thickness 0.15)
				)
				(justify left bottom mirror)
			)
		)
		(fp_text user "License: Apache-2.0"
			(at -0.95 -5.169 90)
			(layer "B.Fab")
			(effects
				(font
					(size 0.7 0.7)
					(thickness 0.15)
				)
				(justify left bottom mirror)
			)
		)
		(pad "1" smd roundrect
			(at -0.48 0 270)
			(size 0.59 0.64)
			(layers "B.Cu" "B.Mask" "B.Paste")
			(roundrect_rratio 0.25)
			(net 548 "Net-(D44-A)")
			(pintype "passive")
		)
		(pad "2" smd roundrect
			(at 0.48 0 270)
			(size 0.59 0.64)
			(layers "B.Cu" "B.Mask" "B.Paste")
			(roundrect_rratio 0.25)
			(net 839 "/Peripherals/I2C_CONN2_3V3")
			(pintype "passive")
		)
	)
	(footprint "antmicro-footprints:R_0402_1005Metric"
		(layer "B.Cu")
		(at 184.25 57.5 -90)
		(descr "Resistor SMD 0402")
		(tags "resistor SMD 0402")
		(property "Reference" "R27"
			(at -3.58 -0.58 90)
			(layer "B.SilkS")
			(effects
				(font
					(size 0.7 0.7)
					(thickness 0.15)
				)
				(justify left bottom mirror)
			)
		)
		(property "Value" "R_2k2_0402"
			(at -1.011843 -1.772047 90)
			(layer "B.Fab")
			(effects
				(font
					(size 0.7 0.7)
					(thickness 0.15)
				)
				(justify left bottom mirror)
			)
		)
		(property "Datasheet" "https://www.bourns.com/docs/product-datasheets/cr.pdf"
			(at 0 0 90)
			(layer "B.Fab")
			(hide yes)
			(effects
				(font
					(size 1.27 1.27)
					(thickness 0.15)
				)
				(justify mirror)
			)
		)
		(property "Description" "SMD Chip Resistor, 2.2 kohm, ± 1%, 62.5 mW, 0402 [1005 Metric], Thick Film, General Purpose"
			(at 0 0 90)
			(layer "B.Fab")
			(hide yes)
			(effects
				(font
					(size 1.27 1.27)
					(thickness 0.15)
				)
				(justify mirror)
			)
		)
		(property "Manufacturer" "Bourns"
			(at 0 0 90)
			(unlocked yes)
			(layer "B.Fab")
			(hide yes)
			(effects
				(font
					(size 1 1)
					(thickness 0.15)
				)
				(justify mirror)
			)
		)
		(property "MPN" "CR0402-FX-2201GLF"
			(at 0 0 90)
			(unlocked yes)
			(layer "B.Fab")
			(hide yes)
			(effects
				(font
					(size 1 1)
					(thickness 0.15)
				)
				(justify mirror)
			)
		)
		(property "Val" "2k2"
			(at 0 0 90)
			(unlocked yes)
			(layer "B.Fab")
			(hide yes)
			(effects
				(font
					(size 1 1)
					(thickness 0.15)
				)
				(justify mirror)
			)
		)
		(property "License" "Apache-2.0"
			(at 0 0 90)
			(unlocked yes)
			(layer "B.Fab")
			(hide yes)
			(effects
				(font
					(size 1 1)
					(thickness 0.15)
				)
				(justify mirror)
			)
		)
		(property "Author" "Antmicro"
			(at 0 0 90)
			(unlocked yes)
			(layer "B.Fab")
			(hide yes)
			(effects
				(font
					(size 1 1)
					(thickness 0.15)
				)
				(justify mirror)
			)
		)
		(property "Tolerance" "1%"
			(at 0 0 90)
			(unlocked yes)
			(layer "B.Fab")
			(hide yes)
			(effects
				(font
					(size 1 1)
					(thickness 0.15)
				)
				(justify mirror)
			)
		)
		(sheetname "/Power/")
		(sheetfile "power.kicad_sch")
		(attr smd)
		(fp_rect
			(start -0.925 0.47)
			(end 0.925 -0.47)
			(stroke
				(width 0.05)
				(type default)
			)
			(fill no)
			(layer "B.CrtYd")
		)
		(fp_rect
			(start -0.5 0.25)
			(end 0.5 -0.25)
			(stroke
				(width 0.15)
				(type solid)
			)
			(fill no)
			(layer "B.Fab")
		)
		(fp_text user "Author: Antmicro"
			(at -0.95 -4.169 90)
			(layer "B.Fab")
			(effects
				(font
					(size 0.7 0.7)
					(thickness 0.15)
				)
				(justify left bottom mirror)
			)
		)
		(fp_text user "${REFERENCE}"
			(at -0.95 -3.168 90)
			(layer "B.Fab")
			(effects
				(font
					(size 0.7 0.7)
					(thickness 0.15)
				)
				(justify left bottom mirror)
			)
		)
		(fp_text user "License: Apache-2.0"
			(at -0.95 -5.169 90)
			(layer "B.Fab")
			(effects
				(font
					(size 0.7 0.7)
					(thickness 0.15)
				)
				(justify left bottom mirror)
			)
		)
		(pad "1" smd roundrect
			(at -0.48 0 270)
			(size 0.59 0.64)
			(layers "B.Cu" "B.Mask" "B.Paste")
			(roundrect_rratio 0.25)
			(net 528 "Net-(D4-A)")
			(pintype "passive")
		)
		(pad "2" smd roundrect
			(at 0.48 0 270)
			(size 0.59 0.64)
			(layers "B.Cu" "B.Mask" "B.Paste")
			(roundrect_rratio 0.25)
			(net 13 "VCC")
			(pintype "passive")
		)
	)
	(footprint "antmicro-footprints:R_0402_1005Metric"
		(layer "B.Cu")
		(at 208.726 145.01 180)
		(descr "Resistor SMD 0402")
		(tags "resistor SMD 0402")
		(property "Reference" "R186"
			(at -3.83 -0.530001 0)
			(layer "B.SilkS")
			(effects
				(font
					(size 0.7 0.7)
					(thickness 0.15)
				)
				(justify left bottom mirror)
			)
		)
		(property "Value" "R_0R_0402"
			(at -1.011843 -1.772046 0)
			(layer "B.Fab")
			(effects
				(font
					(size 0.7 0.7)
					(thickness 0.15)
				)
				(justify left bottom mirror)
			)
		)
		(property "Datasheet" "https://industrial.panasonic.com/cdbs/www-data/pdf/RDA0000/AOA0000C301.pdf"
			(at 0 0 0)
			(layer "B.Fab")
			(hide yes)
			(effects
				(font
					(size 1.27 1.27)
					(thickness 0.15)
				)
				(justify mirror)
			)
		)
		(property "Description" "SMD Chip Resistor, Jumper, 0 ohm, 100 mW, 0402 [1005 Metric], Thick Film, General Purpose"
			(at 0 0 0)
			(layer "B.Fab")
			(hide yes)
			(effects
				(font
					(size 1.27 1.27)
					(thickness 0.15)
				)
				(justify mirror)
			)
		)
		(property "MPN" "ERJ2GE0R00X"
			(at 0 0 0)
			(unlocked yes)
			(layer "B.Fab")
			(hide yes)
			(effects
				(font
					(size 1 1)
					(thickness 0.15)
				)
				(justify mirror)
			)
		)
		(property "Manufacturer" "Panasonic"
			(at 0 0 0)
			(unlocked yes)
			(layer "B.Fab")
			(hide yes)
			(effects
				(font
					(size 1 1)
					(thickness 0.15)
				)
				(justify mirror)
			)
		)
		(property "License" "Apache-2.0"
			(at 0 0 0)
			(unlocked yes)
			(layer "B.Fab")
			(hide yes)
			(effects
				(font
					(size 1 1)
					(thickness 0.15)
				)
				(justify mirror)
			)
		)
		(property "Author" "Antmicro"
			(at 0 0 0)
			(unlocked yes)
			(layer "B.Fab")
			(hide yes)
			(effects
				(font
					(size 1 1)
					(thickness 0.15)
				)
				(justify mirror)
			)
		)
		(property "Val" "0R"
			(at 0 0 0)
			(unlocked yes)
			(layer "B.Fab")
			(hide yes)
			(effects
				(font
					(size 1 1)
					(thickness 0.15)
				)
				(justify mirror)
			)
		)
		(property "Tolerance" "~"
			(at 0 0 0)
			(unlocked yes)
			(layer "B.Fab")
			(hide yes)
			(effects
				(font
					(size 1 1)
					(thickness 0.15)
				)
				(justify mirror)
			)
		)
		(property "Current" "1A"
			(at 0 0 0)
			(unlocked yes)
			(layer "B.Fab")
			(hide yes)
			(effects
				(font
					(size 1 1)
					(thickness 0.15)
				)
				(justify mirror)
			)
		)
		(sheetname "/SFP/")
		(sheetfile "sfp.kicad_sch")
		(attr smd)
		(fp_poly
			(pts
				(xy -0.925 0.47) (xy 0.925 0.47) (xy 0.925 -0.47) (xy -0.925 -0.47)
			)
			(stroke
				(width 0.05)
				(type default)
			)
			(fill no)
			(layer "B.CrtYd")
		)
		(fp_poly
			(pts
				(xy -0.5 0.25) (xy 0.5 0.25) (xy 0.5 -0.25) (xy -0.5 -0.25)
			)
			(stroke
				(width 0.15)
				(type solid)
			)
			(fill no)
			(layer "B.Fab")
		)
		(fp_text user "${REFERENCE}"
			(at -0.95 -3.168 0)
			(layer "B.Fab")
			(effects
				(font
					(size 0.7 0.7)
					(thickness 0.15)
				)
				(justify left bottom mirror)
			)
		)
		(fp_text user "Author: Antmicro"
			(at -0.95 -4.169 0)
			(layer "B.Fab")
			(effects
				(font
					(size 0.7 0.7)
					(thickness 0.15)
				)
				(justify left bottom mirror)
			)
		)
		(fp_text user "License: Apache-2.0"
			(at -0.949999 -5.169 0)
			(layer "B.Fab")
			(effects
				(font
					(size 0.7 0.7)
					(thickness 0.15)
				)
				(justify left bottom mirror)
			)
		)
		(pad "1" smd roundrect
			(at -0.48 0 180)
			(size 0.59 0.64)
			(layers "B.Cu" "B.Mask" "B.Paste")
			(roundrect_rratio 0.25)
			(net 1000 "/SFP/I2C_{SFP}.SCL")
			(pintype "passive")
		)
		(pad "2" smd roundrect
			(at 0.48 0 180)
			(size 0.59 0.64)
			(layers "B.Cu" "B.Mask" "B.Paste")
			(roundrect_rratio 0.25)
			(net 823 "/SFP/SCL_SFP")
			(pintype "passive")
		)
	)
	(footprint "antmicro-footprints:R_0402_1005Metric"
		(layer "B.Cu")
		(at 216 88.2 180)
		(descr "Resistor SMD 0402")
		(tags "resistor SMD 0402")
		(property "Reference" "R138"
			(at -7.6 -2.4 0)
			(layer "B.SilkS")
			(effects
				(font
					(size 0.7 0.7)
					(thickness 0.15)
				)
				(justify left bottom mirror)
			)
		)
		(property "Value" "R_1k_0402"
			(at -1.011843 -1.772047 0)
			(layer "B.Fab")
			(effects
				(font
					(size 0.7 0.7)
					(thickness 0.15)
				)
				(justify left bottom mirror)
			)
		)
		(property "Datasheet" "https://www.bourns.com/docs/product-datasheets/cr.pdf"
			(at 0 0 0)
			(layer "B.Fab")
			(hide yes)
			(effects
				(font
					(size 1.27 1.27)
					(thickness 0.15)
				)
				(justify mirror)
			)
		)
		(property "Description" "SMD Chip Resistor, 1 kohm, ± 1%, 63 mW, 0402 [1005 Metric], Thick Film, General Purpose"
			(at 0 0 0)
			(layer "B.Fab")
			(hide yes)
			(effects
				(font
					(size 1.27 1.27)
					(thickness 0.15)
				)
				(justify mirror)
			)
		)
		(property "Manufacturer" "Bourns"
			(at 0 0 0)
			(unlocked yes)
			(layer "B.Fab")
			(hide yes)
			(effects
				(font
					(size 1 1)
					(thickness 0.15)
				)
				(justify mirror)
			)
		)
		(property "MPN" "CR0402-FX-1001GLF"
			(at 0 0 0)
			(unlocked yes)
			(layer "B.Fab")
			(hide yes)
			(effects
				(font
					(size 1 1)
					(thickness 0.15)
				)
				(justify mirror)
			)
		)
		(property "Val" "1k"
			(at 0 0 0)
			(unlocked yes)
			(layer "B.Fab")
			(hide yes)
			(effects
				(font
					(size 1 1)
					(thickness 0.15)
				)
				(justify mirror)
			)
		)
		(property "License" "Apache-2.0"
			(at 0 0 0)
			(unlocked yes)
			(layer "B.Fab")
			(hide yes)
			(effects
				(font
					(size 1 1)
					(thickness 0.15)
				)
				(justify mirror)
			)
		)
		(property "Author" "Antmicro"
			(at 0 0 0)
			(unlocked yes)
			(layer "B.Fab")
			(hide yes)
			(effects
				(font
					(size 1 1)
					(thickness 0.15)
				)
				(justify mirror)
			)
		)
		(property "Tolerance" "1%"
			(at 0 0 0)
			(unlocked yes)
			(layer "B.Fab")
			(hide yes)
			(effects
				(font
					(size 1 1)
					(thickness 0.15)
				)
				(justify mirror)
			)
		)
		(sheetname "/USB DP Alt mode/")
		(sheetfile "usb_dp.kicad_sch")
		(attr smd exclude_from_pos_files exclude_from_bom dnp)
		(fp_rect
			(start -0.925 0.47)
			(end 0.925 -0.47)
			(stroke
				(width 0.05)
				(type default)
			)
			(fill no)
			(layer "B.CrtYd")
		)
		(fp_rect
			(start -0.5 0.25)
			(end 0.5 -0.25)
			(stroke
				(width 0.15)
				(type solid)
			)
			(fill no)
			(layer "B.Fab")
		)
		(fp_text user "License: Apache-2.0"
			(at -0.95 -5.169 0)
			(layer "B.Fab")
			(effects
				(font
					(size 0.7 0.7)
					(thickness 0.15)
				)
				(justify left bottom mirror)
			)
		)
		(fp_text user "Author: Antmicro"
			(at -0.95 -4.169 0)
			(layer "B.Fab")
			(effects
				(font
					(size 0.7 0.7)
					(thickness 0.15)
				)
				(justify left bottom mirror)
			)
		)
		(fp_text user "${REFERENCE}"
			(at -0.95 -3.168 0)
			(layer "B.Fab")
			(effects
				(font
					(size 0.7 0.7)
					(thickness 0.15)
				)
				(justify left bottom mirror)
			)
		)
		(pad "1" smd roundrect
			(at -0.48 0 180)
			(size 0.59 0.64)
			(layers "B.Cu" "B.Mask" "B.Paste")
			(roundrect_rratio 0.25)
			(net 968 "/USB DP Alt mode/USBC1_EQ0")
			(pintype "passive")
		)
		(pad "2" smd roundrect
			(at 0.48 0 180)
			(size 0.59 0.64)
			(layers "B.Cu" "B.Mask" "B.Paste")
			(roundrect_rratio 0.25)
			(net 2 "+3V3")
			(pintype "passive")
		)
	)
	(footprint "antmicro-footprints:TP_SMD_0.75mm"
		(layer "B.Cu")
		(at 89.7 83.35 -90)
		(property "Reference" "TP100"
			(at 0.45 -0.4 90)
			(layer "B.SilkS")
			(effects
				(font
					(size 0.7 0.7)
					(thickness 0.15)
				)
				(justify left bottom mirror)
			)
		)
		(property "Value" "TP_0.75mm_SMD"
			(at 0 -1.2 90)
			(layer "B.Fab")
			(effects
				(font
					(size 0.7 0.7)
					(thickness 0.15)
				)
				(justify left bottom mirror)
			)
		)
		(property "Description" "SMT test point"
			(at 0 0 90)
			(layer "B.Fab")
			(hide yes)
			(effects
				(font
					(size 1.27 1.27)
					(thickness 0.15)
				)
				(justify mirror)
			)
		)
		(property "MPN" ""
			(at 0 0 90)
			(unlocked yes)
			(layer "B.Fab")
			(hide yes)
			(effects
				(font
					(size 1 1)
					(thickness 0.15)
				)
				(justify mirror)
			)
		)
		(property "Manufacturer" ""
			(at 0 0 90)
			(unlocked yes)
			(layer "B.Fab")
			(hide yes)
			(effects
				(font
					(size 1 1)
					(thickness 0.15)
				)
				(justify mirror)
			)
		)
		(property "Author" "Antmicro"
			(at 0 0 90)
			(unlocked yes)
			(layer "B.Fab")
			(hide yes)
			(effects
				(font
					(size 1 1)
					(thickness 0.15)
				)
				(justify mirror)
			)
		)
		(property "License" "Apache-2.0"
			(at 0 0 90)
			(unlocked yes)
			(layer "B.Fab")
			(hide yes)
			(effects
				(font
					(size 1 1)
					(thickness 0.15)
				)
				(justify mirror)
			)
		)
		(sheetname "/SoM_IO/")
		(sheetfile "som_io.kicad_sch")
		(attr exclude_from_pos_files exclude_from_bom)
		(fp_circle
			(center 0 0)
			(end 0.475 0)
			(stroke
				(width 0.05)
				(type default)
			)
			(fill no)
			(layer "B.CrtYd")
		)
		(fp_text user "${REFERENCE}"
			(at -0.4 -2.7 90)
			(layer "B.Fab")
			(effects
				(font
					(size 0.7 0.7)
					(thickness 0.15)
				)
				(justify left bottom mirror)
			)
		)
		(fp_text user "Author: Antmicro"
			(at -0.4 -3.901 90)
			(layer "B.Fab")
			(effects
				(font
					(size 0.7 0.7)
					(thickness 0.15)
				)
				(justify left bottom mirror)
			)
		)
		(fp_text user "License: Apache-2.0"
			(at -0.4 -5.101 90)
			(layer "B.Fab")
			(effects
				(font
					(size 0.7 0.7)
					(thickness 0.15)
				)
				(justify left bottom mirror)
			)
		)
		(pad "1" smd circle
			(at 0 0 270)
			(size 0.75 0.75)
			(layers "B.Cu" "B.Mask")
			(net 150 "/SoM_IO/I2S_{M.2}.FS")
			(pinfunction "1")
			(pintype "passive")
		)
	)
	(footprint "antmicro-footprints:R_0402_1005Metric"
		(layer "B.Cu")
		(at 238.2 107.824468 180)
		(descr "Resistor SMD 0402")
		(tags "resistor SMD 0402")
		(property "Reference" "R339"
			(at -1.8 -2.375532 0)
			(layer "B.SilkS")
			(effects
				(font
					(size 0.7 0.7)
					(thickness 0.15)
				)
				(justify left bottom mirror)
			)
		)
		(property "Value" "R_0R_0402"
			(at -1.011843 -1.772046 0)
			(layer "B.Fab")
			(effects
				(font
					(size 0.7 0.7)
					(thickness 0.15)
				)
				(justify left bottom mirror)
			)
		)
		(property "Datasheet" "https://industrial.panasonic.com/cdbs/www-data/pdf/RDA0000/AOA0000C301.pdf"
			(at 0 0 0)
			(layer "B.Fab")
			(hide yes)
			(effects
				(font
					(size 1.27 1.27)
					(thickness 0.15)
				)
				(justify mirror)
			)
		)
		(property "Description" "SMD Chip Resistor, Jumper, 0 ohm, 100 mW, 0402 [1005 Metric], Thick Film, General Purpose"
			(at 0 0 0)
			(layer "B.Fab")
			(hide yes)
			(effects
				(font
					(size 1.27 1.27)
					(thickness 0.15)
				)
				(justify mirror)
			)
		)
		(property "MPN" "ERJ2GE0R00X"
			(at 0 0 0)
			(unlocked yes)
			(layer "B.Fab")
			(hide yes)
			(effects
				(font
					(size 1 1)
					(thickness 0.15)
				)
				(justify mirror)
			)
		)
		(property "Manufacturer" "Panasonic"
			(at 0 0 0)
			(unlocked yes)
			(layer "B.Fab")
			(hide yes)
			(effects
				(font
					(size 1 1)
					(thickness 0.15)
				)
				(justify mirror)
			)
		)
		(property "License" "Apache-2.0"
			(at 0 0 0)
			(unlocked yes)
			(layer "B.Fab")
			(hide yes)
			(effects
				(font
					(size 1 1)
					(thickness 0.15)
				)
				(justify mirror)
			)
		)
		(property "Author" "Antmicro"
			(at 0 0 0)
			(unlocked yes)
			(layer "B.Fab")
			(hide yes)
			(effects
				(font
					(size 1 1)
					(thickness 0.15)
				)
				(justify mirror)
			)
		)
		(property "Val" "0R"
			(at 0 0 0)
			(unlocked yes)
			(layer "B.Fab")
			(hide yes)
			(effects
				(font
					(size 1 1)
					(thickness 0.15)
				)
				(justify mirror)
			)
		)
		(property "Tolerance" "~"
			(at 0 0 0)
			(unlocked yes)
			(layer "B.Fab")
			(hide yes)
			(effects
				(font
					(size 1 1)
					(thickness 0.15)
				)
				(justify mirror)
			)
		)
		(property "Current" "1A"
			(at 0 0 0)
			(unlocked yes)
			(layer "B.Fab")
			(hide yes)
			(effects
				(font
					(size 1 1)
					(thickness 0.15)
				)
				(justify mirror)
			)
		)
		(sheetname "/Recovery USB/")
		(sheetfile "recovery_usb.kicad_sch")
		(attr smd)
		(fp_poly
			(pts
				(xy -0.925 0.47) (xy -0.925 -0.47) (xy 0.925 -0.47) (xy 0.925 0.47)
			)
			(stroke
				(width 0.05)
				(type default)
			)
			(fill no)
			(layer "B.CrtYd")
		)
		(fp_poly
			(pts
				(xy -0.5 0.25) (xy -0.5 -0.25) (xy 0.5 -0.25) (xy 0.5 0.25)
			)
			(stroke
				(width 0.15)
				(type solid)
			)
			(fill no)
			(layer "B.Fab")
		)
		(fp_text user "License: Apache-2.0"
			(at -0.949999 -5.169 0)
			(layer "B.Fab")
			(effects
				(font
					(size 0.7 0.7)
					(thickness 0.15)
				)
				(justify left bottom mirror)
			)
		)
		(fp_text user "${REFERENCE}"
			(at -0.95 -3.168 0)
			(layer "B.Fab")
			(effects
				(font
					(size 0.7 0.7)
					(thickness 0.15)
				)
				(justify left bottom mirror)
			)
		)
		(fp_text user "Author: Antmicro"
			(at -0.95 -4.169 0)
			(layer "B.Fab")
			(effects
				(font
					(size 0.7 0.7)
					(thickness 0.15)
				)
				(justify left bottom mirror)
			)
		)
		(pad "1" smd roundrect
			(at -0.48 0 180)
			(size 0.59 0.64)
			(layers "B.Cu" "B.Mask" "B.Paste")
			(roundrect_rratio 0.25)
			(net 1017 "/Recovery USB/USBC2_PEN")
			(pintype "passive")
		)
		(pad "2" smd roundrect
			(at 0.48 0 180)
			(size 0.59 0.64)
			(layers "B.Cu" "B.Mask" "B.Paste")
			(roundrect_rratio 0.25)
			(net 1245 "Net-(R265-Pad1)")
			(pintype "passive")
		)
	)
	(footprint "antmicro-footprints:R_0402_1005Metric"
		(layer "B.Cu")
		(at 216.1 125.5)
		(descr "Resistor SMD 0402")
		(tags "resistor SMD 0402")
		(property "Reference" "R57"
			(at 1 -0.29 0)
			(layer "B.SilkS")
			(effects
				(font
					(size 0.7 0.7)
					(thickness 0.15)
				)
				(justify right top mirror)
			)
		)
		(property "Value" "R_0R_0402"
			(at -1.011843 -1.772047 0)
			(layer "B.Fab")
			(effects
				(font
					(size 0.7 0.7)
					(thickness 0.15)
				)
				(justify right top mirror)
			)
		)
		(property "Datasheet" "https://industrial.panasonic.com/cdbs/www-data/pdf/RDA0000/AOA0000C301.pdf"
			(at 0 0 0)
			(layer "B.Fab")
			(hide yes)
			(effects
				(font
					(size 1.27 1.27)
					(thickness 0.15)
				)
				(justify mirror)
			)
		)
		(property "Description" "SMD Chip Resistor, Jumper, 0 ohm, 100 mW, 0402 [1005 Metric], Thick Film, General Purpose"
			(at 0 0 0)
			(layer "B.Fab")
			(hide yes)
			(effects
				(font
					(size 1.27 1.27)
					(thickness 0.15)
				)
				(justify mirror)
			)
		)
		(property "Manufacturer" "Panasonic"
			(at 0 0 180)
			(unlocked yes)
			(layer "B.Fab")
			(hide yes)
			(effects
				(font
					(size 1 1)
					(thickness 0.15)
				)
				(justify mirror)
			)
		)
		(property "MPN" "ERJ2GE0R00X"
			(at 0 0 180)
			(unlocked yes)
			(layer "B.Fab")
			(hide yes)
			(effects
				(font
					(size 1 1)
					(thickness 0.15)
				)
				(justify mirror)
			)
		)
		(property "Val" "0R"
			(at 0 0 180)
			(unlocked yes)
			(layer "B.Fab")
			(hide yes)
			(effects
				(font
					(size 1 1)
					(thickness 0.15)
				)
				(justify mirror)
			)
		)
		(property "License" "Apache-2.0"
			(at 0 0 180)
			(unlocked yes)
			(layer "B.Fab")
			(hide yes)
			(effects
				(font
					(size 1 1)
					(thickness 0.15)
				)
				(justify mirror)
			)
		)
		(property "Author" "Antmicro"
			(at 0 0 180)
			(unlocked yes)
			(layer "B.Fab")
			(hide yes)
			(effects
				(font
					(size 1 1)
					(thickness 0.15)
				)
				(justify mirror)
			)
		)
		(property "Tolerance" "~"
			(at 0 0 180)
			(unlocked yes)
			(layer "B.Fab")
			(hide yes)
			(effects
				(font
					(size 1 1)
					(thickness 0.15)
				)
				(justify mirror)
			)
		)
		(property "Current" "1A"
			(at 0 0 180)
			(unlocked yes)
			(layer "B.Fab")
			(hide yes)
			(effects
				(font
					(size 1 1)
					(thickness 0.15)
				)
				(justify mirror)
			)
		)
		(sheetname "/USB Hub/")
		(sheetfile "usb_hub.kicad_sch")
		(attr smd)
		(fp_rect
			(start -0.925 0.47)
			(end 0.925 -0.47)
			(stroke
				(width 0.05)
				(type default)
			)
			(fill no)
			(layer "B.CrtYd")
		)
		(fp_rect
			(start -0.5 0.25)
			(end 0.5 -0.25)
			(stroke
				(width 0.15)
				(type solid)
			)
			(fill no)
			(layer "B.Fab")
		)
		(fp_text user "${REFERENCE}"
			(at -0.95 -3.168 0)
			(layer "B.Fab")
			(effects
				(font
					(size 0.7 0.7)
					(thickness 0.15)
				)
				(justify right top mirror)
			)
		)
		(fp_text user "Author: Antmicro"
			(at -0.95 -4.169 0)
			(layer "B.Fab")
			(effects
				(font
					(size 0.7 0.7)
					(thickness 0.15)
				)
				(justify right top mirror)
			)
		)
		(fp_text user "License: Apache-2.0"
			(at -0.95 -5.169 0)
			(layer "B.Fab")
			(effects
				(font
					(size 0.7 0.7)
					(thickness 0.15)
				)
				(justify right top mirror)
			)
		)
		(pad "1" smd roundrect
			(at -0.48 0)
			(size 0.59 0.64)
			(layers "B.Cu" "B.Mask" "B.Paste")
			(roundrect_rratio 0.25)
			(net 1141 "Net-(U21-USB2DN_DM4)")
			(pintype "passive")
		)
		(pad "2" smd roundrect
			(at 0.48 0)
			(size 0.59 0.64)
			(layers "B.Cu" "B.Mask" "B.Paste")
			(roundrect_rratio 0.25)
			(net 2 "+3V3")
			(pintype "passive")
		)
	)
	(footprint "antmicro-footprints:LED_0603_1608Metric_G"
		(layer "B.Cu")
		(at 134.7 55.3 -90)
		(descr "LED SMD 0603 Green")
		(tags "LED SMD 0603 Green")
		(property "Reference" "D44"
			(at -1.08 2.22 90)
			(layer "B.SilkS")
			(effects
				(font
					(size 0.7 0.7)
					(thickness 0.15)
				)
				(justify left bottom mirror)
			)
		)
		(property "Value" "LED_G_0603_LTST-C190GKT"
			(at -0.001 -1.599 90)
			(layer "B.Fab")
			(effects
				(font
					(size 0.7 0.7)
					(thickness 0.15)
				)
				(justify left bottom mirror)
			)
		)
		(property "Datasheet" "https://media.digikey.com/pdf/Data%20Sheets/Lite-On%20PDFs/LTST-C190GKT.pdf"
			(at 0 0 90)
			(layer "B.Fab")
			(hide yes)
			(effects
				(font
					(size 1.27 1.27)
					(thickness 0.15)
				)
				(justify mirror)
			)
		)
		(property "Description" "LED, Green, SMD, 0603, 20 mA, 2.1 V, 569 nm"
			(at 0 0 90)
			(layer "B.Fab")
			(hide yes)
			(effects
				(font
					(size 1.27 1.27)
					(thickness 0.15)
				)
				(justify mirror)
			)
		)
		(property "MPN" "LTST-C190GKT"
			(at 0 0 90)
			(unlocked yes)
			(layer "B.Fab")
			(hide yes)
			(effects
				(font
					(size 1 1)
					(thickness 0.15)
				)
				(justify mirror)
			)
		)
		(property "Manufacturer" "Lite-On"
			(at 0 0 90)
			(unlocked yes)
			(layer "B.Fab")
			(hide yes)
			(effects
				(font
					(size 1 1)
					(thickness 0.15)
				)
				(justify mirror)
			)
		)
		(property "Author" "Antmicro"
			(at 0 0 90)
			(unlocked yes)
			(layer "B.Fab")
			(hide yes)
			(effects
				(font
					(size 1 1)
					(thickness 0.15)
				)
				(justify mirror)
			)
		)
		(property "License" "Apache-2.0"
			(at 0 0 90)
			(unlocked yes)
			(layer "B.Fab")
			(hide yes)
			(effects
				(font
					(size 1 1)
					(thickness 0.15)
				)
				(justify mirror)
			)
		)
		(property "Color" "Green"
			(at 0 0 90)
			(unlocked yes)
			(layer "B.Fab")
			(hide yes)
			(effects
				(font
					(size 1 1)
					(thickness 0.15)
				)
				(justify mirror)
			)
		)
		(sheetname "/Peripherals/")
		(sheetfile "peripherals.kicad_sch")
		(attr smd)
		(fp_line
			(start 0.22 0.35)
			(end -0.22 0.35)
			(stroke
				(width 0.15)
				(type solid)
			)
			(layer "B.SilkS")
		)
		(fp_line
			(start -1.18 0.319)
			(end -1.18 -0.321)
			(stroke
				(width 0.15)
				(type solid)
			)
			(layer "B.SilkS")
		)
		(fp_line
			(start -0.094672 -0.001008)
			(end 0.105329 0.198992)
			(stroke
				(width 0.1)
				(type solid)
			)
			(layer "B.SilkS")
		)
		(fp_line
			(start -0.094672 -0.001008)
			(end -0.24 -0.001008)
			(stroke
				(width 0.1)
				(type solid)
			)
			(layer "B.SilkS")
		)
		(fp_line
			(start 0.105328 -0.001008)
			(end 0.240001 -0.001)
			(stroke
				(width 0.1)
				(type solid)
			)
			(layer "B.SilkS")
		)
		(fp_line
			(start -0.094672 -0.201008)
			(end -0.094672 0.198992)
			(stroke
				(width 0.1)
				(type solid)
			)
			(layer "B.SilkS")
		)
		(fp_line
			(start 0.105328 -0.201008)
			(end 0.105329 0.198992)
			(stroke
				(width 0.1)
				(type solid)
			)
			(layer "B.SilkS")
		)
		(fp_line
			(start 0.105328 -0.201008)
			(end -0.094672 -0.001008)
			(stroke
				(width 0.1)
				(type solid)
			)
			(layer "B.SilkS")
		)
		(fp_line
			(start 0.22 -0.35)
			(end -0.22 -0.35)
			(stroke
				(width 0.15)
				(type solid)
			)
			(layer "B.SilkS")
		)
		(fp_poly
			(pts
				(xy 1.25 -0.65) (xy 1.25 0.65) (xy -1.25 0.65) (xy -1.25 -0.65)
			)
			(stroke
				(width 0.05)
				(type solid)
			)
			(fill no)
			(layer "B.CrtYd")
		)
		(fp_line
			(start -0.199 0.202)
			(end -0.199 -0.1)
			(stroke
				(width 0.15)
				(type solid)
			)
			(layer "B.Fab")
		)
		(fp_line
			(start 0.201 0.202)
			(end -0.101 0)
			(stroke
				(width 0.15)
				(type solid)
			)
			(layer "B.Fab")
		)
		(fp_line
			(start -0.199 0)
			(end -0.597 0)
			(stroke
				(width 0.15)
				(type solid)
			)
			(layer "B.Fab")
		)
		(fp_line
			(start -0.101 0)
			(end 0.201 -0.2)
			(stroke
				(width 0.15)
				(type solid)
			)
			(layer "B.Fab")
		)
		(fp_line
			(start 0.200999 0)
			(end 0.201 0.202)
			(stroke
				(width 0.15)
				(type solid)
			)
			(layer "B.Fab")
		)
		(fp_line
			(start 0.599 0)
			(end 0.200999 0)
			(stroke
				(width 0.15)
				(type solid)
			)
			(layer "B.Fab")
		)
		(fp_line
			(start -0.199 -0.2)
			(end -0.199 -0.1)
			(stroke
				(width 0.15)
				(type solid)
			)
			(layer "B.Fab")
		)
		(fp_line
			(start 0.201 -0.2)
			(end 0.200999 0)
			(stroke
				(width 0.15)
				(type solid)
			)
			(layer "B.Fab")
		)
		(fp_poly
			(pts
				(xy 0.848 -0.4) (xy 0.848 0.401999) (xy -0.85 0.402) (xy -0.85 -0.4)
			)
			(stroke
				(width 0.15)
				(type solid)
			)
			(fill no)
			(layer "B.Fab")
		)
		(fp_text user "License: Apache-2.0"
			(at -1.4224 -3.599 90)
			(layer "B.Fab")
			(effects
				(font
					(size 0.7 0.7)
					(thickness 0.15)
				)
				(justify left bottom mirror)
			)
		)
		(fp_text user "Author: Antmicro"
			(at -1.4224 -4.799 90)
			(layer "B.Fab")
			(effects
				(font
					(size 0.7 0.7)
					(thickness 0.15)
				)
				(justify left bottom mirror)
			)
		)
		(fp_text user "${REFERENCE}"
			(at -1.4224 -5.999 90)
			(layer "B.Fab")
			(effects
				(font
					(size 0.7 0.7)
					(thickness 0.15)
				)
				(justify left bottom mirror)
			)
		)
		(pad "1" smd roundrect
			(at -0.7 0 90)
			(size 0.8 1)
			(layers "B.Cu" "B.Mask" "B.Paste")
			(roundrect_rratio 0.2)
			(net 1 "GND")
			(pinfunction "C")
			(pintype "passive")
		)
		(pad "2" smd roundrect
			(at 0.7 0 90)
			(size 0.8 1)
			(layers "B.Cu" "B.Mask" "B.Paste")
			(roundrect_rratio 0.2)
			(net 548 "Net-(D44-A)")
			(pinfunction "A")
			(pintype "passive")
		)
	)
	(footprint "antmicro-footprints:R_0402_1005Metric"
		(layer "B.Cu")
		(at 191.12 121.7 90)
		(descr "Resistor SMD 0402")
		(tags "resistor SMD 0402")
		(property "Reference" "R99"
			(at -3 -0.42 90)
			(layer "B.SilkS")
			(effects
				(font
					(size 0.7 0.7)
					(thickness 0.15)
				)
				(justify right top mirror)
			)
		)
		(property "Value" "R_0R_0402"
			(at -1.011843 -1.772047 90)
			(layer "B.Fab")
			(effects
				(font
					(size 0.7 0.7)
					(thickness 0.15)
				)
				(justify right top mirror)
			)
		)
		(property "Datasheet" "https://industrial.panasonic.com/cdbs/www-data/pdf/RDA0000/AOA0000C301.pdf"
			(at 0 0 90)
			(layer "B.Fab")
			(hide yes)
			(effects
				(font
					(size 1.27 1.27)
					(thickness 0.15)
				)
				(justify mirror)
			)
		)
		(property "Description" "SMD Chip Resistor, Jumper, 0 ohm, 100 mW, 0402 [1005 Metric], Thick Film, General Purpose"
			(at 0 0 90)
			(layer "B.Fab")
			(hide yes)
			(effects
				(font
					(size 1.27 1.27)
					(thickness 0.15)
				)
				(justify mirror)
			)
		)
		(property "MPN" "ERJ2GE0R00X"
			(at 0 0 270)
			(unlocked yes)
			(layer "B.Fab")
			(hide yes)
			(effects
				(font
					(size 1 1)
					(thickness 0.15)
				)
				(justify mirror)
			)
		)
		(property "Manufacturer" "Panasonic"
			(at 0 0 270)
			(unlocked yes)
			(layer "B.Fab")
			(hide yes)
			(effects
				(font
					(size 1 1)
					(thickness 0.15)
				)
				(justify mirror)
			)
		)
		(property "License" "Apache-2.0"
			(at 0 0 270)
			(unlocked yes)
			(layer "B.Fab")
			(hide yes)
			(effects
				(font
					(size 1 1)
					(thickness 0.15)
				)
				(justify mirror)
			)
		)
		(property "Author" "Antmicro"
			(at 0 0 270)
			(unlocked yes)
			(layer "B.Fab")
			(hide yes)
			(effects
				(font
					(size 1 1)
					(thickness 0.15)
				)
				(justify mirror)
			)
		)
		(property "Val" "0R"
			(at 0 0 270)
			(unlocked yes)
			(layer "B.Fab")
			(hide yes)
			(effects
				(font
					(size 1 1)
					(thickness 0.15)
				)
				(justify mirror)
			)
		)
		(property "Tolerance" "~"
			(at 0 0 270)
			(unlocked yes)
			(layer "B.Fab")
			(hide yes)
			(effects
				(font
					(size 1 1)
					(thickness 0.15)
				)
				(justify mirror)
			)
		)
		(property "Current" "1A"
			(at 0 0 270)
			(unlocked yes)
			(layer "B.Fab")
			(hide yes)
			(effects
				(font
					(size 1 1)
					(thickness 0.15)
				)
				(justify mirror)
			)
		)
		(sheetname "/USB Debug, PD/")
		(sheetfile "usb_debug_pd.kicad_sch")
		(attr smd exclude_from_pos_files exclude_from_bom dnp)
		(fp_rect
			(start -0.925 0.47)
			(end 0.925 -0.47)
			(stroke
				(width 0.05)
				(type default)
			)
			(fill no)
			(layer "B.CrtYd")
		)
		(fp_rect
			(start -0.5 0.25)
			(end 0.5 -0.25)
			(stroke
				(width 0.15)
				(type solid)
			)
			(fill no)
			(layer "B.Fab")
		)
		(fp_text user "Author: Antmicro"
			(at -0.95 -4.169 90)
			(layer "B.Fab")
			(effects
				(font
					(size 0.7 0.7)
					(thickness 0.15)
				)
				(justify right top mirror)
			)
		)
		(fp_text user "License: Apache-2.0"
			(at -0.95 -5.169 90)
			(layer "B.Fab")
			(effects
				(font
					(size 0.7 0.7)
					(thickness 0.15)
				)
				(justify right top mirror)
			)
		)
		(fp_text user "${REFERENCE}"
			(at -0.95 -3.168 90)
			(layer "B.Fab")
			(effects
				(font
					(size 0.7 0.7)
					(thickness 0.15)
				)
				(justify right top mirror)
			)
		)
		(pad "1" smd roundrect
			(at -0.48 0 90)
			(size 0.59 0.64)
			(layers "B.Cu" "B.Mask" "B.Paste")
			(roundrect_rratio 0.25)
			(net 812 "/USB Debug, PD/~{CS}")
			(pintype "passive")
		)
		(pad "2" smd roundrect
			(at 0.48 0 90)
			(size 0.59 0.64)
			(layers "B.Cu" "B.Mask" "B.Paste")
			(roundrect_rratio 0.25)
			(net 929 "/USB Debug, PD/SPI_{HUB_DEBUG}.~{CS0}")
			(pintype "passive")
		)
	)
	(footprint "antmicro-footprints:C_0402_1005Metric"
		(layer "B.Cu")
		(at 134.8 65.2 -90)
		(descr "Capacitor SMD 0402")
		(tags "capacitor SMD 0402")
		(property "Reference" "C208"
			(at 0.9 -0.4 90)
			(layer "B.SilkS")
			(effects
				(font
					(size 0.7 0.7)
					(thickness 0.15)
				)
				(justify left bottom mirror)
			)
		)
		(property "Value" "C_100n_0402"
			(at -1.022927 -2.155213 90)
			(layer "B.Fab")
			(effects
				(font
					(size 0.7 0.7)
					(thickness 0.15)
				)
				(justify left bottom mirror)
			)
		)
		(property "Datasheet" "https://www.murata.com/products/productdetail?partno=GRM155R61H104KE14%23"
			(at 0 0 90)
			(layer "B.Fab")
			(hide yes)
			(effects
				(font
					(size 1.27 1.27)
					(thickness 0.15)
				)
				(justify mirror)
			)
		)
		(property "Description" "SMD Multilayer Ceramic Capacitor, 0.1 µF, 50 V, 0402 [1005 Metric], ± 10%, X5R, GRM Series"
			(at 0 0 90)
			(layer "B.Fab")
			(hide yes)
			(effects
				(font
					(size 1.27 1.27)
					(thickness 0.15)
				)
				(justify mirror)
			)
		)
		(property "Manufacturer" "Murata"
			(at 0 0 90)
			(unlocked yes)
			(layer "B.Fab")
			(hide yes)
			(effects
				(font
					(size 1 1)
					(thickness 0.15)
				)
				(justify mirror)
			)
		)
		(property "MPN" "GRM155R61H104KE14D"
			(at 0 0 90)
			(unlocked yes)
			(layer "B.Fab")
			(hide yes)
			(effects
				(font
					(size 1 1)
					(thickness 0.15)
				)
				(justify mirror)
			)
		)
		(property "Val" "100n"
			(at 0 0 90)
			(unlocked yes)
			(layer "B.Fab")
			(hide yes)
			(effects
				(font
					(size 1 1)
					(thickness 0.15)
				)
				(justify mirror)
			)
		)
		(property "License" "Apache-2.0"
			(at 0 0 90)
			(unlocked yes)
			(layer "B.Fab")
			(hide yes)
			(effects
				(font
					(size 1 1)
					(thickness 0.15)
				)
				(justify mirror)
			)
		)
		(property "Author" "Antmicro"
			(at 0 0 90)
			(unlocked yes)
			(layer "B.Fab")
			(hide yes)
			(effects
				(font
					(size 1 1)
					(thickness 0.15)
				)
				(justify mirror)
			)
		)
		(property "Voltage" "50V"
			(at 0 0 90)
			(unlocked yes)
			(layer "B.Fab")
			(hide yes)
			(effects
				(font
					(size 1 1)
					(thickness 0.15)
				)
				(justify mirror)
			)
		)
		(property "Dielectric" "X5R"
			(at 0 0 90)
			(unlocked yes)
			(layer "B.Fab")
			(hide yes)
			(effects
				(font
					(size 1 1)
					(thickness 0.15)
				)
				(justify mirror)
			)
		)
		(sheetname "/Peripherals/")
		(sheetfile "peripherals.kicad_sch")
		(attr smd)
		(fp_poly
			(pts
				(xy -0.925 0.47) (xy 0.925 0.47) (xy 0.925 -0.47) (xy -0.925 -0.47)
			)
			(stroke
				(width 0.05)
				(type default)
			)
			(fill no)
			(layer "B.CrtYd")
		)
		(fp_line
			(start -0.494 0.25)
			(end 0.504 0.25)
			(stroke
				(width 0.15)
				(type solid)
			)
			(layer "B.Fab")
		)
		(fp_line
			(start 0.504 0.25)
			(end 0.504 -0.248)
			(stroke
				(width 0.15)
				(type solid)
			)
			(layer "B.Fab")
		)
		(fp_line
			(start -0.494 -0.248)
			(end -0.494 0.25)
			(stroke
				(width 0.15)
				(type solid)
			)
			(layer "B.Fab")
		)
		(fp_line
			(start 0.504 -0.248)
			(end -0.494 -0.248)
			(stroke
				(width 0.15)
				(type solid)
			)
			(layer "B.Fab")
		)
		(fp_text user "Author: Antmicro"
			(at -0.939 -3.399 90)
			(layer "B.Fab")
			(effects
				(font
					(size 0.7 0.7)
					(thickness 0.15)
				)
				(justify left bottom mirror)
			)
		)
		(fp_text user "License: Apache-2.0"
			(at -0.939 -5.799 90)
			(layer "B.Fab")
			(effects
				(font
					(size 0.7 0.7)
					(thickness 0.15)
				)
				(justify left bottom mirror)
			)
		)
		(fp_text user "${REFERENCE}"
			(at -0.939 -4.599 90)
			(layer "B.Fab")
			(effects
				(font
					(size 0.7 0.7)
					(thickness 0.15)
				)
				(justify left bottom mirror)
			)
		)
		(pad "1" smd roundrect
			(at -0.48 0 270)
			(size 0.59 0.64)
			(layers "B.Cu" "B.Mask" "B.Paste")
			(roundrect_rratio 0.25)
			(net 2 "+3V3")
			(pintype "passive")
		)
		(pad "2" smd roundrect
			(at 0.48 0 270)
			(size 0.59 0.64)
			(layers "B.Cu" "B.Mask" "B.Paste")
			(roundrect_rratio 0.25)
			(net 1 "GND")
			(pintype "passive")
		)
	)
	(footprint "antmicro-footprints:R_0402_1005Metric"
		(layer "B.Cu")
		(at 64.2 66.52 -90)
		(descr "Resistor SMD 0402")
		(tags "resistor SMD 0402")
		(property "Reference" "R389"
			(at -9.7 0 90)
			(layer "B.SilkS")
			(effects
				(font
					(size 0.7 0.7)
					(thickness 0.15)
				)
				(justify left bottom mirror)
			)
		)
		(property "Value" "R_2k2_0402"
			(at -1.011843 -1.772047 90)
			(layer "B.Fab")
			(effects
				(font
					(size 0.7 0.7)
					(thickness 0.15)
				)
				(justify left bottom mirror)
			)
		)
		(property "Datasheet" "https://www.bourns.com/docs/product-datasheets/cr.pdf"
			(at 0 0 90)
			(layer "B.Fab")
			(hide yes)
			(effects
				(font
					(size 1.27 1.27)
					(thickness 0.15)
				)
				(justify mirror)
			)
		)
		(property "Description" "SMD Chip Resistor, 2.2 kohm, ± 1%, 62.5 mW, 0402 [1005 Metric], Thick Film, General Purpose"
			(at 0 0 90)
			(layer "B.Fab")
			(hide yes)
			(effects
				(font
					(size 1.27 1.27)
					(thickness 0.15)
				)
				(justify mirror)
			)
		)
		(property "MPN" "CR0402-FX-2201GLF"
			(at 0 0 90)
			(unlocked yes)
			(layer "B.Fab")
			(hide yes)
			(effects
				(font
					(size 1 1)
					(thickness 0.15)
				)
				(justify mirror)
			)
		)
		(property "Manufacturer" "Bourns"
			(at 0 0 90)
			(unlocked yes)
			(layer "B.Fab")
			(hide yes)
			(effects
				(font
					(size 1 1)
					(thickness 0.15)
				)
				(justify mirror)
			)
		)
		(property "License" "Apache-2.0"
			(at 0 0 90)
			(unlocked yes)
			(layer "B.Fab")
			(hide yes)
			(effects
				(font
					(size 1 1)
					(thickness 0.15)
				)
				(justify mirror)
			)
		)
		(property "Author" "Antmicro"
			(at 0 0 90)
			(unlocked yes)
			(layer "B.Fab")
			(hide yes)
			(effects
				(font
					(size 1 1)
					(thickness 0.15)
				)
				(justify mirror)
			)
		)
		(property "Val" "2k2"
			(at 0 0 90)
			(unlocked yes)
			(layer "B.Fab")
			(hide yes)
			(effects
				(font
					(size 1 1)
					(thickness 0.15)
				)
				(justify mirror)
			)
		)
		(property "Tolerance" "1%"
			(at 0 0 90)
			(unlocked yes)
			(layer "B.Fab")
			(hide yes)
			(effects
				(font
					(size 1 1)
					(thickness 0.15)
				)
				(justify mirror)
			)
		)
		(sheetname "/CSI/")
		(sheetfile "csi.kicad_sch")
		(attr smd)
		(fp_rect
			(start -0.925 0.47)
			(end 0.925 -0.47)
			(stroke
				(width 0.05)
				(type default)
			)
			(fill no)
			(layer "B.CrtYd")
		)
		(fp_rect
			(start -0.5 0.25)
			(end 0.5 -0.25)
			(stroke
				(width 0.15)
				(type solid)
			)
			(fill no)
			(layer "B.Fab")
		)
		(fp_text user "${REFERENCE}"
			(at -0.95 -3.168 90)
			(layer "B.Fab")
			(effects
				(font
					(size 0.7 0.7)
					(thickness 0.15)
				)
				(justify left bottom mirror)
			)
		)
		(fp_text user "Author: Antmicro"
			(at -0.95 -4.169 90)
			(layer "B.Fab")
			(effects
				(font
					(size 0.7 0.7)
					(thickness 0.15)
				)
				(justify left bottom mirror)
			)
		)
		(fp_text user "License: Apache-2.0"
			(at -0.95 -5.169 90)
			(layer "B.Fab")
			(effects
				(font
					(size 0.7 0.7)
					(thickness 0.15)
				)
				(justify left bottom mirror)
			)
		)
		(pad "1" smd roundrect
			(at -0.48 0 270)
			(size 0.59 0.64)
			(layers "B.Cu" "B.Mask" "B.Paste")
			(roundrect_rratio 0.25)
			(net 979 "/CSI/CSIA_I2C_VCC")
			(pintype "passive")
		)
		(pad "2" smd roundrect
			(at 0.48 0 270)
			(size 0.59 0.64)
			(layers "B.Cu" "B.Mask" "B.Paste")
			(roundrect_rratio 0.25)
			(net 988 "/CSI/SCL_CAM1")
			(pintype "passive")
		)
	)
	(footprint "antmicro-footprints:C_0402_1005Metric"
		(layer "B.Cu")
		(at 95.180001 103.6 -90)
		(descr "Capacitor SMD 0402")
		(tags "capacitor SMD 0402")
		(property "Reference" "C326"
			(at -3.8 -0.3 90)
			(layer "B.SilkS")
			(effects
				(font
					(size 0.7 0.7)
					(thickness 0.15)
				)
				(justify left bottom mirror)
			)
		)
		(property "Value" "C_100n_0402"
			(at -1.022927 -2.155213 90)
			(layer "B.Fab")
			(effects
				(font
					(size 0.7 0.7)
					(thickness 0.15)
				)
				(justify left bottom mirror)
			)
		)
		(property "Datasheet" "https://www.murata.com/products/productdetail?partno=GRM155R61H104KE14%23"
			(at 0 0 90)
			(layer "B.Fab")
			(hide yes)
			(effects
				(font
					(size 1.27 1.27)
					(thickness 0.15)
				)
				(justify mirror)
			)
		)
		(property "Description" "SMD Multilayer Ceramic Capacitor, 0.1 µF, 50 V, 0402 [1005 Metric], ± 10%, X5R, GRM Series"
			(at 0 0 90)
			(layer "B.Fab")
			(hide yes)
			(effects
				(font
					(size 1.27 1.27)
					(thickness 0.15)
				)
				(justify mirror)
			)
		)
		(property "Manufacturer" "Murata"
			(at 0 0 90)
			(unlocked yes)
			(layer "B.Fab")
			(hide yes)
			(effects
				(font
					(size 1 1)
					(thickness 0.15)
				)
				(justify mirror)
			)
		)
		(property "MPN" "GRM155R61H104KE14D"
			(at 0 0 90)
			(unlocked yes)
			(layer "B.Fab")
			(hide yes)
			(effects
				(font
					(size 1 1)
					(thickness 0.15)
				)
				(justify mirror)
			)
		)
		(property "Val" "100n"
			(at 0 0 90)
			(unlocked yes)
			(layer "B.Fab")
			(hide yes)
			(effects
				(font
					(size 1 1)
					(thickness 0.15)
				)
				(justify mirror)
			)
		)
		(property "License" "Apache-2.0"
			(at 0 0 90)
			(unlocked yes)
			(layer "B.Fab")
			(hide yes)
			(effects
				(font
					(size 1 1)
					(thickness 0.15)
				)
				(justify mirror)
			)
		)
		(property "Author" "Antmicro"
			(at 0 0 90)
			(unlocked yes)
			(layer "B.Fab")
			(hide yes)
			(effects
				(font
					(size 1 1)
					(thickness 0.15)
				)
				(justify mirror)
			)
		)
		(property "Voltage" "50V"
			(at 0 0 90)
			(unlocked yes)
			(layer "B.Fab")
			(hide yes)
			(effects
				(font
					(size 1 1)
					(thickness 0.15)
				)
				(justify mirror)
			)
		)
		(property "Dielectric" "X5R"
			(at 0 0 90)
			(unlocked yes)
			(layer "B.Fab")
			(hide yes)
			(effects
				(font
					(size 1 1)
					(thickness 0.15)
				)
				(justify mirror)
			)
		)
		(sheetname "/SoM_IO2/")
		(sheetfile "som_io2.kicad_sch")
		(attr smd)
		(fp_poly
			(pts
				(xy -0.925 0.47) (xy 0.925 0.47) (xy 0.925 -0.47) (xy -0.925 -0.47)
			)
			(stroke
				(width 0.05)
				(type default)
			)
			(fill no)
			(layer "B.CrtYd")
		)
		(fp_line
			(start -0.494 0.25)
			(end 0.504 0.25)
			(stroke
				(width 0.15)
				(type solid)
			)
			(layer "B.Fab")
		)
		(fp_line
			(start 0.504 0.25)
			(end 0.504 -0.248)
			(stroke
				(width 0.15)
				(type solid)
			)
			(layer "B.Fab")
		)
		(fp_line
			(start -0.494 -0.248)
			(end -0.494 0.25)
			(stroke
				(width 0.15)
				(type solid)
			)
			(layer "B.Fab")
		)
		(fp_line
			(start 0.504 -0.248)
			(end -0.494 -0.248)
			(stroke
				(width 0.15)
				(type solid)
			)
			(layer "B.Fab")
		)
		(fp_text user "${REFERENCE}"
			(at -0.939 -4.599 90)
			(layer "B.Fab")
			(effects
				(font
					(size 0.7 0.7)
					(thickness 0.15)
				)
				(justify left bottom mirror)
			)
		)
		(fp_text user "License: Apache-2.0"
			(at -0.939 -5.799 90)
			(layer "B.Fab")
			(effects
				(font
					(size 0.7 0.7)
					(thickness 0.15)
				)
				(justify left bottom mirror)
			)
		)
		(fp_text user "Author: Antmicro"
			(at -0.939 -3.399 90)
			(layer "B.Fab")
			(effects
				(font
					(size 0.7 0.7)
					(thickness 0.15)
				)
				(justify left bottom mirror)
			)
		)
		(pad "1" smd roundrect
			(at -0.48 0 270)
			(size 0.59 0.64)
			(layers "B.Cu" "B.Mask" "B.Paste")
			(roundrect_rratio 0.25)
			(net 570 "/Expansion connector/DP1.TX2+")
			(pintype "passive")
		)
		(pad "2" smd roundrect
			(at 0.48 0 270)
			(size 0.59 0.64)
			(layers "B.Cu" "B.Mask" "B.Paste")
			(roundrect_rratio 0.25)
			(net 1223 "/SoM_IO2/DP1.TX2_C+")
			(pintype "passive")
		)
	)
	(footprint "antmicro-footprints:C_0402_1005Metric"
		(layer "B.Cu")
		(at 180.23 82.5)
		(descr "Capacitor SMD 0402")
		(tags "capacitor SMD 0402")
		(property "Reference" "C262"
			(at -1.83 0.5 0)
			(layer "B.SilkS")
			(effects
				(font
					(size 0.7 0.7)
					(thickness 0.15)
				)
				(justify right top mirror)
			)
		)
		(property "Value" "C_1u_25V_0402"
			(at -1.022927 -2.155213 0)
			(layer "B.Fab")
			(effects
				(font
					(size 0.7 0.7)
					(thickness 0.15)
				)
				(justify right top mirror)
			)
		)
		(property "Datasheet" "https://www.murata.com/products/productdetail?partno=GRM155R61E105KE11%23"
			(at 0 0 0)
			(layer "B.Fab")
			(hide yes)
			(effects
				(font
					(size 1.27 1.27)
					(thickness 0.15)
				)
				(justify mirror)
			)
		)
		(property "Description" "SMD Multilayer Ceramic Capacitor, 1 µF, 25 V, 0402 [1005 Metric], ± 10%, X5R, GRM Series"
			(at 0 0 0)
			(layer "B.Fab")
			(hide yes)
			(effects
				(font
					(size 1.27 1.27)
					(thickness 0.15)
				)
				(justify mirror)
			)
		)
		(property "MPN" "GRM155R61E105KE11J"
			(at 0 0 180)
			(unlocked yes)
			(layer "B.Fab")
			(hide yes)
			(effects
				(font
					(size 1 1)
					(thickness 0.15)
				)
				(justify mirror)
			)
		)
		(property "Manufacturer" "Murata"
			(at 0 0 180)
			(unlocked yes)
			(layer "B.Fab")
			(hide yes)
			(effects
				(font
					(size 1 1)
					(thickness 0.15)
				)
				(justify mirror)
			)
		)
		(property "License" "Apache-2.0"
			(at 0 0 180)
			(unlocked yes)
			(layer "B.Fab")
			(hide yes)
			(effects
				(font
					(size 1 1)
					(thickness 0.15)
				)
				(justify mirror)
			)
		)
		(property "Author" "Antmicro"
			(at 0 0 180)
			(unlocked yes)
			(layer "B.Fab")
			(hide yes)
			(effects
				(font
					(size 1 1)
					(thickness 0.15)
				)
				(justify mirror)
			)
		)
		(property "Val" "1u"
			(at 0 0 180)
			(unlocked yes)
			(layer "B.Fab")
			(hide yes)
			(effects
				(font
					(size 1 1)
					(thickness 0.15)
				)
				(justify mirror)
			)
		)
		(property "Voltage" "25V"
			(at 0 0 180)
			(unlocked yes)
			(layer "B.Fab")
			(hide yes)
			(effects
				(font
					(size 1 1)
					(thickness 0.15)
				)
				(justify mirror)
			)
		)
		(property "Dielectric" "X5R"
			(at 0 0 180)
			(unlocked yes)
			(layer "B.Fab")
			(hide yes)
			(effects
				(font
					(size 1 1)
					(thickness 0.15)
				)
				(justify mirror)
			)
		)
		(sheetname "/Power/")
		(sheetfile "power.kicad_sch")
		(attr smd exclude_from_pos_files exclude_from_bom dnp)
		(fp_rect
			(start -0.925 0.47)
			(end 0.925 -0.47)
			(stroke
				(width 0.05)
				(type default)
			)
			(fill no)
			(layer "B.CrtYd")
		)
		(fp_line
			(start -0.494 -0.248)
			(end -0.494 0.25)
			(stroke
				(width 0.15)
				(type solid)
			)
			(layer "B.Fab")
		)
		(fp_line
			(start -0.494 0.25)
			(end 0.504 0.25)
			(stroke
				(width 0.15)
				(type solid)
			)
			(layer "B.Fab")
		)
		(fp_line
			(start 0.504 -0.248)
			(end -0.494 -0.248)
			(stroke
				(width 0.15)
				(type solid)
			)
			(layer "B.Fab")
		)
		(fp_line
			(start 0.504 0.25)
			(end 0.504 -0.248)
			(stroke
				(width 0.15)
				(type solid)
			)
			(layer "B.Fab")
		)
		(fp_text user "${REFERENCE}"
			(at -0.939 -4.599 0)
			(layer "B.Fab")
			(effects
				(font
					(size 0.7 0.7)
					(thickness 0.15)
				)
				(justify right top mirror)
			)
		)
		(fp_text user "License: Apache-2.0"
			(at -0.939 -5.799 0)
			(layer "B.Fab")
			(effects
				(font
					(size 0.7 0.7)
					(thickness 0.15)
				)
				(justify right top mirror)
			)
		)
		(fp_text user "Author: Antmicro"
			(at -0.939 -3.399 0)
			(layer "B.Fab")
			(effects
				(font
					(size 0.7 0.7)
					(thickness 0.15)
				)
				(justify right top mirror)
			)
		)
		(pad "1" smd roundrect
			(at -0.48 0)
			(size 0.59 0.64)
			(layers "B.Cu" "B.Mask" "B.Paste")
			(roundrect_rratio 0.25)
			(net 1 "GND")
			(pintype "passive")
		)
		(pad "2" smd roundrect
			(at 0.48 0)
			(size 0.59 0.64)
			(layers "B.Cu" "B.Mask" "B.Paste")
			(roundrect_rratio 0.25)
			(net 13 "VCC")
			(pintype "passive")
		)
	)
	(footprint "antmicro-footprints:R_0402_1005Metric"
		(layer "B.Cu")
		(at 161.8 57.5 -90)
		(descr "Resistor SMD 0402")
		(tags "resistor SMD 0402")
		(property "Reference" "R240"
			(at -1.7 0.5 90)
			(layer "B.SilkS")
			(effects
				(font
					(size 0.7 0.7)
					(thickness 0.15)
				)
				(justify left bottom mirror)
			)
		)
		(property "Value" "R_470R_0402"
			(at -1.011843 -1.772046 90)
			(layer "B.Fab")
			(effects
				(font
					(size 0.7 0.7)
					(thickness 0.15)
				)
				(justify left bottom mirror)
			)
		)
		(property "Datasheet" "https://www.bourns.com/docs/product-datasheets/cr.pdf"
			(at 0 0 90)
			(layer "B.Fab")
			(hide yes)
			(effects
				(font
					(size 1.27 1.27)
					(thickness 0.15)
				)
				(justify mirror)
			)
		)
		(property "Description" "SMD Chip Resistor, 470 ohm, ± 1%, 62.5 mW, 0402 [1005 Metric], Thick Film, General Purpose"
			(at 0 0 90)
			(layer "B.Fab")
			(hide yes)
			(effects
				(font
					(size 1.27 1.27)
					(thickness 0.15)
				)
				(justify mirror)
			)
		)
		(property "MPN" "CR0402-FX-4700GLF"
			(at 0 0 90)
			(unlocked yes)
			(layer "B.Fab")
			(hide yes)
			(effects
				(font
					(size 1 1)
					(thickness 0.15)
				)
				(justify mirror)
			)
		)
		(property "Manufacturer" "Bourns"
			(at 0 0 90)
			(unlocked yes)
			(layer "B.Fab")
			(hide yes)
			(effects
				(font
					(size 1 1)
					(thickness 0.15)
				)
				(justify mirror)
			)
		)
		(property "License" "Apache-2.0"
			(at 0 0 90)
			(unlocked yes)
			(layer "B.Fab")
			(hide yes)
			(effects
				(font
					(size 1 1)
					(thickness 0.15)
				)
				(justify mirror)
			)
		)
		(property "Author" "Antmicro"
			(at 0 0 90)
			(unlocked yes)
			(layer "B.Fab")
			(hide yes)
			(effects
				(font
					(size 1 1)
					(thickness 0.15)
				)
				(justify mirror)
			)
		)
		(property "Val" "470R"
			(at 0 0 90)
			(unlocked yes)
			(layer "B.Fab")
			(hide yes)
			(effects
				(font
					(size 1 1)
					(thickness 0.15)
				)
				(justify mirror)
			)
		)
		(property "Tolerance" "1%"
			(at 0 0 90)
			(unlocked yes)
			(layer "B.Fab")
			(hide yes)
			(effects
				(font
					(size 1 1)
					(thickness 0.15)
				)
				(justify mirror)
			)
		)
		(property "Current" "1A"
			(at 0 0 90)
			(unlocked yes)
			(layer "B.Fab")
			(hide yes)
			(effects
				(font
					(size 1 1)
					(thickness 0.15)
				)
				(justify mirror)
			)
		)
		(sheetname "/Power/")
		(sheetfile "power.kicad_sch")
		(attr smd)
		(fp_poly
			(pts
				(xy -0.925 0.47) (xy 0.925 0.47) (xy 0.925 -0.47) (xy -0.925 -0.47)
			)
			(stroke
				(width 0.05)
				(type default)
			)
			(fill no)
			(layer "B.CrtYd")
		)
		(fp_poly
			(pts
				(xy -0.5 0.25) (xy 0.5 0.25) (xy 0.5 -0.25) (xy -0.5 -0.25)
			)
			(stroke
				(width 0.15)
				(type solid)
			)
			(fill no)
			(layer "B.Fab")
		)
		(fp_text user "License: Apache-2.0"
			(at -0.949999 -5.169 90)
			(layer "B.Fab")
			(effects
				(font
					(size 0.7 0.7)
					(thickness 0.15)
				)
				(justify left bottom mirror)
			)
		)
		(fp_text user "Author: Antmicro"
			(at -0.95 -4.169 90)
			(layer "B.Fab")
			(effects
				(font
					(size 0.7 0.7)
					(thickness 0.15)
				)
				(justify left bottom mirror)
			)
		)
		(fp_text user "${REFERENCE}"
			(at -0.95 -3.168 90)
			(layer "B.Fab")
			(effects
				(font
					(size 0.7 0.7)
					(thickness 0.15)
				)
				(justify left bottom mirror)
			)
		)
		(pad "1" smd roundrect
			(at -0.48 0 270)
			(size 0.59 0.64)
			(layers "B.Cu" "B.Mask" "B.Paste")
			(roundrect_rratio 0.25)
			(net 1008 "Net-(D40-A)")
			(pintype "passive")
		)
		(pad "2" smd roundrect
			(at 0.48 0 270)
			(size 0.59 0.64)
			(layers "B.Cu" "B.Mask" "B.Paste")
			(roundrect_rratio 0.25)
			(net 5 "+5V")
			(pintype "passive")
		)
	)
	(footprint "antmicro-footprints:C_0402_1005Metric"
		(layer "B.Cu")
		(at 94 119.78 180)
		(descr "Capacitor SMD 0402")
		(tags "capacitor SMD 0402")
		(property "Reference" "C214"
			(at -3.9 -0.725 0)
			(layer "B.SilkS")
			(effects
				(font
					(size 0.7 0.7)
					(thickness 0.15)
				)
				(justify left bottom mirror)
			)
		)
		(property "Value" "C_220n_0402"
			(at -1.022927 -2.155213 0)
			(layer "B.Fab")
			(effects
				(font
					(size 0.7 0.7)
					(thickness 0.15)
				)
				(justify left bottom mirror)
			)
		)
		(property "Datasheet" "https://www.yageo.com/en/Chart/Download/pdf/CC0402KRX5R6BB224"
			(at 0 0 0)
			(layer "B.Fab")
			(hide yes)
			(effects
				(font
					(size 1.27 1.27)
					(thickness 0.15)
				)
				(justify mirror)
			)
		)
		(property "Description" "SMD Multilayer Ceramic Capacitor, 0.22 µF, 10 V, 0402 [1005 Metric], ± 10%, X5R, CC Series"
			(at 0 0 0)
			(layer "B.Fab")
			(hide yes)
			(effects
				(font
					(size 1.27 1.27)
					(thickness 0.15)
				)
				(justify mirror)
			)
		)
		(property "MPN" "CC0402KRX5R6BB224"
			(at 0 0 180)
			(unlocked yes)
			(layer "B.Fab")
			(hide yes)
			(effects
				(font
					(size 1 1)
					(thickness 0.15)
				)
				(justify mirror)
			)
		)
		(property "Val" "220n"
			(at 0 0 180)
			(unlocked yes)
			(layer "B.Fab")
			(hide yes)
			(effects
				(font
					(size 1 1)
					(thickness 0.15)
				)
				(justify mirror)
			)
		)
		(property "Voltage" "25V"
			(at 0 0 180)
			(unlocked yes)
			(layer "B.Fab")
			(hide yes)
			(effects
				(font
					(size 1 1)
					(thickness 0.15)
				)
				(justify mirror)
			)
		)
		(property "Dielectric" "X7R"
			(at 0 0 180)
			(unlocked yes)
			(layer "B.Fab")
			(hide yes)
			(effects
				(font
					(size 1 1)
					(thickness 0.15)
				)
				(justify mirror)
			)
		)
		(property "Manufacturer" "YAGEO"
			(at 0 0 180)
			(unlocked yes)
			(layer "B.Fab")
			(hide yes)
			(effects
				(font
					(size 1 1)
					(thickness 0.15)
				)
				(justify mirror)
			)
		)
		(property "License" "Apache-2.0"
			(at 0 0 180)
			(unlocked yes)
			(layer "B.Fab")
			(hide yes)
			(effects
				(font
					(size 1 1)
					(thickness 0.15)
				)
				(justify mirror)
			)
		)
		(property "Author" "Antmicro"
			(at 0 0 180)
			(unlocked yes)
			(layer "B.Fab")
			(hide yes)
			(effects
				(font
					(size 1 1)
					(thickness 0.15)
				)
				(justify mirror)
			)
		)
		(property "Public" "False"
			(at 0 0 180)
			(unlocked yes)
			(layer "B.Fab")
			(hide yes)
			(effects
				(font
					(size 1 1)
					(thickness 0.15)
				)
				(justify mirror)
			)
		)
		(sheetname "/Expansion connector/")
		(sheetfile "expansion_connector.kicad_sch")
		(attr smd)
		(fp_rect
			(start -0.925 0.47)
			(end 0.925 -0.47)
			(stroke
				(width 0.05)
				(type default)
			)
			(fill no)
			(layer "B.CrtYd")
		)
		(fp_line
			(start 0.504 0.25)
			(end 0.504 -0.248)
			(stroke
				(width 0.15)
				(type solid)
			)
			(layer "B.Fab")
		)
		(fp_line
			(start 0.504 -0.248)
			(end -0.494 -0.248)
			(stroke
				(width 0.15)
				(type solid)
			)
			(layer "B.Fab")
		)
		(fp_line
			(start -0.494 0.25)
			(end 0.504 0.25)
			(stroke
				(width 0.15)
				(type solid)
			)
			(layer "B.Fab")
		)
		(fp_line
			(start -0.494 -0.248)
			(end -0.494 0.25)
			(stroke
				(width 0.15)
				(type solid)
			)
			(layer "B.Fab")
		)
		(fp_text user "License: Apache-2.0"
			(at -0.939 -5.799 0)
			(layer "B.Fab")
			(effects
				(font
					(size 0.7 0.7)
					(thickness 0.15)
				)
				(justify left bottom mirror)
			)
		)
		(fp_text user "${REFERENCE}"
			(at -0.939 -4.599 0)
			(layer "B.Fab")
			(effects
				(font
					(size 0.7 0.7)
					(thickness 0.15)
				)
				(justify left bottom mirror)
			)
		)
		(fp_text user "Author: Antmicro"
			(at -0.939 -3.399 0)
			(layer "B.Fab")
			(effects
				(font
					(size 0.7 0.7)
					(thickness 0.15)
				)
				(justify left bottom mirror)
			)
		)
		(pad "1" smd roundrect
			(at -0.48 0 180)
			(size 0.59 0.64)
			(layers "B.Cu" "B.Mask" "B.Paste")
			(roundrect_rratio 0.25)
			(net 516 "/Expansion connector/PCIe_{C2x1}.TX0-")
			(pintype "passive")
		)
		(pad "2" smd roundrect
			(at 0.48 0 180)
			(size 0.59 0.64)
			(layers "B.Cu" "B.Mask" "B.Paste")
			(roundrect_rratio 0.25)
			(net 479 "/Expansion connector/PET0_C2_N")
			(pintype "passive")
		)
	)
	(footprint "antmicro-footprints:TP_SMD_0.75mm"
		(layer "B.Cu")
		(at 199.8 122.6 180)
		(property "Reference" "TP2"
			(at 1 1.4 0)
			(layer "B.SilkS")
			(effects
				(font
					(size 0.7 0.7)
					(thickness 0.15)
				)
				(justify right top mirror)
			)
		)
		(property "Value" "TP_0.75mm_SMD"
			(at 0 -1.2 180)
			(layer "B.Fab")
			(effects
				(font
					(size 0.7 0.7)
					(thickness 0.15)
				)
				(justify right top mirror)
			)
		)
		(property "Description" "SMT test point"
			(at 0 0 180)
			(layer "B.Fab")
			(hide yes)
			(effects
				(font
					(size 1.27 1.27)
					(thickness 0.15)
				)
				(justify mirror)
			)
		)
		(property "MPN" ""
			(at 0 0 0)
			(unlocked yes)
			(layer "B.Fab")
			(hide yes)
			(effects
				(font
					(size 1 1)
					(thickness 0.15)
				)
				(justify mirror)
			)
		)
		(property "Manufacturer" ""
			(at 0 0 0)
			(unlocked yes)
			(layer "B.Fab")
			(hide yes)
			(effects
				(font
					(size 1 1)
					(thickness 0.15)
				)
				(justify mirror)
			)
		)
		(property "Author" "Antmicro"
			(at 0 0 0)
			(unlocked yes)
			(layer "B.Fab")
			(hide yes)
			(effects
				(font
					(size 1 1)
					(thickness 0.15)
				)
				(justify mirror)
			)
		)
		(property "License" "Apache-2.0"
			(at 0 0 0)
			(unlocked yes)
			(layer "B.Fab")
			(hide yes)
			(effects
				(font
					(size 1 1)
					(thickness 0.15)
				)
				(justify mirror)
			)
		)
		(sheetname "/USB Hub/")
		(sheetfile "usb_hub.kicad_sch")
		(attr exclude_from_pos_files exclude_from_bom)
		(fp_circle
			(center 0 0)
			(end 0.475 0)
			(stroke
				(width 0.05)
				(type default)
			)
			(fill no)
			(layer "B.CrtYd")
		)
		(fp_text user "Author: Antmicro"
			(at -0.4 -3.901 180)
			(layer "B.Fab")
			(effects
				(font
					(size 0.7 0.7)
					(thickness 0.15)
				)
				(justify right top mirror)
			)
		)
		(fp_text user "${REFERENCE}"
			(at -0.4 -2.7 180)
			(layer "B.Fab")
			(effects
				(font
					(size 0.7 0.7)
					(thickness 0.15)
				)
				(justify right top mirror)
			)
		)
		(fp_text user "License: Apache-2.0"
			(at -0.4 -5.101 180)
			(layer "B.Fab")
			(effects
				(font
					(size 0.7 0.7)
					(thickness 0.15)
				)
				(justify right top mirror)
			)
		)
		(pad "1" smd circle
			(at 0 0 180)
			(size 0.75 0.75)
			(layers "B.Cu" "B.Mask")
			(net 911 "/USB Hub/PRT_CTL2")
			(pinfunction "1")
			(pintype "passive")
		)
	)
	(footprint "antmicro-footprints:C_0402_1005Metric"
		(layer "B.Cu")
		(at 94 122.769999 180)
		(descr "Capacitor SMD 0402")
		(tags "capacitor SMD 0402")
		(property "Reference" "C220"
			(at -3.8 -0.625 0)
			(layer "B.SilkS")
			(effects
				(font
					(size 0.7 0.7)
					(thickness 0.15)
				)
				(justify left bottom mirror)
			)
		)
		(property "Value" "C_220n_0402"
			(at -1.022927 -2.155213 0)
			(layer "B.Fab")
			(effects
				(font
					(size 0.7 0.7)
					(thickness 0.15)
				)
				(justify left bottom mirror)
			)
		)
		(property "Datasheet" "https://www.yageo.com/en/Chart/Download/pdf/CC0402KRX5R6BB224"
			(at 0 0 0)
			(layer "B.Fab")
			(hide yes)
			(effects
				(font
					(size 1.27 1.27)
					(thickness 0.15)
				)
				(justify mirror)
			)
		)
		(property "Description" "SMD Multilayer Ceramic Capacitor, 0.22 µF, 10 V, 0402 [1005 Metric], ± 10%, X5R, CC Series"
			(at 0 0 0)
			(layer "B.Fab")
			(hide yes)
			(effects
				(font
					(size 1.27 1.27)
					(thickness 0.15)
				)
				(justify mirror)
			)
		)
		(property "MPN" "CC0402KRX5R6BB224"
			(at 0 0 180)
			(unlocked yes)
			(layer "B.Fab")
			(hide yes)
			(effects
				(font
					(size 1 1)
					(thickness 0.15)
				)
				(justify mirror)
			)
		)
		(property "Val" "220n"
			(at 0 0 180)
			(unlocked yes)
			(layer "B.Fab")
			(hide yes)
			(effects
				(font
					(size 1 1)
					(thickness 0.15)
				)
				(justify mirror)
			)
		)
		(property "Voltage" "25V"
			(at 0 0 180)
			(unlocked yes)
			(layer "B.Fab")
			(hide yes)
			(effects
				(font
					(size 1 1)
					(thickness 0.15)
				)
				(justify mirror)
			)
		)
		(property "Dielectric" "X7R"
			(at 0 0 180)
			(unlocked yes)
			(layer "B.Fab")
			(hide yes)
			(effects
				(font
					(size 1 1)
					(thickness 0.15)
				)
				(justify mirror)
			)
		)
		(property "Manufacturer" "YAGEO"
			(at 0 0 180)
			(unlocked yes)
			(layer "B.Fab")
			(hide yes)
			(effects
				(font
					(size 1 1)
					(thickness 0.15)
				)
				(justify mirror)
			)
		)
		(property "License" "Apache-2.0"
			(at 0 0 180)
			(unlocked yes)
			(layer "B.Fab")
			(hide yes)
			(effects
				(font
					(size 1 1)
					(thickness 0.15)
				)
				(justify mirror)
			)
		)
		(property "Author" "Antmicro"
			(at 0 0 180)
			(unlocked yes)
			(layer "B.Fab")
			(hide yes)
			(effects
				(font
					(size 1 1)
					(thickness 0.15)
				)
				(justify mirror)
			)
		)
		(property "Public" "False"
			(at 0 0 180)
			(unlocked yes)
			(layer "B.Fab")
			(hide yes)
			(effects
				(font
					(size 1 1)
					(thickness 0.15)
				)
				(justify mirror)
			)
		)
		(sheetname "/Expansion connector/")
		(sheetfile "expansion_connector.kicad_sch")
		(attr smd)
		(fp_poly
			(pts
				(xy -0.925 0.47) (xy 0.925 0.47) (xy 0.925 -0.47) (xy -0.925 -0.47)
			)
			(stroke
				(width 0.05)
				(type default)
			)
			(fill no)
			(layer "B.CrtYd")
		)
		(fp_line
			(start 0.504 0.25)
			(end 0.504 -0.248)
			(stroke
				(width 0.15)
				(type solid)
			)
			(layer "B.Fab")
		)
		(fp_line
			(start 0.504 -0.248)
			(end -0.494 -0.248)
			(stroke
				(width 0.15)
				(type solid)
			)
			(layer "B.Fab")
		)
		(fp_line
			(start -0.494 0.25)
			(end 0.504 0.25)
			(stroke
				(width 0.15)
				(type solid)
			)
			(layer "B.Fab")
		)
		(fp_line
			(start -0.494 -0.248)
			(end -0.494 0.25)
			(stroke
				(width 0.15)
				(type solid)
			)
			(layer "B.Fab")
		)
		(fp_text user "${REFERENCE}"
			(at -0.939 -4.599 0)
			(layer "B.Fab")
			(effects
				(font
					(size 0.7 0.7)
					(thickness 0.15)
				)
				(justify left bottom mirror)
			)
		)
		(fp_text user "License: Apache-2.0"
			(at -0.939 -5.799 0)
			(layer "B.Fab")
			(effects
				(font
					(size 0.7 0.7)
					(thickness 0.15)
				)
				(justify left bottom mirror)
			)
		)
		(fp_text user "Author: Antmicro"
			(at -0.939 -3.399 0)
			(layer "B.Fab")
			(effects
				(font
					(size 0.7 0.7)
					(thickness 0.15)
				)
				(justify left bottom mirror)
			)
		)
		(pad "1" smd roundrect
			(at -0.48 0 180)
			(size 0.59 0.64)
			(layers "B.Cu" "B.Mask" "B.Paste")
			(roundrect_rratio 0.25)
			(net 467 "/Expansion connector/PCIe_{C3x2}.TX1+")
			(pintype "passive")
		)
		(pad "2" smd roundrect
			(at 0.48 0 180)
			(size 0.59 0.64)
			(layers "B.Cu" "B.Mask" "B.Paste")
			(roundrect_rratio 0.25)
			(net 520 "/Expansion connector/PET1_C3_N")
			(pintype "passive")
		)
	)
	(footprint "antmicro-footprints:R_0402_1005Metric"
		(layer "B.Cu")
		(at 109.995 138.43 90)
		(descr "Resistor SMD 0402")
		(tags "resistor SMD 0402")
		(property "Reference" "R221"
			(at -1.35 -2.795 90)
			(layer "B.SilkS")
			(effects
				(font
					(size 0.7 0.7)
					(thickness 0.15)
				)
				(justify right top mirror)
			)
		)
		(property "Value" "R_200R_0402"
			(at -1.011843 -1.772047 90)
			(layer "B.Fab")
			(effects
				(font
					(size 0.7 0.7)
					(thickness 0.15)
				)
				(justify right top mirror)
			)
		)
		(property "Datasheet" "https://www.bourns.com/docs/product-datasheets/cr.pdf"
			(at 0 0 90)
			(layer "B.Fab")
			(hide yes)
			(effects
				(font
					(size 1.27 1.27)
					(thickness 0.15)
				)
				(justify mirror)
			)
		)
		(property "Description" "SMD Chip Resistor, 200 ohm, ± 1%, 62.5 mW, 0402 [1005 Metric], Thick Film, General Purpose"
			(at 0 0 90)
			(layer "B.Fab")
			(hide yes)
			(effects
				(font
					(size 1.27 1.27)
					(thickness 0.15)
				)
				(justify mirror)
			)
		)
		(property "MPN" "CR0402-FX-2000GLF"
			(at 0 0 270)
			(unlocked yes)
			(layer "B.Fab")
			(hide yes)
			(effects
				(font
					(size 1 1)
					(thickness 0.15)
				)
				(justify mirror)
			)
		)
		(property "Manufacturer" "Bourns"
			(at 0 0 270)
			(unlocked yes)
			(layer "B.Fab")
			(hide yes)
			(effects
				(font
					(size 1 1)
					(thickness 0.15)
				)
				(justify mirror)
			)
		)
		(property "License" "Apache-2.0"
			(at 0 0 270)
			(unlocked yes)
			(layer "B.Fab")
			(hide yes)
			(effects
				(font
					(size 1 1)
					(thickness 0.15)
				)
				(justify mirror)
			)
		)
		(property "Author" "Antmicro"
			(at 0 0 270)
			(unlocked yes)
			(layer "B.Fab")
			(hide yes)
			(effects
				(font
					(size 1 1)
					(thickness 0.15)
				)
				(justify mirror)
			)
		)
		(property "Val" "200R"
			(at 0 0 270)
			(unlocked yes)
			(layer "B.Fab")
			(hide yes)
			(effects
				(font
					(size 1 1)
					(thickness 0.15)
				)
				(justify mirror)
			)
		)
		(property "Tolerance" "1%"
			(at 0 0 270)
			(unlocked yes)
			(layer "B.Fab")
			(hide yes)
			(effects
				(font
					(size 1 1)
					(thickness 0.15)
				)
				(justify mirror)
			)
		)
		(sheetname "/M.2/")
		(sheetfile "m2.kicad_sch")
		(attr smd)
		(fp_rect
			(start -0.925 0.47)
			(end 0.925 -0.47)
			(stroke
				(width 0.05)
				(type default)
			)
			(fill no)
			(layer "B.CrtYd")
		)
		(fp_rect
			(start -0.5 0.25)
			(end 0.5 -0.25)
			(stroke
				(width 0.15)
				(type solid)
			)
			(fill no)
			(layer "B.Fab")
		)
		(fp_text user "License: Apache-2.0"
			(at -0.95 -5.169 90)
			(layer "B.Fab")
			(effects
				(font
					(size 0.7 0.7)
					(thickness 0.15)
				)
				(justify right top mirror)
			)
		)
		(fp_text user "Author: Antmicro"
			(at -0.95 -4.169 90)
			(layer "B.Fab")
			(effects
				(font
					(size 0.7 0.7)
					(thickness 0.15)
				)
				(justify right top mirror)
			)
		)
		(fp_text user "${REFERENCE}"
			(at -0.95 -3.168 90)
			(layer "B.Fab")
			(effects
				(font
					(size 0.7 0.7)
					(thickness 0.15)
				)
				(justify right top mirror)
			)
		)
		(pad "1" smd roundrect
			(at -0.48 0 90)
			(size 0.59 0.64)
			(layers "B.Cu" "B.Mask" "B.Paste")
			(roundrect_rratio 0.25)
			(net 545 "Net-(D33-A)")
			(pintype "passive")
		)
		(pad "2" smd roundrect
			(at 0.48 0 90)
			(size 0.59 0.64)
			(layers "B.Cu" "B.Mask" "B.Paste")
			(roundrect_rratio 0.25)
			(net 2 "+3V3")
			(pintype "passive")
		)
	)
	(footprint "antmicro-footprints:Vishay_PowerPAK_1212-8_Single"
		(layer "B.Cu")
		(at 183.08 75.564 90)
		(descr "PowerPAK 1212-8 Single")
		(tags "Vishay PowerPAK 1212-8 Single")
		(property "Reference" "Q25"
			(at -0.036 1.92 90)
			(layer "B.SilkS")
			(effects
				(font
					(size 0.7 0.7)
					(thickness 0.15)
				)
				(justify right top mirror)
			)
		)
		(property "Value" "SISS05DN-T1-GE3"
			(at 0 -2.7 90)
			(layer "B.Fab")
			(effects
				(font
					(size 0.7 0.7)
					(thickness 0.15)
				)
				(justify right top mirror)
			)
		)
		(property "Datasheet" "https://www.vishay.com/docs/77029/siss05dn.pdf"
			(at 0 0 90)
			(layer "B.Fab")
			(hide yes)
			(effects
				(font
					(size 1.27 1.27)
					(thickness 0.15)
				)
				(justify mirror)
			)
		)
		(property "Description" "Power MOSFET, P Channel, 30 V, 108 A, 0.0035 ohm, PowerPAK 1212, Surface Mount"
			(at 0 0 90)
			(layer "B.Fab")
			(hide yes)
			(effects
				(font
					(size 1.27 1.27)
					(thickness 0.15)
				)
				(justify mirror)
			)
		)
		(property "MPN" "SISS05DN-T1-GE3"
			(at 0 0 270)
			(unlocked yes)
			(layer "B.Fab")
			(hide yes)
			(effects
				(font
					(size 1 1)
					(thickness 0.15)
				)
				(justify mirror)
			)
		)
		(property "Manufacturer" "Vishay"
			(at 0 0 270)
			(unlocked yes)
			(layer "B.Fab")
			(hide yes)
			(effects
				(font
					(size 1 1)
					(thickness 0.15)
				)
				(justify mirror)
			)
		)
		(property "Author" "Antmicro"
			(at 0 0 270)
			(unlocked yes)
			(layer "B.Fab")
			(hide yes)
			(effects
				(font
					(size 1 1)
					(thickness 0.15)
				)
				(justify mirror)
			)
		)
		(property "License" "Apache-2.0"
			(at 0 0 270)
			(unlocked yes)
			(layer "B.Fab")
			(hide yes)
			(effects
				(font
					(size 1 1)
					(thickness 0.15)
				)
				(justify mirror)
			)
		)
		(sheetname "/Power/")
		(sheetfile "power.kicad_sch")
		(attr smd)
		(fp_line
			(start -1.635 -1.634)
			(end 1.634 -1.634)
			(stroke
				(width 0.15)
				(type solid)
			)
			(layer "B.SilkS")
		)
		(fp_line
			(start 1.634 -1.3)
			(end 1.634 -1.634)
			(stroke
				(width 0.15)
				(type solid)
			)
			(layer "B.SilkS")
		)
		(fp_line
			(start -1.635 -1.3)
			(end -1.635 -1.634)
			(stroke
				(width 0.15)
				(type solid)
			)
			(layer "B.SilkS")
		)
		(fp_line
			(start 1.648 1.651)
			(end 1.648 1.317)
			(stroke
				(width 0.15)
				(type solid)
			)
			(layer "B.SilkS")
		)
		(fp_line
			(start -1.651 1.651)
			(end -1.651 1.317)
			(stroke
				(width 0.15)
				(type solid)
			)
			(layer "B.SilkS")
		)
		(fp_line
			(start -1.651 1.651)
			(end 1.648 1.651)
			(stroke
				(width 0.15)
				(type solid)
			)
			(layer "B.SilkS")
		)
		(fp_circle
			(center -1.9 1.4)
			(end -1.85 1.4)
			(stroke
				(width 0.15)
				(type solid)
			)
			(fill yes)
			(layer "B.SilkS")
		)
		(fp_rect
			(start -2 1.8)
			(end 2 -1.798)
			(stroke
				(width 0.05)
				(type solid)
			)
			(fill no)
			(layer "B.CrtYd")
		)
		(fp_line
			(start -1.6425 1.4175)
			(end -1.4175 1.6425)
			(stroke
				(width 0.15)
				(type solid)
			)
			(layer "B.Fab")
		)
		(fp_rect
			(start -1.651 1.651)
			(end 1.648 -1.648)
			(stroke
				(width 0.15)
				(type solid)
			)
			(fill no)
			(layer "B.Fab")
		)
		(fp_text user "License: Apache-2.0"
			(at -8 -7.1 90)
			(layer "B.Fab")
			(effects
				(font
					(size 0.7 0.7)
					(thickness 0.15)
				)
				(justify right top mirror)
			)
		)
		(fp_text user "Author: Antmicro"
			(at -8 -5.9 90)
			(layer "B.Fab")
			(effects
				(font
					(size 0.7 0.7)
					(thickness 0.15)
				)
				(justify right top mirror)
			)
		)
		(fp_text user "${REFERENCE}"
			(at -8 -4.7 90)
			(layer "B.Fab")
			(effects
				(font
					(size 0.7 0.7)
					(thickness 0.15)
				)
				(justify right top mirror)
			)
		)
		(pad "1" smd rect
			(at -1.436 0.99 90)
			(size 0.99 0.405)
			(layers "B.Cu" "B.Mask" "B.Paste")
			(net 525 "/Power/USBPD2_HV")
			(pinfunction "S")
			(pintype "passive")
		)
		(pad "2" smd rect
			(at -1.436 0.332 90)
			(size 0.99 0.405)
			(layers "B.Cu" "B.Mask" "B.Paste")
			(net 525 "/Power/USBPD2_HV")
			(pinfunction "S")
			(pintype "passive")
		)
		(pad "3" smd rect
			(at -1.436 -0.33 90)
			(size 0.99 0.405)
			(layers "B.Cu" "B.Mask" "B.Paste")
			(net 525 "/Power/USBPD2_HV")
			(pinfunction "S")
			(pintype "passive")
		)
		(pad "4" smd rect
			(at -1.436 -0.988 90)
			(size 0.99 0.405)
			(layers "B.Cu" "B.Mask" "B.Paste")
			(net 1203 "Net-(Q25-G)")
			(pinfunction "G")
			(pintype "input")
		)
		(pad "5" smd custom
			(at 0.557 0 90)
			(size 1.725 2.235)
			(layers "B.Cu" "B.Mask" "B.Paste")
			(net 904 "+20V")
			(pinfunction "D")
			(pintype "passive")
			(zone_connect 2)
			(options
				(clearance outline)
				(anchor rect)
			)
			(primitives
				(gr_poly
					(pts
						(xy 0.8625 -0.1275) (xy 0.8625 0.1275) (xy 1.3725 0.1275) (xy 1.3725 0.5325) (xy 0.8625 0.5325)
						(xy 0.8625 0.7875) (xy 1.3725 0.7875) (xy 1.3725 1.195) (xy 0.6125 1.195) (xy 0.6125 -1.195) (xy 1.3725 -1.195)
						(xy 1.3725 -0.7875) (xy 0.8625 -0.7875) (xy 0.8625 -0.5325) (xy 1.3725 -0.5325) (xy 1.3725 -0.1275)
					)
					(width 0)
					(fill yes)
				)
			)
		)
	)
	(footprint "antmicro-footprints:R_0402_1005Metric"
		(layer "B.Cu")
		(at 238.1 80.45 180)
		(descr "Resistor SMD 0402")
		(tags "resistor SMD 0402")
		(property "Reference" "R149"
			(at -1.5 2.65 0)
			(layer "B.SilkS")
			(effects
				(font
					(size 0.7 0.7)
					(thickness 0.15)
				)
				(justify left bottom mirror)
			)
		)
		(property "Value" "R_0R_0402"
			(at -1.011843 -1.772046 0)
			(layer "B.Fab")
			(effects
				(font
					(size 0.7 0.7)
					(thickness 0.15)
				)
				(justify left bottom mirror)
			)
		)
		(property "Datasheet" "https://industrial.panasonic.com/cdbs/www-data/pdf/RDA0000/AOA0000C301.pdf"
			(at 0 0 0)
			(layer "B.Fab")
			(hide yes)
			(effects
				(font
					(size 1.27 1.27)
					(thickness 0.15)
				)
				(justify mirror)
			)
		)
		(property "Description" "SMD Chip Resistor, Jumper, 0 ohm, 100 mW, 0402 [1005 Metric], Thick Film, General Purpose"
			(at 0 0 0)
			(layer "B.Fab")
			(hide yes)
			(effects
				(font
					(size 1.27 1.27)
					(thickness 0.15)
				)
				(justify mirror)
			)
		)
		(property "Manufacturer" "Panasonic"
			(at 0 0 0)
			(unlocked yes)
			(layer "B.Fab")
			(hide yes)
			(effects
				(font
					(size 1 1)
					(thickness 0.15)
				)
				(justify mirror)
			)
		)
		(property "MPN" "ERJ2GE0R00X"
			(at 0 0 0)
			(unlocked yes)
			(layer "B.Fab")
			(hide yes)
			(effects
				(font
					(size 1 1)
					(thickness 0.15)
				)
				(justify mirror)
			)
		)
		(property "Val" "0R"
			(at 0 0 0)
			(unlocked yes)
			(layer "B.Fab")
			(hide yes)
			(effects
				(font
					(size 1 1)
					(thickness 0.15)
				)
				(justify mirror)
			)
		)
		(property "License" "Apache-2.0"
			(at 0 0 0)
			(unlocked yes)
			(layer "B.Fab")
			(hide yes)
			(effects
				(font
					(size 1 1)
					(thickness 0.15)
				)
				(justify mirror)
			)
		)
		(property "Author" "Antmicro"
			(at 0 0 0)
			(unlocked yes)
			(layer "B.Fab")
			(hide yes)
			(effects
				(font
					(size 1 1)
					(thickness 0.15)
				)
				(justify mirror)
			)
		)
		(property "Tolerance" "~"
			(at 0 0 0)
			(unlocked yes)
			(layer "B.Fab")
			(hide yes)
			(effects
				(font
					(size 1 1)
					(thickness 0.15)
				)
				(justify mirror)
			)
		)
		(property "Current" "1A"
			(at 0 0 0)
			(unlocked yes)
			(layer "B.Fab")
			(hide yes)
			(effects
				(font
					(size 1 1)
					(thickness 0.15)
				)
				(justify mirror)
			)
		)
		(sheetname "/USB Debug, PD/")
		(sheetfile "usb_debug_pd.kicad_sch")
		(attr smd exclude_from_pos_files exclude_from_bom dnp)
		(fp_poly
			(pts
				(xy -0.925 0.47) (xy -0.925 -0.47) (xy 0.925 -0.47) (xy 0.925 0.47)
			)
			(stroke
				(width 0.05)
				(type default)
			)
			(fill no)
			(layer "B.CrtYd")
		)
		(fp_poly
			(pts
				(xy -0.5 0.25) (xy -0.5 -0.25) (xy 0.5 -0.25) (xy 0.5 0.25)
			)
			(stroke
				(width 0.15)
				(type solid)
			)
			(fill no)
			(layer "B.Fab")
		)
		(fp_text user "${REFERENCE}"
			(at -0.95 -3.168 0)
			(layer "B.Fab")
			(effects
				(font
					(size 0.7 0.7)
					(thickness 0.15)
				)
				(justify left bottom mirror)
			)
		)
		(fp_text user "Author: Antmicro"
			(at -0.95 -4.169 0)
			(layer "B.Fab")
			(effects
				(font
					(size 0.7 0.7)
					(thickness 0.15)
				)
				(justify left bottom mirror)
			)
		)
		(fp_text user "License: Apache-2.0"
			(at -0.949999 -5.169 0)
			(layer "B.Fab")
			(effects
				(font
					(size 0.7 0.7)
					(thickness 0.15)
				)
				(justify left bottom mirror)
			)
		)
		(pad "1" smd roundrect
			(at -0.48 0 180)
			(size 0.59 0.64)
			(layers "B.Cu" "B.Mask" "B.Paste")
			(roundrect_rratio 0.25)
			(net 975 "/USB Debug, PD/USBC0_5V_PEN")
			(pintype "passive")
		)
		(pad "2" smd roundrect
			(at 0.48 0 180)
			(size 0.59 0.64)
			(layers "B.Cu" "B.Mask" "B.Paste")
			(roundrect_rratio 0.25)
			(net 5 "+5V")
			(pintype "passive")
		)
	)
	(footprint "antmicro-footprints:C_0402_1005Metric"
		(layer "B.Cu")
		(at 230.07 126.9 180)
		(descr "Capacitor SMD 0402")
		(tags "capacitor SMD 0402")
		(property "Reference" "C106"
			(at -2.13 -1.4 0)
			(layer "B.SilkS")
			(effects
				(font
					(size 0.7 0.7)
					(thickness 0.15)
				)
				(justify left bottom mirror)
			)
		)
		(property "Value" "C_100n_0402"
			(at -1.022927 -2.155213 0)
			(layer "B.Fab")
			(effects
				(font
					(size 0.7 0.7)
					(thickness 0.15)
				)
				(justify left bottom mirror)
			)
		)
		(property "Datasheet" "https://www.murata.com/products/productdetail?partno=GRM155R61H104KE14%23"
			(at 0 0 0)
			(layer "B.Fab")
			(hide yes)
			(effects
				(font
					(size 1.27 1.27)
					(thickness 0.15)
				)
				(justify mirror)
			)
		)
		(property "Description" "SMD Multilayer Ceramic Capacitor, 0.1 µF, 50 V, 0402 [1005 Metric], ± 10%, X5R, GRM Series"
			(at 0 0 0)
			(layer "B.Fab")
			(hide yes)
			(effects
				(font
					(size 1.27 1.27)
					(thickness 0.15)
				)
				(justify mirror)
			)
		)
		(property "Manufacturer" "Murata"
			(at 0 0 0)
			(unlocked yes)
			(layer "B.Fab")
			(hide yes)
			(effects
				(font
					(size 1 1)
					(thickness 0.15)
				)
				(justify mirror)
			)
		)
		(property "MPN" "GRM155R61H104KE14D"
			(at 0 0 0)
			(unlocked yes)
			(layer "B.Fab")
			(hide yes)
			(effects
				(font
					(size 1 1)
					(thickness 0.15)
				)
				(justify mirror)
			)
		)
		(property "Val" "100n"
			(at 0 0 0)
			(unlocked yes)
			(layer "B.Fab")
			(hide yes)
			(effects
				(font
					(size 1 1)
					(thickness 0.15)
				)
				(justify mirror)
			)
		)
		(property "License" "Apache-2.0"
			(at 0 0 0)
			(unlocked yes)
			(layer "B.Fab")
			(hide yes)
			(effects
				(font
					(size 1 1)
					(thickness 0.15)
				)
				(justify mirror)
			)
		)
		(property "Author" "Antmicro"
			(at 0 0 0)
			(unlocked yes)
			(layer "B.Fab")
			(hide yes)
			(effects
				(font
					(size 1 1)
					(thickness 0.15)
				)
				(justify mirror)
			)
		)
		(property "Voltage" "50V"
			(at 0 0 0)
			(unlocked yes)
			(layer "B.Fab")
			(hide yes)
			(effects
				(font
					(size 1 1)
					(thickness 0.15)
				)
				(justify mirror)
			)
		)
		(property "Dielectric" "X5R"
			(at 0 0 0)
			(unlocked yes)
			(layer "B.Fab")
			(hide yes)
			(effects
				(font
					(size 1 1)
					(thickness 0.15)
				)
				(justify mirror)
			)
		)
		(sheetname "/USB Hub/")
		(sheetfile "usb_hub.kicad_sch")
		(attr smd)
		(fp_poly
			(pts
				(xy -0.925 0.47) (xy 0.925 0.47) (xy 0.925 -0.47) (xy -0.925 -0.47)
			)
			(stroke
				(width 0.05)
				(type default)
			)
			(fill no)
			(layer "B.CrtYd")
		)
		(fp_line
			(start 0.504 0.25)
			(end 0.504 -0.248)
			(stroke
				(width 0.15)
				(type solid)
			)
			(layer "B.Fab")
		)
		(fp_line
			(start 0.504 -0.248)
			(end -0.494 -0.248)
			(stroke
				(width 0.15)
				(type solid)
			)
			(layer "B.Fab")
		)
		(fp_line
			(start -0.494 0.25)
			(end 0.504 0.25)
			(stroke
				(width 0.15)
				(type solid)
			)
			(layer "B.Fab")
		)
		(fp_line
			(start -0.494 -0.248)
			(end -0.494 0.25)
			(stroke
				(width 0.15)
				(type solid)
			)
			(layer "B.Fab")
		)
		(fp_text user "Author: Antmicro"
			(at -0.939 -3.399 0)
			(layer "B.Fab")
			(effects
				(font
					(size 0.7 0.7)
					(thickness 0.15)
				)
				(justify left bottom mirror)
			)
		)
		(fp_text user "License: Apache-2.0"
			(at -0.939 -5.799 0)
			(layer "B.Fab")
			(effects
				(font
					(size 0.7 0.7)
					(thickness 0.15)
				)
				(justify left bottom mirror)
			)
		)
		(fp_text user "${REFERENCE}"
			(at -0.939 -4.599 0)
			(layer "B.Fab")
			(effects
				(font
					(size 0.7 0.7)
					(thickness 0.15)
				)
				(justify left bottom mirror)
			)
		)
		(pad "1" smd roundrect
			(at -0.48 0 180)
			(size 0.59 0.64)
			(layers "B.Cu" "B.Mask" "B.Paste")
			(roundrect_rratio 0.25)
			(net 115 "/USB Hub/USBC4_VBUS")
			(pintype "passive")
		)
		(pad "2" smd roundrect
			(at 0.48 0 180)
			(size 0.59 0.64)
			(layers "B.Cu" "B.Mask" "B.Paste")
			(roundrect_rratio 0.25)
			(net 1 "GND")
			(pintype "passive")
		)
	)
	(footprint "antmicro-footprints:R_0402_1005Metric"
		(layer "B.Cu")
		(at 208.726 147 180)
		(descr "Resistor SMD 0402")
		(tags "resistor SMD 0402")
		(property "Reference" "R198"
			(at -3.8 -0.55 0)
			(layer "B.SilkS")
			(effects
				(font
					(size 0.7 0.7)
					(thickness 0.15)
				)
				(justify left bottom mirror)
			)
		)
		(property "Value" "R_0R_0402"
			(at -1.011843 -1.772047 0)
			(layer "B.Fab")
			(effects
				(font
					(size 0.7 0.7)
					(thickness 0.15)
				)
				(justify left bottom mirror)
			)
		)
		(property "Datasheet" "https://industrial.panasonic.com/cdbs/www-data/pdf/RDA0000/AOA0000C301.pdf"
			(at 0 0 0)
			(layer "B.Fab")
			(hide yes)
			(effects
				(font
					(size 1.27 1.27)
					(thickness 0.15)
				)
				(justify mirror)
			)
		)
		(property "Description" "SMD Chip Resistor, Jumper, 0 ohm, 100 mW, 0402 [1005 Metric], Thick Film, General Purpose"
			(at 0 0 0)
			(layer "B.Fab")
			(hide yes)
			(effects
				(font
					(size 1.27 1.27)
					(thickness 0.15)
				)
				(justify mirror)
			)
		)
		(property "MPN" "ERJ2GE0R00X"
			(at 0 0 0)
			(unlocked yes)
			(layer "B.Fab")
			(hide yes)
			(effects
				(font
					(size 1 1)
					(thickness 0.15)
				)
				(justify mirror)
			)
		)
		(property "Manufacturer" "Panasonic"
			(at 0 0 0)
			(unlocked yes)
			(layer "B.Fab")
			(hide yes)
			(effects
				(font
					(size 1 1)
					(thickness 0.15)
				)
				(justify mirror)
			)
		)
		(property "License" "Apache-2.0"
			(at 0 0 0)
			(unlocked yes)
			(layer "B.Fab")
			(hide yes)
			(effects
				(font
					(size 1 1)
					(thickness 0.15)
				)
				(justify mirror)
			)
		)
		(property "Author" "Antmicro"
			(at 0 0 0)
			(unlocked yes)
			(layer "B.Fab")
			(hide yes)
			(effects
				(font
					(size 1 1)
					(thickness 0.15)
				)
				(justify mirror)
			)
		)
		(property "Val" "0R"
			(at 0 0 0)
			(unlocked yes)
			(layer "B.Fab")
			(hide yes)
			(effects
				(font
					(size 1 1)
					(thickness 0.15)
				)
				(justify mirror)
			)
		)
		(property "Tolerance" "~"
			(at 0 0 0)
			(unlocked yes)
			(layer "B.Fab")
			(hide yes)
			(effects
				(font
					(size 1 1)
					(thickness 0.15)
				)
				(justify mirror)
			)
		)
		(property "Current" "1A"
			(at 0 0 0)
			(unlocked yes)
			(layer "B.Fab")
			(hide yes)
			(effects
				(font
					(size 1 1)
					(thickness 0.15)
				)
				(justify mirror)
			)
		)
		(sheetname "/SFP/")
		(sheetfile "sfp.kicad_sch")
		(attr smd)
		(fp_rect
			(start -0.925 0.47)
			(end 0.925 -0.47)
			(stroke
				(width 0.05)
				(type default)
			)
			(fill no)
			(layer "B.CrtYd")
		)
		(fp_rect
			(start -0.5 0.25)
			(end 0.5 -0.25)
			(stroke
				(width 0.15)
				(type solid)
			)
			(fill no)
			(layer "B.Fab")
		)
		(fp_text user "${REFERENCE}"
			(at -0.95 -3.168 0)
			(layer "B.Fab")
			(effects
				(font
					(size 0.7 0.7)
					(thickness 0.15)
				)
				(justify left bottom mirror)
			)
		)
		(fp_text user "License: Apache-2.0"
			(at -0.95 -5.169 0)
			(layer "B.Fab")
			(effects
				(font
					(size 0.7 0.7)
					(thickness 0.15)
				)
				(justify left bottom mirror)
			)
		)
		(fp_text user "Author: Antmicro"
			(at -0.95 -4.169 0)
			(layer "B.Fab")
			(effects
				(font
					(size 0.7 0.7)
					(thickness 0.15)
				)
				(justify left bottom mirror)
			)
		)
		(pad "1" smd roundrect
			(at -0.48 0 180)
			(size 0.59 0.64)
			(layers "B.Cu" "B.Mask" "B.Paste")
			(roundrect_rratio 0.25)
			(net 1 "GND")
			(pintype "passive")
		)
		(pad "2" smd roundrect
			(at 0.48 0 180)
			(size 0.59 0.64)
			(layers "B.Cu" "B.Mask" "B.Paste")
			(roundrect_rratio 0.25)
			(net 1367 "Net-(J12-TX_{DISABLE})")
			(pintype "passive")
		)
	)
	(footprint "antmicro-footprints:Bus_M.2_Socket_Key_E_TE_2199230-6"
		(locked yes)
		(layer "B.Cu")
		(at 117.46 129.51 -90)
		(property "Reference" "J14"
			(at 11.45 -5.015 0)
			(layer "B.SilkS")
			(effects
				(font
					(size 0.7 0.7)
					(thickness 0.15)
				)
				(justify left bottom mirror)
			)
		)
		(property "Value" "Bus_M.2_2199230-2"
			(at -10.999 -5.75 90)
			(layer "B.Fab")
			(effects
				(font
					(size 0.7 0.7)
					(thickness 0.15)
				)
				(justify left bottom mirror)
			)
		)
		(property "Datasheet" "https://eu.mouser.com/datasheet/2/418/9/ENG_DS_1_1773702_1NGFFQRG_EN_0214_1_1773702_1NGFF_-3328593.pdf"
			(at 0 0 90)
			(layer "B.Fab")
			(hide yes)
			(effects
				(font
					(size 1.27 1.27)
					(thickness 0.15)
				)
				(justify mirror)
			)
		)
		(property "Description" "Key E, PCI connector"
			(at 0 0 90)
			(layer "B.Fab")
			(hide yes)
			(effects
				(font
					(size 1.27 1.27)
					(thickness 0.15)
				)
				(justify mirror)
			)
		)
		(property "MPN" "2199230-2"
			(at 0 0 90)
			(unlocked yes)
			(layer "B.Fab")
			(hide yes)
			(effects
				(font
					(size 1 1)
					(thickness 0.15)
				)
				(justify mirror)
			)
		)
		(property "Manufacturer" "TE Connectivity"
			(at 0 0 90)
			(unlocked yes)
			(layer "B.Fab")
			(hide yes)
			(effects
				(font
					(size 1 1)
					(thickness 0.15)
				)
				(justify mirror)
			)
		)
		(property "Author" "Antmicro"
			(at 0 0 90)
			(unlocked yes)
			(layer "B.Fab")
			(hide yes)
			(effects
				(font
					(size 1 1)
					(thickness 0.15)
				)
				(justify mirror)
			)
		)
		(property "License" "Apache-2.0"
			(at 0 0 90)
			(unlocked yes)
			(layer "B.Fab")
			(hide yes)
			(effects
				(font
					(size 1 1)
					(thickness 0.15)
				)
				(justify mirror)
			)
		)
		(sheetname "/M.2/")
		(sheetfile "m2.kicad_sch")
		(attr smd)
		(fp_line
			(start -3.499 3.899)
			(end -1.499 3.899)
			(stroke
				(width 0.15)
				(type solid)
			)
			(layer "B.SilkS")
		)
		(fp_line
			(start 10.999 1.5)
			(end 10.999 -2.85)
			(stroke
				(width 0.15)
				(type solid)
			)
			(layer "B.SilkS")
		)
		(fp_line
			(start -10.999 -2.85)
			(end -10.999 1.5)
			(stroke
				(width 0.15)
				(type solid)
			)
			(layer "B.SilkS")
		)
		(fp_line
			(start -9.599 -2.85)
			(end -10.999 -2.85)
			(stroke
				(width 0.15)
				(type solid)
			)
			(layer "B.SilkS")
		)
		(fp_line
			(start -9.599 -2.85)
			(end -9.599 -4.1)
			(stroke
				(width 0.15)
				(type solid)
			)
			(layer "B.SilkS")
		)
		(fp_line
			(start 10.999 -2.85)
			(end 9.601 -2.85)
			(stroke
				(width 0.15)
				(type solid)
			)
			(layer "B.SilkS")
		)
		(fp_line
			(start -9.599 -4.1)
			(end -9.249 -4.1)
			(stroke
				(width 0.15)
				(type solid)
			)
			(layer "B.SilkS")
		)
		(fp_line
			(start -3.75 -4.1)
			(end -1.75 -4.1)
			(stroke
				(width 0.15)
				(type solid)
			)
			(layer "B.SilkS")
		)
		(fp_line
			(start 9.251 -4.1)
			(end 9.601 -4.1)
			(stroke
				(width 0.15)
				(type solid)
			)
			(layer "B.SilkS")
		)
		(fp_line
			(start 9.601 -4.1)
			(end 9.601 -2.85)
			(stroke
				(width 0.15)
				(type solid)
			)
			(layer "B.SilkS")
		)
		(fp_circle
			(center -9.249 5.64)
			(end -9.199 5.64)
			(stroke
				(width 0.15)
				(type solid)
			)
			(fill yes)
			(layer "B.SilkS")
		)
		(fp_rect
			(start -11.94 5.34)
			(end 11.95 -5.35)
			(stroke
				(width 0.05)
				(type solid)
			)
			(fill no)
			(layer "B.CrtYd")
		)
		(fp_line
			(start -9.999 0.25)
			(end 9.999 0.25)
			(stroke
				(width 0.15)
				(type solid)
			)
			(layer "B.Fab")
		)
		(fp_text user "Author: Antmicro"
			(at -11.94 -10.15 90)
			(layer "B.Fab")
			(effects
				(font
					(size 0.7 0.7)
					(thickness 0.15)
				)
				(justify left bottom mirror)
			)
		)
		(fp_text user "${REFERENCE}"
			(at -11.94 -8.95 90)
			(layer "B.Fab")
			(effects
				(font
					(size 0.7 0.7)
					(thickness 0.15)
				)
				(justify left bottom mirror)
			)
		)
		(fp_text user "License: Apache-2.0"
			(at -11.94 -7.75 90)
			(layer "B.Fab")
			(effects
				(font
					(size 0.7 0.7)
					(thickness 0.15)
				)
				(justify left bottom mirror)
			)
		)
		(pad "" np_thru_hole circle
			(at -9.999 -1.499 270)
			(size 1.1 1.1)
			(drill 1.1)
			(layers "*.Cu" "*.Mask")
		)
		(pad "" np_thru_hole circle
			(at 9.999 -1.499 270)
			(size 1.6 1.6)
			(drill 1.6)
			(layers "*.Cu" "*.Mask")
		)
		(pad "1" smd rect
			(at -9.249 3.749 270)
			(size 0.3 1.55)
			(layers "B.Cu" "B.Mask" "B.Paste")
			(net 1 "GND")
			(pinfunction "GND")
			(pintype "power_in")
		)
		(pad "2" smd rect
			(at -9.001 -3.749 270)
			(size 0.3 1.55)
			(layers "B.Cu" "B.Mask" "B.Paste")
			(net 2 "+3V3")
			(pinfunction "3.3V")
			(pintype "power_in")
		)
		(pad "3" smd rect
			(at -8.751 3.749 270)
			(size 0.3 1.55)
			(layers "B.Cu" "B.Mask" "B.Paste")
			(net 272 "/M.2/WIFI_BT_USB_D_P")
			(pinfunction "USB_D_P")
			(pintype "bidirectional")
		)
		(pad "4" smd rect
			(at -8.501 -3.749 270)
			(size 0.3 1.55)
			(layers "B.Cu" "B.Mask" "B.Paste")
			(net 2 "+3V3")
			(pinfunction "3.3V")
			(pintype "passive")
		)
		(pad "5" smd rect
			(at -8.251 3.749 270)
			(size 0.3 1.55)
			(layers "B.Cu" "B.Mask" "B.Paste")
			(net 259 "/M.2/WIFI_BT_USB_D_N")
			(pinfunction "USB_D_N")
			(pintype "bidirectional")
		)
		(pad "6" smd rect
			(at -8 -3.749 270)
			(size 0.3 1.55)
			(layers "B.Cu" "B.Mask" "B.Paste")
			(net 34 "/M.2/~{LED_1}")
			(pinfunction "~{LED_1}")
			(pintype "output")
		)
		(pad "7" smd rect
			(at -7.75 3.749 270)
			(size 0.3 1.55)
			(layers "B.Cu" "B.Mask" "B.Paste")
			(net 1 "GND")
			(pinfunction "GND")
			(pintype "passive")
		)
		(pad "8" smd rect
			(at -7.5 -3.749 270)
			(size 0.3 1.55)
			(layers "B.Cu" "B.Mask" "B.Paste")
			(net 255 "unconnected-(J14-PCM_CLK-Pad8)")
			(pinfunction "PCM_CLK")
			(pintype "bidirectional+no_connect")
		)
		(pad "9" smd rect
			(at -7.25 3.749 270)
			(size 0.3 1.55)
			(layers "B.Cu" "B.Mask" "B.Paste")
			(net 277 "unconnected-(J14-SDIO_CLK-Pad9)")
			(pinfunction "SDIO_CLK")
			(pintype "input+no_connect")
		)
		(pad "10" smd rect
			(at -7 -3.749 270)
			(size 0.3 1.55)
			(layers "B.Cu" "B.Mask" "B.Paste")
			(net 1007 "unconnected-(J14-PCM_SYNC-Pad10)")
			(pinfunction "PCM_SYNC")
			(pintype "bidirectional+no_connect")
		)
		(pad "11" smd rect
			(at -6.75 3.749 270)
			(size 0.3 1.55)
			(layers "B.Cu" "B.Mask" "B.Paste")
			(net 254 "unconnected-(J14-SDIO_CMD-Pad11)")
			(pinfunction "SDIO_CMD")
			(pintype "bidirectional+no_connect")
		)
		(pad "12" smd rect
			(at -6.5 -3.749 270)
			(size 0.3 1.55)
			(layers "B.Cu" "B.Mask" "B.Paste")
			(net 1006 "unconnected-(J14-PCM_IN-Pad12)")
			(pinfunction "PCM_IN")
			(pintype "bidirectional+no_connect")
		)
		(pad "13" smd rect
			(at -6.25 3.749 270)
			(size 0.3 1.55)
			(layers "B.Cu" "B.Mask" "B.Paste")
			(net 268 "unconnected-(J14-SDIO_D0-Pad13)")
			(pinfunction "SDIO_D0")
			(pintype "bidirectional+no_connect")
		)
		(pad "14" smd rect
			(at -6 -3.749 270)
			(size 0.3 1.55)
			(layers "B.Cu" "B.Mask" "B.Paste")
			(net 274 "unconnected-(J14-PCM_OUT-Pad14)")
			(pinfunction "PCM_OUT")
			(pintype "bidirectional+no_connect")
		)
		(pad "15" smd rect
			(at -5.75 3.749 270)
			(size 0.3 1.55)
			(layers "B.Cu" "B.Mask" "B.Paste")
			(net 262 "unconnected-(J14-SDIO_D1-Pad15)")
			(pinfunction "SDIO_D1")
			(pintype "bidirectional+no_connect")
		)
		(pad "16" smd rect
			(at -5.5 -3.749 270)
			(size 0.3 1.55)
			(layers "B.Cu" "B.Mask" "B.Paste")
			(net 35 "/M.2/~{LED_2}")
			(pinfunction "~{LED_2}")
			(pintype "output")
		)
		(pad "17" smd rect
			(at -5.25 3.749 270)
			(size 0.3 1.55)
			(layers "B.Cu" "B.Mask" "B.Paste")
			(net 266 "unconnected-(J14-SDIO_D2-Pad17)")
			(pinfunction "SDIO_D2")
			(pintype "bidirectional+no_connect")
		)
		(pad "18" smd rect
			(at -5.001 -3.749 270)
			(size 0.3 1.55)
			(layers "B.Cu" "B.Mask" "B.Paste")
			(net 1 "GND")
			(pinfunction "GND")
			(pintype "passive")
		)
		(pad "19" smd rect
			(at -4.751 3.749 270)
			(size 0.3 1.55)
			(layers "B.Cu" "B.Mask" "B.Paste")
			(net 258 "unconnected-(J14-SDIO_D3-Pad19)")
			(pinfunction "SDIO_D3")
			(pintype "bidirectional+no_connect")
		)
		(pad "20" smd rect
			(at -4.501 -3.749 270)
			(size 0.3 1.55)
			(layers "B.Cu" "B.Mask" "B.Paste")
			(net 1337 "unconnected-(J14-~{UART_WAKE}-Pad20)")
			(pinfunction "~{UART_WAKE}")
			(pintype "output+no_connect")
		)
		(pad "21" smd rect
			(at -4.251 3.749 270)
			(size 0.3 1.55)
			(layers "B.Cu" "B.Mask" "B.Paste")
			(net 240 "unconnected-(J14-SDIO_~{WAKE}-Pad21)")
			(pinfunction "SDIO_~{WAKE}")
			(pintype "bidirectional+no_connect")
		)
		(pad "22" smd rect
			(at -4.001 -3.749 270)
			(size 0.3 1.55)
			(layers "B.Cu" "B.Mask" "B.Paste")
			(net 250 "unconnected-(J14-UART_RXD-Pad22)")
			(pinfunction "UART_RXD")
			(pintype "bidirectional+no_connect")
		)
		(pad "23" smd rect
			(at -3.75 3.749 270)
			(size 0.3 1.55)
			(layers "B.Cu" "B.Mask" "B.Paste")
			(net 275 "unconnected-(J14-SDIO_~{RESET}-Pad23)")
			(pinfunction "SDIO_~{RESET}")
			(pintype "input+no_connect")
		)
		(pad "32" smd rect
			(at -1.5 -3.749 270)
			(size 0.3 1.55)
			(layers "B.Cu" "B.Mask" "B.Paste")
			(net 263 "unconnected-(J14-UART_TXD-Pad32)")
			(pinfunction "UART_TXD")
			(pintype "bidirectional+no_connect")
		)
		(pad "33" smd rect
			(at -1.25 3.749 270)
			(size 0.3 1.55)
			(layers "B.Cu" "B.Mask" "B.Paste")
			(net 1 "GND")
			(pinfunction "GND")
			(pintype "passive")
		)
		(pad "34" smd rect
			(at -1 -3.749 270)
			(size 0.3 1.55)
			(layers "B.Cu" "B.Mask" "B.Paste")
			(net 273 "unconnected-(J14-UART_CTS-Pad34)")
			(pinfunction "UART_CTS")
			(pintype "bidirectional+no_connect")
		)
		(pad "35" smd rect
			(at -0.75 3.749 270)
			(size 0.3 1.55)
			(layers "B.Cu" "B.Mask" "B.Paste")
			(net 444 "/M.2/M2_E_PET0_N")
			(pinfunction "PET0_P")
			(pintype "input")
		)
		(pad "36" smd rect
			(at -0.5 -3.749 270)
			(size 0.3 1.55)
			(layers "B.Cu" "B.Mask" "B.Paste")
			(net 267 "unconnected-(J14-UART_RTS-Pad36)")
			(pinfunction "UART_RTS")
			(pintype "bidirectional+no_connect")
		)
		(pad "37" smd rect
			(at -0.25 3.749 270)
			(size 0.3 1.55)
			(layers "B.Cu" "B.Mask" "B.Paste")
			(net 440 "/M.2/M2_E_PET0_P")
			(pinfunction "PET0_N")
			(pintype "input")
		)
		(pad "38" smd rect
			(at 0 -3.749 270)
			(size 0.3 1.55)
			(layers "B.Cu" "B.Mask" "B.Paste")
			(net 1336 "unconnected-(J14-VENDOR_1-Pad38)")
			(pinfunction "VENDOR_1")
			(pintype "bidirectional+no_connect")
		)
		(pad "39" smd rect
			(at 0.25 3.749 270)
			(size 0.3 1.55)
			(layers "B.Cu" "B.Mask" "B.Paste")
			(net 1 "GND")
			(pinfunction "GND")
			(pintype "passive")
		)
		(pad "40" smd rect
			(at 0.5 -3.749 270)
			(size 0.3 1.55)
			(layers "B.Cu" "B.Mask" "B.Paste")
			(net 1334 "unconnected-(J14-VENDOR_2-Pad40)")
			(pinfunction "VENDOR_2")
			(pintype "bidirectional+no_connect")
		)
		(pad "41" smd rect
			(at 0.75 3.749 270)
			(size 0.3 1.55)
			(layers "B.Cu" "B.Mask" "B.Paste")
			(net 130 "/M.2/PCIe_{C1x1}.RX0+")
			(pinfunction "PER0_P")
			(pintype "output")
		)
		(pad "42" smd rect
			(at 1 -3.749 270)
			(size 0.3 1.55)
			(layers "B.Cu" "B.Mask" "B.Paste")
			(net 1335 "unconnected-(J14-VENDOR_3-Pad42)")
			(pinfunction "VENDOR_3")
			(pintype "bidirectional+no_connect")
		)
		(pad "43" smd rect
			(at 1.25 3.749 270)
			(size 0.3 1.55)
			(layers "B.Cu" "B.Mask" "B.Paste")
			(net 94 "/M.2/PCIe_{C1x1}.RX0-")
			(pinfunction "PER0_N")
			(pintype "output")
		)
		(pad "44" smd rect
			(at 1.5 -3.749 270)
			(size 0.3 1.55)
			(layers "B.Cu" "B.Mask" "B.Paste")
			(net 248 "unconnected-(J14-COEX3-Pad44)")
			(pinfunction "COEX3")
			(pintype "bidirectional+no_connect")
		)
		(pad "45" smd rect
			(at 1.75 3.749 270)
			(size 0.3 1.55)
			(layers "B.Cu" "B.Mask" "B.Paste")
			(net 1 "GND")
			(pinfunction "GND")
			(pintype "passive")
		)
		(pad "46" smd rect
			(at 2 -3.749 270)
			(size 0.3 1.55)
			(layers "B.Cu" "B.Mask" "B.Paste")
			(net 261 "unconnected-(J14-COEX_TXD-Pad46)")
			(pinfunction "COEX_TXD")
			(pintype "bidirectional+no_connect")
		)
		(pad "47" smd rect
			(at 2.25 3.749 270)
			(size 0.3 1.55)
			(layers "B.Cu" "B.Mask" "B.Paste")
			(net 676 "/M.2/PCIe_{C1x1}.CLK-")
			(pinfunction "REFCLK0_P")
			(pintype "input")
		)
		(pad "48" smd rect
			(at 2.5 -3.749 270)
			(size 0.3 1.55)
			(layers "B.Cu" "B.Mask" "B.Paste")
			(net 252 "unconnected-(J14-COEX_RXD-Pad48)")
			(pinfunction "COEX_RXD")
			(pintype "bidirectional+no_connect")
		)
		(pad "49" smd rect
			(at 2.75 3.749 270)
			(size 0.3 1.55)
			(layers "B.Cu" "B.Mask" "B.Paste")
			(net 589 "/M.2/PCIe_{C1x1}.CLK+")
			(pinfunction "REFCLK0_N")
			(pintype "input")
		)
		(pad "50" smd rect
			(at 3 -3.749 270)
			(size 0.3 1.55)
			(layers "B.Cu" "B.Mask" "B.Paste")
			(net 832 "/M.2/M2_E_SUSCLK")
			(pinfunction "SUSCLK")
			(pintype "input")
		)
		(pad "51" smd rect
			(at 3.25 3.749 270)
			(size 0.3 1.55)
			(layers "B.Cu" "B.Mask" "B.Paste")
			(net 1 "GND")
			(pinfunction "GND")
			(pintype "passive")
		)
		(pad "52" smd rect
			(at 3.5 -3.749 270)
			(size 0.3 1.55)
			(layers "B.Cu" "B.Mask" "B.Paste")
			(net 831 "/M.2/~{PERST_E}")
			(pinfunction "~{PERST0}")
			(pintype "input")
		)
		(pad "53" smd rect
			(at 3.75 3.749 270)
			(size 0.3 1.55)
			(layers "B.Cu" "B.Mask" "B.Paste")
			(net 834 "/M.2/~{CLKREQ_E}")
			(pinfunction "~{CLKREQ0}")
			(pintype "output")
		)
		(pad "54" smd rect
			(at 4 -3.749 270)
			(size 0.3 1.55)
			(layers "B.Cu" "B.Mask" "B.Paste")
			(net 247 "/M.2/M2_E_W_DIS_2")
			(pinfunction "W_DISABLE2")
			(pintype "input")
		)
		(pad "55" smd rect
			(at 4.25 3.749 270)
			(size 0.3 1.55)
			(layers "B.Cu" "B.Mask" "B.Paste")
			(net 833 "/M.2/~{PEWAKE_E}")
			(pinfunction "~{PEWAKE0}")
			(pintype "output")
		)
		(pad "56" smd rect
			(at 4.5 -3.749 270)
			(size 0.3 1.55)
			(layers "B.Cu" "B.Mask" "B.Paste")
			(net 244 "/M.2/M2_E_W_DIS_1")
			(pinfunction "W_DISABLE1")
			(pintype "input")
		)
		(pad "57" smd rect
			(at 4.75 3.749 270)
			(size 0.3 1.55)
			(layers "B.Cu" "B.Mask" "B.Paste")
			(net 1 "GND")
			(pinfunction "GND")
			(pintype "passive")
		)
		(pad "58" smd rect
			(at 5 -3.749 270)
			(size 0.3 1.55)
			(layers "B.Cu" "B.Mask" "B.Paste")
			(net 256 "unconnected-(J14-I2C_DATA-Pad58)")
			(pinfunction "I2C_DATA")
			(pintype "bidirectional+no_connect")
		)
		(pad "59" smd rect
			(at 5.25 3.749 270)
			(size 0.3 1.55)
			(layers "B.Cu" "B.Mask" "B.Paste")
			(net 830 "unconnected-(J14-PET1_P-Pad59)")
			(pinfunction "PET1_P")
			(pintype "input+no_connect")
		)
		(pad "60" smd rect
			(at 5.5 -3.749 270)
			(size 0.3 1.55)
			(layers "B.Cu" "B.Mask" "B.Paste")
			(net 264 "unconnected-(J14-I2C_CLK-Pad60)")
			(pinfunction "I2C_CLK")
			(pintype "bidirectional+no_connect")
		)
		(pad "61" smd rect
			(at 5.75 3.749 270)
			(size 0.3 1.55)
			(layers "B.Cu" "B.Mask" "B.Paste")
			(net 835 "unconnected-(J14-PET1_N-Pad61)")
			(pinfunction "PET1_N")
			(pintype "input+no_connect")
		)
		(pad "62" smd rect
			(at 6 -3.749 270)
			(size 0.3 1.55)
			(layers "B.Cu" "B.Mask" "B.Paste")
			(net 257 "/M.2/~{M2_E_ALERT}")
			(pinfunction "~{ALERT}")
			(pintype "output")
		)
		(pad "63" smd rect
			(at 6.25 3.749 270)
			(size 0.3 1.55)
			(layers "B.Cu" "B.Mask" "B.Paste")
			(net 1 "GND")
			(pinfunction "GND")
			(pintype "passive")
		)
		(pad "64" smd rect
			(at 6.5 -3.749 270)
			(size 0.3 1.55)
			(layers "B.Cu" "B.Mask" "B.Paste")
			(net 251 "unconnected-(J14-RFU-Pad64)")
			(pinfunction "RFU")
			(pintype "no_connect")
		)
		(pad "65" smd rect
			(at 6.75 3.749 270)
			(size 0.3 1.55)
			(layers "B.Cu" "B.Mask" "B.Paste")
			(net 828 "unconnected-(J14-PER1_P-Pad65)")
			(pinfunction "PER1_P")
			(pintype "output+no_connect")
		)
		(pad "66" smd rect
			(at 6.999 -3.749 270)
			(size 0.3 1.55)
			(layers "B.Cu" "B.Mask" "B.Paste")
			(net 276 "unconnected-(J14-UIM_SWP-Pad66)")
			(pinfunction "UIM_SWP")
			(pintype "bidirectional+no_connect")
		)
		(pad "67" smd rect
			(at 7.249 3.749 270)
			(size 0.3 1.55)
			(layers "B.Cu" "B.Mask" "B.Paste")
			(net 829 "unconnected-(J14-PER1_N-Pad67)")
			(pinfunction "PER1_N")
			(pintype "output+no_connect")
		)
		(pad "68" smd rect
			(at 7.499 -3.749 270)
			(size 0.3 1.55)
			(layers "B.Cu" "B.Mask" "B.Paste")
			(net 265 "unconnected-(J14-UIM_POWER_SNK-Pad68)")
			(pinfunction "UIM_POWER_SNK")
			(pintype "bidirectional+no_connect")
		)
		(pad "69" smd rect
			(at 7.749 3.749 270)
			(size 0.3 1.55)
			(layers "B.Cu" "B.Mask" "B.Paste")
			(net 1 "GND")
			(pinfunction "GND")
			(pintype "passive")
		)
		(pad "70" smd rect
			(at 7.999 -3.749 270)
			(size 0.3 1.55)
			(layers "B.Cu" "B.Mask" "B.Paste")
			(net 278 "unconnected-(J14-UIM_POWER_SRC-Pad70)")
			(pinfunction "UIM_POWER_SRC")
			(pintype "bidirectional+no_connect")
		)
		(pad "71" smd rect
			(at 8.249 3.749 270)
			(size 0.3 1.55)
			(layers "B.Cu" "B.Mask" "B.Paste")
			(net 836 "unconnected-(J14-REFCLK1_P-Pad71)")
			(pinfunction "REFCLK1_P")
			(pintype "input+no_connect")
		)
		(pad "72" smd rect
			(at 8.499 -3.749 270)
			(size 0.3 1.55)
			(layers "B.Cu" "B.Mask" "B.Paste")
			(net 2 "+3V3")
			(pinfunction "3.3V")
			(pintype "passive")
		)
		(pad "73" smd rect
			(at 8.749 3.749 270)
			(size 0.3 1.55)
			(layers "B.Cu" "B.Mask" "B.Paste")
			(net 837 "unconnected-(J14-REFCLK1_N-Pad73)")
			(pinfunction "REFCLK1_N")
			(pintype "input+no_connect")
		)
		(pad "74" smd rect
			(at 8.999 -3.749 270)
			(size 0.3 1.55)
			(layers "B.Cu" "B.Mask" "B.Paste")
			(net 2 "+3V3")
			(pinfunction "3.3V")
			(pintype "passive")
		)
		(pad "75" smd rect
			(at 9.249 3.749 270)
			(size 0.3 1.55)
			(layers "B.Cu" "B.Mask" "B.Paste")
			(net 1 "GND")
			(pinfunction "GND")
			(pintype "passive")
		)
		(pad "MP" smd rect
			(at -10.35 3.001 270)
			(size 1.2 2.75)
			(layers "B.Cu" "B.Mask" "B.Paste")
			(net 1 "GND")
			(pinfunction "MP")
			(pintype "passive")
		)
		(pad "MP" smd rect
			(at 10.351 3.001 270)
			(size 1.2 2.75)
			(layers "B.Cu" "B.Mask" "B.Paste")
			(net 1 "GND")
			(pinfunction "MP")
			(pintype "passive")
		)
	)
	(footprint "antmicro-footprints:R_0402_1005Metric"
		(layer "B.Cu")
		(at 223.5 56.25 180)
		(descr "Resistor SMD 0402")
		(tags "resistor SMD 0402")
		(property "Reference" "R178"
			(at -3 -2.65 0)
			(layer "B.SilkS")
			(effects
				(font
					(size 0.7 0.7)
					(thickness 0.15)
				)
				(justify left bottom mirror)
			)
		)
		(property "Value" "R_470R_0402"
			(at -1.011843 -1.772046 0)
			(layer "B.Fab")
			(effects
				(font
					(size 0.7 0.7)
					(thickness 0.15)
				)
				(justify left bottom mirror)
			)
		)
		(property "Datasheet" "https://www.bourns.com/docs/product-datasheets/cr.pdf"
			(at 0 0 0)
			(layer "B.Fab")
			(hide yes)
			(effects
				(font
					(size 1.27 1.27)
					(thickness 0.15)
				)
				(justify mirror)
			)
		)
		(property "Description" "SMD Chip Resistor, 470 ohm, ± 1%, 62.5 mW, 0402 [1005 Metric], Thick Film, General Purpose"
			(at 0 0 0)
			(layer "B.Fab")
			(hide yes)
			(effects
				(font
					(size 1.27 1.27)
					(thickness 0.15)
				)
				(justify mirror)
			)
		)
		(property "Manufacturer" "Bourns"
			(at 0 0 0)
			(unlocked yes)
			(layer "B.Fab")
			(hide yes)
			(effects
				(font
					(size 1 1)
					(thickness 0.15)
				)
				(justify mirror)
			)
		)
		(property "MPN" "CR0402-FX-4700GLF"
			(at 0 0 0)
			(unlocked yes)
			(layer "B.Fab")
			(hide yes)
			(effects
				(font
					(size 1 1)
					(thickness 0.15)
				)
				(justify mirror)
			)
		)
		(property "Val" "470R"
			(at 0 0 0)
			(unlocked yes)
			(layer "B.Fab")
			(hide yes)
			(effects
				(font
					(size 1 1)
					(thickness 0.15)
				)
				(justify mirror)
			)
		)
		(property "License" "Apache-2.0"
			(at 0 0 0)
			(unlocked yes)
			(layer "B.Fab")
			(hide yes)
			(effects
				(font
					(size 1 1)
					(thickness 0.15)
				)
				(justify mirror)
			)
		)
		(property "Author" "Antmicro"
			(at 0 0 0)
			(unlocked yes)
			(layer "B.Fab")
			(hide yes)
			(effects
				(font
					(size 1 1)
					(thickness 0.15)
				)
				(justify mirror)
			)
		)
		(property "Tolerance" "1%"
			(at 0 0 0)
			(unlocked yes)
			(layer "B.Fab")
			(hide yes)
			(effects
				(font
					(size 1 1)
					(thickness 0.15)
				)
				(justify mirror)
			)
		)
		(sheetname "/CSI/")
		(sheetfile "csi.kicad_sch")
		(attr smd)
		(fp_poly
			(pts
				(xy -0.925 0.47) (xy -0.925 -0.47) (xy 0.925 -0.47) (xy 0.925 0.47)
			)
			(stroke
				(width 0.05)
				(type default)
			)
			(fill no)
			(layer "B.CrtYd")
		)
		(fp_poly
			(pts
				(xy -0.5 0.25) (xy -0.5 -0.25) (xy 0.5 -0.25) (xy 0.5 0.25)
			)
			(stroke
				(width 0.15)
				(type solid)
			)
			(fill no)
			(layer "B.Fab")
		)
		(fp_text user "Author: Antmicro"
			(at -0.95 -4.169 0)
			(layer "B.Fab")
			(effects
				(font
					(size 0.7 0.7)
					(thickness 0.15)
				)
				(justify left bottom mirror)
			)
		)
		(fp_text user "License: Apache-2.0"
			(at -0.949999 -5.169 0)
			(layer "B.Fab")
			(effects
				(font
					(size 0.7 0.7)
					(thickness 0.15)
				)
				(justify left bottom mirror)
			)
		)
		(fp_text user "${REFERENCE}"
			(at -0.95 -3.168 0)
			(layer "B.Fab")
			(effects
				(font
					(size 0.7 0.7)
					(thickness 0.15)
				)
				(justify left bottom mirror)
			)
		)
		(pad "1" smd roundrect
			(at -0.48 0 180)
			(size 0.59 0.64)
			(layers "B.Cu" "B.Mask" "B.Paste")
			(roundrect_rratio 0.25)
			(net 540 "Net-(D27-A)")
			(pintype "passive")
		)
		(pad "2" smd roundrect
			(at 0.48 0 180)
			(size 0.59 0.64)
			(layers "B.Cu" "B.Mask" "B.Paste")
			(roundrect_rratio 0.25)
			(net 9 "/CSI/CSIB_5V")
			(pintype "passive")
		)
	)
	(footprint "antmicro-footprints:C_0402_1005Metric"
		(layer "B.Cu")
		(at 126.5635 142.81 180)
		(descr "Capacitor SMD 0402")
		(tags "capacitor SMD 0402")
		(property "Reference" "C203"
			(at 1.060532 -0.52 0)
			(layer "B.SilkS")
			(effects
				(font
					(size 0.7 0.7)
					(thickness 0.15)
				)
				(justify left bottom mirror)
			)
		)
		(property "Value" "C_100n_0402"
			(at -1.022927 -2.155213 0)
			(layer "B.Fab")
			(effects
				(font
					(size 0.7 0.7)
					(thickness 0.15)
				)
				(justify left bottom mirror)
			)
		)
		(property "Datasheet" "https://www.murata.com/products/productdetail?partno=GRM155R61H104KE14%23"
			(at 0 0 0)
			(layer "B.Fab")
			(hide yes)
			(effects
				(font
					(size 1.27 1.27)
					(thickness 0.15)
				)
				(justify mirror)
			)
		)
		(property "Description" "SMD Multilayer Ceramic Capacitor, 0.1 µF, 50 V, 0402 [1005 Metric], ± 10%, X5R, GRM Series"
			(at 0 0 0)
			(layer "B.Fab")
			(hide yes)
			(effects
				(font
					(size 1.27 1.27)
					(thickness 0.15)
				)
				(justify mirror)
			)
		)
		(property "MPN" "GRM155R61H104KE14D"
			(at 0 0 0)
			(unlocked yes)
			(layer "B.Fab")
			(hide yes)
			(effects
				(font
					(size 1 1)
					(thickness 0.15)
				)
				(justify mirror)
			)
		)
		(property "Val" "100n"
			(at 0 0 0)
			(unlocked yes)
			(layer "B.Fab")
			(hide yes)
			(effects
				(font
					(size 1 1)
					(thickness 0.15)
				)
				(justify mirror)
			)
		)
		(property "Voltage" "50V"
			(at 0 0 0)
			(unlocked yes)
			(layer "B.Fab")
			(hide yes)
			(effects
				(font
					(size 1 1)
					(thickness 0.15)
				)
				(justify mirror)
			)
		)
		(property "Dielectric" "X5R"
			(at 0 0 0)
			(unlocked yes)
			(layer "B.Fab")
			(hide yes)
			(effects
				(font
					(size 1 1)
					(thickness 0.15)
				)
				(justify mirror)
			)
		)
		(property "Manufacturer" "Murata"
			(at 0 0 0)
			(unlocked yes)
			(layer "B.Fab")
			(hide yes)
			(effects
				(font
					(size 1 1)
					(thickness 0.15)
				)
				(justify mirror)
			)
		)
		(property "License" "Apache-2.0"
			(at 0 0 0)
			(unlocked yes)
			(layer "B.Fab")
			(hide yes)
			(effects
				(font
					(size 1 1)
					(thickness 0.15)
				)
				(justify mirror)
			)
		)
		(property "Author" "Antmicro"
			(at 0 0 0)
			(unlocked yes)
			(layer "B.Fab")
			(hide yes)
			(effects
				(font
					(size 1 1)
					(thickness 0.15)
				)
				(justify mirror)
			)
		)
		(sheetname "/Peripherals/")
		(sheetfile "peripherals.kicad_sch")
		(attr smd)
		(fp_rect
			(start -0.925 0.47)
			(end 0.925 -0.47)
			(stroke
				(width 0.05)
				(type default)
			)
			(fill no)
			(layer "B.CrtYd")
		)
		(fp_line
			(start 0.504 0.25)
			(end 0.504 -0.248)
			(stroke
				(width 0.15)
				(type solid)
			)
			(layer "B.Fab")
		)
		(fp_line
			(start 0.504 -0.248)
			(end -0.494 -0.248)
			(stroke
				(width 0.15)
				(type solid)
			)
			(layer "B.Fab")
		)
		(fp_line
			(start -0.494 0.25)
			(end 0.504 0.25)
			(stroke
				(width 0.15)
				(type solid)
			)
			(layer "B.Fab")
		)
		(fp_line
			(start -0.494 -0.248)
			(end -0.494 0.25)
			(stroke
				(width 0.15)
				(type solid)
			)
			(layer "B.Fab")
		)
		(fp_text user "License: Apache-2.0"
			(at -0.939 -5.799 0)
			(layer "B.Fab")
			(effects
				(font
					(size 0.7 0.7)
					(thickness 0.15)
				)
				(justify left bottom mirror)
			)
		)
		(fp_text user "Author: Antmicro"
			(at -0.939 -3.399 0)
			(layer "B.Fab")
			(effects
				(font
					(size 0.7 0.7)
					(thickness 0.15)
				)
				(justify left bottom mirror)
			)
		)
		(fp_text user "${REFERENCE}"
			(at -0.939 -4.599 0)
			(layer "B.Fab")
			(effects
				(font
					(size 0.7 0.7)
					(thickness 0.15)
				)
				(justify left bottom mirror)
			)
		)
		(pad "1" smd roundrect
			(at -0.48 0 180)
			(size 0.59 0.64)
			(layers "B.Cu" "B.Mask" "B.Paste")
			(roundrect_rratio 0.25)
			(net 1 "GND")
			(pintype "passive")
		)
		(pad "2" smd roundrect
			(at 0.48 0 180)
			(size 0.59 0.64)
			(layers "B.Cu" "B.Mask" "B.Paste")
			(roundrect_rratio 0.25)
			(net 2 "+3V3")
			(pintype "passive")
		)
	)
	(footprint "antmicro-footprints:DHVQFN-14-1EP_2.5x3mm"
		(layer "B.Cu")
		(at 160.33 67.24 180)
		(property "Reference" "U59"
			(at -1.27 -4.16 90)
			(layer "B.SilkS")
			(effects
				(font
					(size 0.7 0.7)
					(thickness 0.15)
				)
				(justify right top mirror)
			)
		)
		(property "Value" "TXU0304BQAR"
			(at 0 -2.898 0)
			(layer "B.Fab")
			(effects
				(font
					(size 0.7 0.7)
					(thickness 0.15)
				)
				(justify left bottom mirror)
			)
		)
		(property "Datasheet" "https://www.ti.com/lit/ds/symlink/txu0304.pdf?ts=1637748643258&ref_url=https%253A%252F%252Fwww.ti.com%252Fproduct%252FTXU0304"
			(at 0 0 0)
			(layer "B.Fab")
			(hide yes)
			(effects
				(font
					(size 1.27 1.27)
					(thickness 0.15)
				)
				(justify mirror)
			)
		)
		(property "Description" "Logic translator/level shifter"
			(at 0 0 0)
			(layer "B.Fab")
			(hide yes)
			(effects
				(font
					(size 1.27 1.27)
					(thickness 0.15)
				)
				(justify mirror)
			)
		)
		(property "MPN" "TXU0304BQAR"
			(at 0 0 0)
			(unlocked yes)
			(layer "B.Fab")
			(hide yes)
			(effects
				(font
					(size 1 1)
					(thickness 0.15)
				)
				(justify mirror)
			)
		)
		(property "Manufacturer" "Texas Instruments"
			(at 0 0 0)
			(unlocked yes)
			(layer "B.Fab")
			(hide yes)
			(effects
				(font
					(size 1 1)
					(thickness 0.15)
				)
				(justify mirror)
			)
		)
		(property "Author" "Antmicro"
			(at 0 0 0)
			(unlocked yes)
			(layer "B.Fab")
			(hide yes)
			(effects
				(font
					(size 1 1)
					(thickness 0.15)
				)
				(justify mirror)
			)
		)
		(property "License" "Apache-2.0"
			(at 0 0 0)
			(unlocked yes)
			(layer "B.Fab")
			(hide yes)
			(effects
				(font
					(size 1 1)
					(thickness 0.15)
				)
				(justify mirror)
			)
		)
		(sheetname "/SoM_IO2/")
		(sheetfile "som_io2.kicad_sch")
		(attr smd exclude_from_pos_files exclude_from_bom dnp)
		(fp_line
			(start 1.35 1.601)
			(end 1.35 1.25)
			(stroke
				(width 0.15)
				(type solid)
			)
			(layer "B.SilkS")
		)
		(fp_line
			(start 1.35 1.601)
			(end 0.494 1.601)
			(stroke
				(width 0.15)
				(type solid)
			)
			(layer "B.SilkS")
		)
		(fp_line
			(start 1.35 -1.6)
			(end 1.35 -1.249)
			(stroke
				(width 0.15)
				(type solid)
			)
			(layer "B.SilkS")
		)
		(fp_line
			(start 0.494 -1.6)
			(end 1.35 -1.6)
			(stroke
				(width 0.15)
				(type solid)
			)
			(layer "B.SilkS")
		)
		(fp_line
			(start -1.35 1.601)
			(end -1.35 1.25)
			(stroke
				(width 0.15)
				(type solid)
			)
			(layer "B.SilkS")
		)
		(fp_line
			(start -1.351 1.601)
			(end -0.5 1.601)
			(stroke
				(width 0.15)
				(type solid)
			)
			(layer "B.SilkS")
		)
		(fp_line
			(start -1.351 -1.6)
			(end -0.5 -1.6)
			(stroke
				(width 0.15)
				(type solid)
			)
			(layer "B.SilkS")
		)
		(fp_line
			(start -1.351 -1.6)
			(end -1.351 -1.249)
			(stroke
				(width 0.15)
				(type solid)
			)
			(layer "B.SilkS")
		)
		(fp_circle
			(center -0.7 1.85)
			(end -0.653 1.85)
			(stroke
				(width 0.15)
				(type solid)
			)
			(fill yes)
			(layer "B.SilkS")
		)
		(fp_rect
			(start -1.85 2)
			(end 1.8 -1.95)
			(stroke
				(width 0.05)
				(type solid)
			)
			(fill no)
			(layer "B.CrtYd")
		)
		(fp_line
			(start 1.249 1.5)
			(end 1.249 -1.499)
			(stroke
				(width 0.15)
				(type solid)
			)
			(layer "B.Fab")
		)
		(fp_line
			(start 1.249 -1.499)
			(end -1.25 -1.499)
			(stroke
				(width 0.15)
				(type solid)
			)
			(layer "B.Fab")
		)
		(fp_line
			(start -1 1.5)
			(end 1.249 1.5)
			(stroke
				(width 0.15)
				(type solid)
			)
			(layer "B.Fab")
		)
		(fp_line
			(start -1.25 1.25)
			(end -1 1.5)
			(stroke
				(width 0.15)
				(type solid)
			)
			(layer "B.Fab")
		)
		(fp_line
			(start -1.25 -1.499)
			(end -1.25 1.25)
			(stroke
				(width 0.15)
				(type solid)
			)
			(layer "B.Fab")
		)
		(fp_text user "License: Apache-2.0"
			(at -1.841 -6.097 0)
			(layer "B.Fab")
			(effects
				(font
					(size 0.7 0.7)
					(thickness 0.15)
				)
				(justify left bottom mirror)
			)
		)
		(fp_text user "${REFERENCE}"
			(at -1.841 -4.897 0)
			(layer "B.Fab")
			(effects
				(font
					(size 0.7 0.7)
					(thickness 0.15)
				)
				(justify left bottom mirror)
			)
		)
		(fp_text user "Author: Antmicro"
			(at -1.841 -7.296 0)
			(layer "B.Fab")
			(effects
				(font
					(size 0.7 0.7)
					(thickness 0.15)
				)
				(justify left bottom mirror)
			)
		)
		(pad "1" smd oval
			(at -0.25 1.5 180)
			(size 0.3 0.8)
			(layers "B.Cu" "B.Mask" "B.Paste")
			(net 269 "/SoM_IO2/TC_VCC")
			(pinfunction "VCCA")
			(pintype "power_in")
		)
		(pad "2" smd oval
			(at -1.25 1 90)
			(size 0.3 0.8)
			(layers "B.Cu" "B.Mask" "B.Paste")
			(net 869 "/SoM_IO2/TC_JTAG_TMS")
			(pinfunction "A1")
			(pintype "input")
		)
		(pad "3" smd oval
			(at -1.25 0.5 90)
			(size 0.3 0.8)
			(layers "B.Cu" "B.Mask" "B.Paste")
			(net 868 "/SoM_IO2/TC_JTAG_TDI")
			(pinfunction "A2")
			(pintype "input")
		)
		(pad "4" smd oval
			(at -1.25 0 90)
			(size 0.3 0.8)
			(layers "B.Cu" "B.Mask" "B.Paste")
			(net 871 "/SoM_IO2/TC_JTAG_TCK")
			(pinfunction "A3")
			(pintype "input")
		)
		(pad "5" smd oval
			(at -1.25 -0.494 90)
			(size 0.3 0.8)
			(layers "B.Cu" "B.Mask" "B.Paste")
			(net 872 "/SoM_IO2/TC_JTAG_TDO")
			(pinfunction "A4Y")
			(pintype "output")
		)
		(pad "6" smd oval
			(at -1.25 -0.994 90)
			(size 0.3 0.8)
			(layers "B.Cu" "B.Mask" "B.Paste")
			(net 1124 "unconnected-(U59-NC-Pad6)")
			(pinfunction "NC")
			(pintype "no_connect")
		)
		(pad "7" smd oval
			(at -0.25 -1.499 180)
			(size 0.3 0.8)
			(layers "B.Cu" "B.Mask" "B.Paste")
			(net 1 "GND")
			(pinfunction "GND")
			(pintype "passive")
		)
		(pad "8" smd oval
			(at 0.244 -1.499 180)
			(size 0.3 0.8)
			(layers "B.Cu" "B.Mask" "B.Paste")
			(net 11 "+1V8")
			(pinfunction "OE")
			(pintype "tri_state")
		)
		(pad "9" smd oval
			(at 1.249 -0.994 90)
			(size 0.3 0.8)
			(layers "B.Cu" "B.Mask" "B.Paste")
			(net 1123 "unconnected-(U59-NC-Pad9)")
			(pinfunction "NC")
			(pintype "no_connect")
		)
		(pad "10" smd oval
			(at 1.249 -0.494 90)
			(size 0.3 0.8)
			(layers "B.Cu" "B.Mask" "B.Paste")
			(net 1031 "Net-(U59-B4)")
			(pinfunction "B4")
			(pintype "input")
		)
		(pad "11" smd oval
			(at 1.249 0 90)
			(size 0.3 0.8)
			(layers "B.Cu" "B.Mask" "B.Paste")
			(net 1028 "Net-(U59-B3Y)")
			(pinfunction "B3Y")
			(pintype "output")
		)
		(pad "12" smd oval
			(at 1.249 0.5 90)
			(size 0.3 0.8)
			(layers "B.Cu" "B.Mask" "B.Paste")
			(net 1029 "Net-(U59-B2Y)")
			(pinfunction "B2Y")
			(pintype "output")
		)
		(pad "13" smd oval
			(at 1.249 1 90)
			(size 0.3 0.8)
			(layers "B.Cu" "B.Mask" "B.Paste")
			(net 1030 "Net-(U59-B1Y)")
			(pinfunction "B1Y")
			(pintype "output")
		)
		(pad "14" smd oval
			(at 0.244 1.5 180)
			(size 0.3 0.8)
			(layers "B.Cu" "B.Mask" "B.Paste")
			(net 11 "+1V8")
			(pinfunction "VCCB")
			(pintype "power_in")
		)
		(pad "15" smd rect
			(at 0 0 180)
			(size 1 1.5)
			(layers "B.Cu" "B.Mask" "B.Paste")
			(net 1 "GND")
			(pinfunction "GND")
			(pintype "power_in")
		)
	)
	(footprint "antmicro-footprints:C_0402_1005Metric"
		(layer "B.Cu")
		(at 207 61.512999 180)
		(descr "Capacitor SMD 0402")
		(tags "capacitor SMD 0402")
		(property "Reference" "C159"
			(at 0.89 -0.42 0)
			(layer "B.SilkS")
			(effects
				(font
					(size 0.7 0.7)
					(thickness 0.15)
				)
				(justify left bottom mirror)
			)
		)
		(property "Value" "C_100n_0402"
			(at -1.022927 -2.155213 0)
			(layer "B.Fab")
			(effects
				(font
					(size 0.7 0.7)
					(thickness 0.15)
				)
				(justify left bottom mirror)
			)
		)
		(property "Datasheet" "https://www.murata.com/products/productdetail?partno=GRM155R61H104KE14%23"
			(at 0 0 0)
			(layer "B.Fab")
			(hide yes)
			(effects
				(font
					(size 1.27 1.27)
					(thickness 0.15)
				)
				(justify mirror)
			)
		)
		(property "Description" "SMD Multilayer Ceramic Capacitor, 0.1 µF, 50 V, 0402 [1005 Metric], ± 10%, X5R, GRM Series"
			(at 0 0 0)
			(layer "B.Fab")
			(hide yes)
			(effects
				(font
					(size 1.27 1.27)
					(thickness 0.15)
				)
				(justify mirror)
			)
		)
		(property "Manufacturer" "Murata"
			(at 0 0 0)
			(unlocked yes)
			(layer "B.Fab")
			(hide yes)
			(effects
				(font
					(size 1 1)
					(thickness 0.15)
				)
				(justify mirror)
			)
		)
		(property "MPN" "GRM155R61H104KE14D"
			(at 0 0 0)
			(unlocked yes)
			(layer "B.Fab")
			(hide yes)
			(effects
				(font
					(size 1 1)
					(thickness 0.15)
				)
				(justify mirror)
			)
		)
		(property "Val" "100n"
			(at 0 0 0)
			(unlocked yes)
			(layer "B.Fab")
			(hide yes)
			(effects
				(font
					(size 1 1)
					(thickness 0.15)
				)
				(justify mirror)
			)
		)
		(property "License" "Apache-2.0"
			(at 0 0 0)
			(unlocked yes)
			(layer "B.Fab")
			(hide yes)
			(effects
				(font
					(size 1 1)
					(thickness 0.15)
				)
				(justify mirror)
			)
		)
		(property "Author" "Antmicro"
			(at 0 0 0)
			(unlocked yes)
			(layer "B.Fab")
			(hide yes)
			(effects
				(font
					(size 1 1)
					(thickness 0.15)
				)
				(justify mirror)
			)
		)
		(property "Voltage" "50V"
			(at 0 0 0)
			(unlocked yes)
			(layer "B.Fab")
			(hide yes)
			(effects
				(font
					(size 1 1)
					(thickness 0.15)
				)
				(justify mirror)
			)
		)
		(property "Dielectric" "X5R"
			(at 0 0 0)
			(unlocked yes)
			(layer "B.Fab")
			(hide yes)
			(effects
				(font
					(size 1 1)
					(thickness 0.15)
				)
				(justify mirror)
			)
		)
		(sheetname "/CSI/")
		(sheetfile "csi.kicad_sch")
		(attr smd)
		(fp_poly
			(pts
				(xy -0.925 0.47) (xy -0.925 -0.47) (xy 0.925 -0.47) (xy 0.925 0.47)
			)
			(stroke
				(width 0.05)
				(type default)
			)
			(fill no)
			(layer "B.CrtYd")
		)
		(fp_line
			(start 0.504 0.25)
			(end 0.504 -0.248)
			(stroke
				(width 0.15)
				(type solid)
			)
			(layer "B.Fab")
		)
		(fp_line
			(start 0.504 -0.248)
			(end -0.494 -0.248)
			(stroke
				(width 0.15)
				(type solid)
			)
			(layer "B.Fab")
		)
		(fp_line
			(start -0.494 0.25)
			(end 0.504 0.25)
			(stroke
				(width 0.15)
				(type solid)
			)
			(layer "B.Fab")
		)
		(fp_line
			(start -0.494 -0.248)
			(end -0.494 0.25)
			(stroke
				(width 0.15)
				(type solid)
			)
			(layer "B.Fab")
		)
		(fp_text user "License: Apache-2.0"
			(at -0.939 -5.799 0)
			(layer "B.Fab")
			(effects
				(font
					(size 0.7 0.7)
					(thickness 0.15)
				)
				(justify left bottom mirror)
			)
		)
		(fp_text user "Author: Antmicro"
			(at -0.939 -3.399 0)
			(layer "B.Fab")
			(effects
				(font
					(size 0.7 0.7)
					(thickness 0.15)
				)
				(justify left bottom mirror)
			)
		)
		(fp_text user "${REFERENCE}"
			(at -0.939 -4.599 0)
			(layer "B.Fab")
			(effects
				(font
					(size 0.7 0.7)
					(thickness 0.15)
				)
				(justify left bottom mirror)
			)
		)
		(pad "1" smd roundrect
			(at -0.48 0 180)
			(size 0.59 0.64)
			(layers "B.Cu" "B.Mask" "B.Paste")
			(roundrect_rratio 0.25)
			(net 2 "+3V3")
			(pintype "passive")
		)
		(pad "2" smd roundrect
			(at 0.48 0 180)
			(size 0.59 0.64)
			(layers "B.Cu" "B.Mask" "B.Paste")
			(roundrect_rratio 0.25)
			(net 1 "GND")
			(pintype "passive")
		)
	)
	(footprint "antmicro-footprints:R_0402_1005Metric"
		(layer "B.Cu")
		(at 158.51 62.77 90)
		(descr "Resistor SMD 0402")
		(tags "resistor SMD 0402")
		(property "Reference" "R285"
			(at -7.13 -7.01 90)
			(layer "B.SilkS")
			(effects
				(font
					(size 0.7 0.7)
					(thickness 0.15)
				)
				(justify right top mirror)
			)
		)
		(property "Value" "R_10k_0402"
			(at -1.011843 -1.772047 90)
			(layer "B.Fab")
			(effects
				(font
					(size 0.7 0.7)
					(thickness 0.15)
				)
				(justify right top mirror)
			)
		)
		(property "Datasheet" "https://www.bourns.com/docs/product-datasheets/cr.pdf"
			(at 0 0 90)
			(layer "B.Fab")
			(hide yes)
			(effects
				(font
					(size 1.27 1.27)
					(thickness 0.15)
				)
				(justify mirror)
			)
		)
		(property "Description" "SMD Chip Resistor, 10 kohm, ± 1%, 62.5 mW, 0402 [1005 Metric], Thick Film, General Purpose"
			(at 0 0 90)
			(layer "B.Fab")
			(hide yes)
			(effects
				(font
					(size 1.27 1.27)
					(thickness 0.15)
				)
				(justify mirror)
			)
		)
		(property "MPN" "CR0402-FX-1002GLF"
			(at 0 0 270)
			(unlocked yes)
			(layer "B.Fab")
			(hide yes)
			(effects
				(font
					(size 1 1)
					(thickness 0.15)
				)
				(justify mirror)
			)
		)
		(property "Manufacturer" "Bourns"
			(at 0 0 270)
			(unlocked yes)
			(layer "B.Fab")
			(hide yes)
			(effects
				(font
					(size 1 1)
					(thickness 0.15)
				)
				(justify mirror)
			)
		)
		(property "License" "Apache-2.0"
			(at 0 0 270)
			(unlocked yes)
			(layer "B.Fab")
			(hide yes)
			(effects
				(font
					(size 1 1)
					(thickness 0.15)
				)
				(justify mirror)
			)
		)
		(property "Author" "Antmicro"
			(at 0 0 270)
			(unlocked yes)
			(layer "B.Fab")
			(hide yes)
			(effects
				(font
					(size 1 1)
					(thickness 0.15)
				)
				(justify mirror)
			)
		)
		(property "Val" "10k"
			(at 0 0 270)
			(unlocked yes)
			(layer "B.Fab")
			(hide yes)
			(effects
				(font
					(size 1 1)
					(thickness 0.15)
				)
				(justify mirror)
			)
		)
		(property "Tolerance" "1%"
			(at 0 0 270)
			(unlocked yes)
			(layer "B.Fab")
			(hide yes)
			(effects
				(font
					(size 1 1)
					(thickness 0.15)
				)
				(justify mirror)
			)
		)
		(sheetname "/SoM_IO2/")
		(sheetfile "som_io2.kicad_sch")
		(attr smd exclude_from_pos_files exclude_from_bom dnp)
		(fp_rect
			(start -0.925 0.47)
			(end 0.925 -0.47)
			(stroke
				(width 0.05)
				(type default)
			)
			(fill no)
			(layer "B.CrtYd")
		)
		(fp_rect
			(start -0.5 0.25)
			(end 0.5 -0.25)
			(stroke
				(width 0.15)
				(type solid)
			)
			(fill no)
			(layer "B.Fab")
		)
		(fp_text user "Author: Antmicro"
			(at -0.95 -4.169 90)
			(layer "B.Fab")
			(effects
				(font
					(size 0.7 0.7)
					(thickness 0.15)
				)
				(justify right top mirror)
			)
		)
		(fp_text user "License: Apache-2.0"
			(at -0.95 -5.169 90)
			(layer "B.Fab")
			(effects
				(font
					(size 0.7 0.7)
					(thickness 0.15)
				)
				(justify right top mirror)
			)
		)
		(fp_text user "${REFERENCE}"
			(at -0.95 -3.168 90)
			(layer "B.Fab")
			(effects
				(font
					(size 0.7 0.7)
					(thickness 0.15)
				)
				(justify right top mirror)
			)
		)
		(pad "1" smd roundrect
			(at -0.48 0 90)
			(size 0.59 0.64)
			(layers "B.Cu" "B.Mask" "B.Paste")
			(roundrect_rratio 0.25)
			(net 627 "/SoM_IO2/JTAG_TRST_N")
			(pintype "passive")
		)
		(pad "2" smd roundrect
			(at 0.48 0 90)
			(size 0.59 0.64)
			(layers "B.Cu" "B.Mask" "B.Paste")
			(roundrect_rratio 0.25)
			(net 11 "+1V8")
			(pintype "passive")
		)
	)
	(footprint "antmicro-footprints:R_0402_1005Metric"
		(layer "B.Cu")
		(at 65.1 70.4 90)
		(descr "Resistor SMD 0402")
		(tags "resistor SMD 0402")
		(property "Reference" "R400"
			(at -2.2 3.7 90)
			(layer "B.SilkS")
			(effects
				(font
					(size 0.7 0.7)
					(thickness 0.15)
				)
				(justify right top mirror)
			)
		)
		(property "Value" "R_0R_0402"
			(at -1.011843 -1.772047 90)
			(layer "B.Fab")
			(effects
				(font
					(size 0.7 0.7)
					(thickness 0.15)
				)
				(justify right top mirror)
			)
		)
		(property "Datasheet" "https://industrial.panasonic.com/cdbs/www-data/pdf/RDA0000/AOA0000C301.pdf"
			(at 0 0 90)
			(layer "B.Fab")
			(hide yes)
			(effects
				(font
					(size 1.27 1.27)
					(thickness 0.15)
				)
				(justify mirror)
			)
		)
		(property "Description" "SMD Chip Resistor, Jumper, 0 ohm, 100 mW, 0402 [1005 Metric], Thick Film, General Purpose"
			(at 0 0 90)
			(layer "B.Fab")
			(hide yes)
			(effects
				(font
					(size 1.27 1.27)
					(thickness 0.15)
				)
				(justify mirror)
			)
		)
		(property "MPN" "ERJ2GE0R00X"
			(at 0 0 270)
			(unlocked yes)
			(layer "B.Fab")
			(hide yes)
			(effects
				(font
					(size 1 1)
					(thickness 0.15)
				)
				(justify mirror)
			)
		)
		(property "Manufacturer" "Panasonic"
			(at 0 0 270)
			(unlocked yes)
			(layer "B.Fab")
			(hide yes)
			(effects
				(font
					(size 1 1)
					(thickness 0.15)
				)
				(justify mirror)
			)
		)
		(property "License" "Apache-2.0"
			(at 0 0 270)
			(unlocked yes)
			(layer "B.Fab")
			(hide yes)
			(effects
				(font
					(size 1 1)
					(thickness 0.15)
				)
				(justify mirror)
			)
		)
		(property "Author" "Antmicro"
			(at 0 0 270)
			(unlocked yes)
			(layer "B.Fab")
			(hide yes)
			(effects
				(font
					(size 1 1)
					(thickness 0.15)
				)
				(justify mirror)
			)
		)
		(property "Val" "0R"
			(at 0 0 270)
			(unlocked yes)
			(layer "B.Fab")
			(hide yes)
			(effects
				(font
					(size 1 1)
					(thickness 0.15)
				)
				(justify mirror)
			)
		)
		(property "Tolerance" "~"
			(at 0 0 270)
			(unlocked yes)
			(layer "B.Fab")
			(hide yes)
			(effects
				(font
					(size 1 1)
					(thickness 0.15)
				)
				(justify mirror)
			)
		)
		(property "Current" "1A"
			(at 0 0 270)
			(unlocked yes)
			(layer "B.Fab")
			(hide yes)
			(effects
				(font
					(size 1 1)
					(thickness 0.15)
				)
				(justify mirror)
			)
		)
		(sheetname "/CSI/")
		(sheetfile "csi.kicad_sch")
		(attr smd)
		(fp_rect
			(start -0.925 0.47)
			(end 0.925 -0.47)
			(stroke
				(width 0.05)
				(type default)
			)
			(fill no)
			(layer "B.CrtYd")
		)
		(fp_rect
			(start -0.5 0.25)
			(end 0.5 -0.25)
			(stroke
				(width 0.15)
				(type solid)
			)
			(fill no)
			(layer "B.Fab")
		)
		(fp_text user "${REFERENCE}"
			(at -0.95 -3.168 90)
			(layer "B.Fab")
			(effects
				(font
					(size 0.7 0.7)
					(thickness 0.15)
				)
				(justify right top mirror)
			)
		)
		(fp_text user "License: Apache-2.0"
			(at -0.95 -5.169 90)
			(layer "B.Fab")
			(effects
				(font
					(size 0.7 0.7)
					(thickness 0.15)
				)
				(justify right top mirror)
			)
		)
		(fp_text user "Author: Antmicro"
			(at -0.95 -4.169 90)
			(layer "B.Fab")
			(effects
				(font
					(size 0.7 0.7)
					(thickness 0.15)
				)
				(justify right top mirror)
			)
		)
		(pad "1" smd roundrect
			(at -0.48 0 90)
			(size 0.59 0.64)
			(layers "B.Cu" "B.Mask" "B.Paste")
			(roundrect_rratio 0.25)
			(net 1375 "Net-(J11-Pad42)")
			(pintype "passive")
		)
		(pad "2" smd roundrect
			(at 0.48 0 90)
			(size 0.59 0.64)
			(layers "B.Cu" "B.Mask" "B.Paste")
			(roundrect_rratio 0.25)
			(net 988 "/CSI/SCL_CAM1")
			(pintype "passive")
		)
	)
	(footprint "antmicro-footprints:R_0402_1005Metric"
		(layer "B.Cu")
		(at 143.6 65.2 90)
		(descr "Resistor SMD 0402")
		(tags "resistor SMD 0402")
		(property "Reference" "R245"
			(at -3.7 -0.4 90)
			(layer "B.SilkS")
			(effects
				(font
					(size 0.7 0.7)
					(thickness 0.15)
				)
				(justify right top mirror)
			)
		)
		(property "Value" "R_10k_0402"
			(at -1.011843 -1.772046 90)
			(layer "B.Fab")
			(effects
				(font
					(size 0.7 0.7)
					(thickness 0.15)
				)
				(justify right top mirror)
			)
		)
		(property "Datasheet" "https://www.bourns.com/docs/product-datasheets/cr.pdf"
			(at 0 0 90)
			(layer "B.Fab")
			(hide yes)
			(effects
				(font
					(size 1.27 1.27)
					(thickness 0.15)
				)
				(justify mirror)
			)
		)
		(property "Description" "SMD Chip Resistor, 10 kohm, ± 1%, 62.5 mW, 0402 [1005 Metric], Thick Film, General Purpose"
			(at 0 0 90)
			(layer "B.Fab")
			(hide yes)
			(effects
				(font
					(size 1.27 1.27)
					(thickness 0.15)
				)
				(justify mirror)
			)
		)
		(property "Manufacturer" "Bourns"
			(at 0 0 270)
			(unlocked yes)
			(layer "B.Fab")
			(hide yes)
			(effects
				(font
					(size 1 1)
					(thickness 0.15)
				)
				(justify mirror)
			)
		)
		(property "MPN" "CR0402-FX-1002GLF"
			(at 0 0 270)
			(unlocked yes)
			(layer "B.Fab")
			(hide yes)
			(effects
				(font
					(size 1 1)
					(thickness 0.15)
				)
				(justify mirror)
			)
		)
		(property "Val" "10k"
			(at 0 0 270)
			(unlocked yes)
			(layer "B.Fab")
			(hide yes)
			(effects
				(font
					(size 1 1)
					(thickness 0.15)
				)
				(justify mirror)
			)
		)
		(property "License" "Apache-2.0"
			(at 0 0 270)
			(unlocked yes)
			(layer "B.Fab")
			(hide yes)
			(effects
				(font
					(size 1 1)
					(thickness 0.15)
				)
				(justify mirror)
			)
		)
		(property "Author" "Antmicro"
			(at 0 0 270)
			(unlocked yes)
			(layer "B.Fab")
			(hide yes)
			(effects
				(font
					(size 1 1)
					(thickness 0.15)
				)
				(justify mirror)
			)
		)
		(property "Tolerance" "1%"
			(at 0 0 270)
			(unlocked yes)
			(layer "B.Fab")
			(hide yes)
			(effects
				(font
					(size 1 1)
					(thickness 0.15)
				)
				(justify mirror)
			)
		)
		(sheetname "/Peripherals/")
		(sheetfile "peripherals.kicad_sch")
		(attr smd)
		(fp_poly
			(pts
				(xy -0.925 0.47) (xy -0.925 -0.47) (xy 0.925 -0.47) (xy 0.925 0.47)
			)
			(stroke
				(width 0.05)
				(type default)
			)
			(fill no)
			(layer "B.CrtYd")
		)
		(fp_poly
			(pts
				(xy -0.5 0.25) (xy -0.5 -0.25) (xy 0.5 -0.25) (xy 0.5 0.25)
			)
			(stroke
				(width 0.15)
				(type solid)
			)
			(fill no)
			(layer "B.Fab")
		)
		(fp_text user "License: Apache-2.0"
			(at -0.949999 -5.169 90)
			(layer "B.Fab")
			(effects
				(font
					(size 0.7 0.7)
					(thickness 0.15)
				)
				(justify right top mirror)
			)
		)
		(fp_text user "Author: Antmicro"
			(at -0.95 -4.169 90)
			(layer "B.Fab")
			(effects
				(font
					(size 0.7 0.7)
					(thickness 0.15)
				)
				(justify right top mirror)
			)
		)
		(fp_text user "${REFERENCE}"
			(at -0.95 -3.168 90)
			(layer "B.Fab")
			(effects
				(font
					(size 0.7 0.7)
					(thickness 0.15)
				)
				(justify right top mirror)
			)
		)
		(pad "1" smd roundrect
			(at -0.48 0 90)
			(size 0.59 0.64)
			(layers "B.Cu" "B.Mask" "B.Paste")
			(roundrect_rratio 0.25)
			(net 1 "GND")
			(pintype "passive")
		)
		(pad "2" smd roundrect
			(at 0.48 0 90)
			(size 0.59 0.64)
			(layers "B.Cu" "B.Mask" "B.Paste")
			(roundrect_rratio 0.25)
			(net 1010 "Net-(U55-ISET)")
			(pintype "passive")
		)
	)
	(footprint "antmicro-footprints:TP_SMD_0.75mm"
		(layer "B.Cu")
		(at 160 145 -90)
		(property "Reference" "TP90"
			(at -0.4 -1.5 90)
			(layer "B.SilkS")
			(effects
				(font
					(size 0.7 0.7)
					(thickness 0.15)
				)
				(justify left bottom mirror)
			)
		)
		(property "Value" "TP_0.75mm_SMD"
			(at 0 -1.2 90)
			(layer "B.Fab")
			(effects
				(font
					(size 0.7 0.7)
					(thickness 0.15)
				)
				(justify left bottom mirror)
			)
		)
		(property "Description" "SMT test point"
			(at 0 0 90)
			(layer "B.Fab")
			(hide yes)
			(effects
				(font
					(size 1.27 1.27)
					(thickness 0.15)
				)
				(justify mirror)
			)
		)
		(property "MPN" ""
			(at 0 0 90)
			(unlocked yes)
			(layer "B.Fab")
			(hide yes)
			(effects
				(font
					(size 1 1)
					(thickness 0.15)
				)
				(justify mirror)
			)
		)
		(property "Manufacturer" ""
			(at 0 0 90)
			(unlocked yes)
			(layer "B.Fab")
			(hide yes)
			(effects
				(font
					(size 1 1)
					(thickness 0.15)
				)
				(justify mirror)
			)
		)
		(property "Author" "Antmicro"
			(at 0 0 90)
			(unlocked yes)
			(layer "B.Fab")
			(hide yes)
			(effects
				(font
					(size 1 1)
					(thickness 0.15)
				)
				(justify mirror)
			)
		)
		(property "License" "Apache-2.0"
			(at 0 0 90)
			(unlocked yes)
			(layer "B.Fab")
			(hide yes)
			(effects
				(font
					(size 1 1)
					(thickness 0.15)
				)
				(justify mirror)
			)
		)
		(sheetname "/Peripherals/")
		(sheetfile "peripherals.kicad_sch")
		(attr exclude_from_pos_files exclude_from_bom)
		(fp_circle
			(center 0 0)
			(end 0.475 0)
			(stroke
				(width 0.05)
				(type default)
			)
			(fill no)
			(layer "B.CrtYd")
		)
		(fp_text user "License: Apache-2.0"
			(at -0.4 -5.101 90)
			(layer "B.Fab")
			(effects
				(font
					(size 0.7 0.7)
					(thickness 0.15)
				)
				(justify left bottom mirror)
			)
		)
		(fp_text user "${REFERENCE}"
			(at -0.4 -2.7 90)
			(layer "B.Fab")
			(effects
				(font
					(size 0.7 0.7)
					(thickness 0.15)
				)
				(justify left bottom mirror)
			)
		)
		(fp_text user "Author: Antmicro"
			(at -0.4 -3.901 90)
			(layer "B.Fab")
			(effects
				(font
					(size 0.7 0.7)
					(thickness 0.15)
				)
				(justify left bottom mirror)
			)
		)
		(pad "1" smd circle
			(at 0 0 270)
			(size 0.75 0.75)
			(layers "B.Cu" "B.Mask")
			(net 100 "/Peripherals/FAN_TACH")
			(pinfunction "1")
			(pintype "passive")
		)
	)
	(footprint "antmicro-footprints:TP_SMD_0.75mm"
		(layer "B.Cu")
		(at 233.8 116.3 180)
		(property "Reference" "TP43"
			(at 0 0.6 0)
			(layer "B.SilkS")
			(effects
				(font
					(size 0.7 0.7)
					(thickness 0.15)
				)
				(justify left bottom mirror)
			)
		)
		(property "Value" "TP_0.75mm_SMD"
			(at 0 -1.2 0)
			(layer "B.Fab")
			(effects
				(font
					(size 0.7 0.7)
					(thickness 0.15)
				)
				(justify left bottom mirror)
			)
		)
		(property "Description" "SMT test point"
			(at 0 0 0)
			(layer "B.Fab")
			(hide yes)
			(effects
				(font
					(size 1.27 1.27)
					(thickness 0.15)
				)
				(justify mirror)
			)
		)
		(property "MPN" ""
			(at 0 0 0)
			(unlocked yes)
			(layer "B.Fab")
			(hide yes)
			(effects
				(font
					(size 1 1)
					(thickness 0.15)
				)
				(justify mirror)
			)
		)
		(property "Manufacturer" ""
			(at 0 0 0)
			(unlocked yes)
			(layer "B.Fab")
			(hide yes)
			(effects
				(font
					(size 1 1)
					(thickness 0.15)
				)
				(justify mirror)
			)
		)
		(property "Author" "Antmicro"
			(at 0 0 0)
			(unlocked yes)
			(layer "B.Fab")
			(hide yes)
			(effects
				(font
					(size 1 1)
					(thickness 0.15)
				)
				(justify mirror)
			)
		)
		(property "License" "Apache-2.0"
			(at 0 0 0)
			(unlocked yes)
			(layer "B.Fab")
			(hide yes)
			(effects
				(font
					(size 1 1)
					(thickness 0.15)
				)
				(justify mirror)
			)
		)
		(sheetname "/USB Hub/")
		(sheetfile "usb_hub.kicad_sch")
		(attr exclude_from_pos_files exclude_from_bom)
		(fp_circle
			(center 0 0)
			(end 0.475 0)
			(stroke
				(width 0.05)
				(type default)
			)
			(fill no)
			(layer "B.CrtYd")
		)
		(fp_text user "License: Apache-2.0"
			(at -0.4 -5.101 0)
			(layer "B.Fab")
			(effects
				(font
					(size 0.7 0.7)
					(thickness 0.15)
				)
				(justify left bottom mirror)
			)
		)
		(fp_text user "Author: Antmicro"
			(at -0.4 -3.901 0)
			(layer "B.Fab")
			(effects
				(font
					(size 0.7 0.7)
					(thickness 0.15)
				)
				(justify left bottom mirror)
			)
		)
		(fp_text user "${REFERENCE}"
			(at -0.4 -2.7 0)
			(layer "B.Fab")
			(effects
				(font
					(size 0.7 0.7)
					(thickness 0.15)
				)
				(justify left bottom mirror)
			)
		)
		(pad "1" smd circle
			(at 0 0 180)
			(size 0.75 0.75)
			(layers "B.Cu" "B.Mask")
			(net 71 "/USB Hub/USBC3_VBUS")
			(pinfunction "1")
			(pintype "passive")
		)
	)
	(footprint "antmicro-footprints:R_0402_1005Metric"
		(layer "B.Cu")
		(at 212.8 88.775001)
		(descr "Resistor SMD 0402")
		(tags "resistor SMD 0402")
		(property "Reference" "R134"
			(at -3.9 -0.3 0)
			(layer "B.SilkS")
			(effects
				(font
					(size 0.7 0.7)
					(thickness 0.15)
				)
				(justify right top mirror)
			)
		)
		(property "Value" "R_1k_0402"
			(at -1.011843 -1.772046 0)
			(layer "B.Fab")
			(effects
				(font
					(size 0.7 0.7)
					(thickness 0.15)
				)
				(justify right top mirror)
			)
		)
		(property "Datasheet" "https://www.bourns.com/docs/product-datasheets/cr.pdf"
			(at 0 0 0)
			(layer "B.Fab")
			(hide yes)
			(effects
				(font
					(size 1.27 1.27)
					(thickness 0.15)
				)
				(justify mirror)
			)
		)
		(property "Description" "SMD Chip Resistor, 1 kohm, ± 1%, 63 mW, 0402 [1005 Metric], Thick Film, General Purpose"
			(at 0 0 0)
			(layer "B.Fab")
			(hide yes)
			(effects
				(font
					(size 1.27 1.27)
					(thickness 0.15)
				)
				(justify mirror)
			)
		)
		(property "Manufacturer" "Bourns"
			(at 0 0 180)
			(unlocked yes)
			(layer "B.Fab")
			(hide yes)
			(effects
				(font
					(size 1 1)
					(thickness 0.15)
				)
				(justify mirror)
			)
		)
		(property "MPN" "CR0402-FX-1001GLF"
			(at 0 0 180)
			(unlocked yes)
			(layer "B.Fab")
			(hide yes)
			(effects
				(font
					(size 1 1)
					(thickness 0.15)
				)
				(justify mirror)
			)
		)
		(property "Val" "1k"
			(at 0 0 180)
			(unlocked yes)
			(layer "B.Fab")
			(hide yes)
			(effects
				(font
					(size 1 1)
					(thickness 0.15)
				)
				(justify mirror)
			)
		)
		(property "License" "Apache-2.0"
			(at 0 0 180)
			(unlocked yes)
			(layer "B.Fab")
			(hide yes)
			(effects
				(font
					(size 1 1)
					(thickness 0.15)
				)
				(justify mirror)
			)
		)
		(property "Author" "Antmicro"
			(at 0 0 180)
			(unlocked yes)
			(layer "B.Fab")
			(hide yes)
			(effects
				(font
					(size 1 1)
					(thickness 0.15)
				)
				(justify mirror)
			)
		)
		(property "Tolerance" "1%"
			(at 0 0 180)
			(unlocked yes)
			(layer "B.Fab")
			(hide yes)
			(effects
				(font
					(size 1 1)
					(thickness 0.15)
				)
				(justify mirror)
			)
		)
		(sheetname "/USB DP Alt mode/")
		(sheetfile "usb_dp.kicad_sch")
		(attr smd exclude_from_pos_files exclude_from_bom dnp)
		(fp_poly
			(pts
				(xy -0.925 0.47) (xy 0.925 0.47) (xy 0.925 -0.47) (xy -0.925 -0.47)
			)
			(stroke
				(width 0.05)
				(type default)
			)
			(fill no)
			(layer "B.CrtYd")
		)
		(fp_poly
			(pts
				(xy -0.5 0.25) (xy 0.5 0.25) (xy 0.5 -0.25) (xy -0.5 -0.25)
			)
			(stroke
				(width 0.15)
				(type solid)
			)
			(fill no)
			(layer "B.Fab")
		)
		(fp_text user "${REFERENCE}"
			(at -0.95 -3.168 0)
			(layer "B.Fab")
			(effects
				(font
					(size 0.7 0.7)
					(thickness 0.15)
				)
				(justify right top mirror)
			)
		)
		(fp_text user "Author: Antmicro"
			(at -0.95 -4.169 0)
			(layer "B.Fab")
			(effects
				(font
					(size 0.7 0.7)
					(thickness 0.15)
				)
				(justify right top mirror)
			)
		)
		(fp_text user "License: Apache-2.0"
			(at -0.949999 -5.169 0)
			(layer "B.Fab")
			(effects
				(font
					(size 0.7 0.7)
					(thickness 0.15)
				)
				(justify right top mirror)
			)
		)
		(pad "1" smd roundrect
			(at -0.48 0)
			(size 0.59 0.64)
			(layers "B.Cu" "B.Mask" "B.Paste")
			(roundrect_rratio 0.25)
			(net 966 "/USB DP Alt mode/USBC1_DPEQ0")
			(pintype "passive")
		)
		(pad "2" smd roundrect
			(at 0.48 0)
			(size 0.59 0.64)
			(layers "B.Cu" "B.Mask" "B.Paste")
			(roundrect_rratio 0.25)
			(net 2 "+3V3")
			(pintype "passive")
		)
	)
	(footprint "antmicro-footprints:TP_SMD_0.75mm"
		(layer "B.Cu")
		(at 234 127 180)
		(property "Reference" "TP44"
			(at -3.5 -0.3 0)
			(layer "B.SilkS")
			(effects
				(font
					(size 0.7 0.7)
					(thickness 0.15)
				)
				(justify left bottom mirror)
			)
		)
		(property "Value" "TP_0.75mm_SMD"
			(at 0 -1.2 0)
			(layer "B.Fab")
			(effects
				(font
					(size 0.7 0.7)
					(thickness 0.15)
				)
				(justify left bottom mirror)
			)
		)
		(property "Description" "SMT test point"
			(at 0 0 0)
			(layer "B.Fab")
			(hide yes)
			(effects
				(font
					(size 1.27 1.27)
					(thickness 0.15)
				)
				(justify mirror)
			)
		)
		(property "MPN" ""
			(at 0 0 0)
			(unlocked yes)
			(layer "B.Fab")
			(hide yes)
			(effects
				(font
					(size 1 1)
					(thickness 0.15)
				)
				(justify mirror)
			)
		)
		(property "Manufacturer" ""
			(at 0 0 0)
			(unlocked yes)
			(layer "B.Fab")
			(hide yes)
			(effects
				(font
					(size 1 1)
					(thickness 0.15)
				)
				(justify mirror)
			)
		)
		(property "Author" "Antmicro"
			(at 0 0 0)
			(unlocked yes)
			(layer "B.Fab")
			(hide yes)
			(effects
				(font
					(size 1 1)
					(thickness 0.15)
				)
				(justify mirror)
			)
		)
		(property "License" "Apache-2.0"
			(at 0 0 0)
			(unlocked yes)
			(layer "B.Fab")
			(hide yes)
			(effects
				(font
					(size 1 1)
					(thickness 0.15)
				)
				(justify mirror)
			)
		)
		(sheetname "/USB Hub/")
		(sheetfile "usb_hub.kicad_sch")
		(attr exclude_from_pos_files exclude_from_bom)
		(fp_circle
			(center 0 0)
			(end 0.475 0)
			(stroke
				(width 0.05)
				(type default)
			)
			(fill no)
			(layer "B.CrtYd")
		)
		(fp_text user "License: Apache-2.0"
			(at -0.4 -5.101 0)
			(layer "B.Fab")
			(effects
				(font
					(size 0.7 0.7)
					(thickness 0.15)
				)
				(justify left bottom mirror)
			)
		)
		(fp_text user "${REFERENCE}"
			(at -0.4 -2.7 0)
			(layer "B.Fab")
			(effects
				(font
					(size 0.7 0.7)
					(thickness 0.15)
				)
				(justify left bottom mirror)
			)
		)
		(fp_text user "Author: Antmicro"
			(at -0.4 -3.901 0)
			(layer "B.Fab")
			(effects
				(font
					(size 0.7 0.7)
					(thickness 0.15)
				)
				(justify left bottom mirror)
			)
		)
		(pad "1" smd circle
			(at 0 0 180)
			(size 0.75 0.75)
			(layers "B.Cu" "B.Mask")
			(net 115 "/USB Hub/USBC4_VBUS")
			(pinfunction "1")
			(pintype "passive")
		)
	)
	(footprint "antmicro-footprints:C_0402_1005Metric"
		(layer "B.Cu")
		(at 219.52 75.1)
		(descr "Capacitor SMD 0402")
		(tags "capacitor SMD 0402")
		(property "Reference" "C133"
			(at -0.72 -1.4 0)
			(layer "B.SilkS")
			(effects
				(font
					(size 0.7 0.7)
					(thickness 0.15)
				)
				(justify right top mirror)
			)
		)
		(property "Value" "C_100n_0402"
			(at -1.022927 -2.155213 0)
			(layer "B.Fab")
			(effects
				(font
					(size 0.7 0.7)
					(thickness 0.15)
				)
				(justify right top mirror)
			)
		)
		(property "Datasheet" "https://www.murata.com/products/productdetail?partno=GRM155R61H104KE14%23"
			(at 0 0 0)
			(layer "B.Fab")
			(hide yes)
			(effects
				(font
					(size 1.27 1.27)
					(thickness 0.15)
				)
				(justify mirror)
			)
		)
		(property "Description" "SMD Multilayer Ceramic Capacitor, 0.1 µF, 50 V, 0402 [1005 Metric], ± 10%, X5R, GRM Series"
			(at 0 0 0)
			(layer "B.Fab")
			(hide yes)
			(effects
				(font
					(size 1.27 1.27)
					(thickness 0.15)
				)
				(justify mirror)
			)
		)
		(property "Manufacturer" "Murata"
			(at 0 0 180)
			(unlocked yes)
			(layer "B.Fab")
			(hide yes)
			(effects
				(font
					(size 1 1)
					(thickness 0.15)
				)
				(justify mirror)
			)
		)
		(property "MPN" "GRM155R61H104KE14D"
			(at 0 0 180)
			(unlocked yes)
			(layer "B.Fab")
			(hide yes)
			(effects
				(font
					(size 1 1)
					(thickness 0.15)
				)
				(justify mirror)
			)
		)
		(property "Val" "100n"
			(at 0 0 180)
			(unlocked yes)
			(layer "B.Fab")
			(hide yes)
			(effects
				(font
					(size 1 1)
					(thickness 0.15)
				)
				(justify mirror)
			)
		)
		(property "License" "Apache-2.0"
			(at 0 0 180)
			(unlocked yes)
			(layer "B.Fab")
			(hide yes)
			(effects
				(font
					(size 1 1)
					(thickness 0.15)
				)
				(justify mirror)
			)
		)
		(property "Author" "Antmicro"
			(at 0 0 180)
			(unlocked yes)
			(layer "B.Fab")
			(hide yes)
			(effects
				(font
					(size 1 1)
					(thickness 0.15)
				)
				(justify mirror)
			)
		)
		(property "Voltage" "50V"
			(at 0 0 180)
			(unlocked yes)
			(layer "B.Fab")
			(hide yes)
			(effects
				(font
					(size 1 1)
					(thickness 0.15)
				)
				(justify mirror)
			)
		)
		(property "Dielectric" "X5R"
			(at 0 0 180)
			(unlocked yes)
			(layer "B.Fab")
			(hide yes)
			(effects
				(font
					(size 1 1)
					(thickness 0.15)
				)
				(justify mirror)
			)
		)
		(sheetname "/USB Debug, PD/")
		(sheetfile "usb_debug_pd.kicad_sch")
		(attr smd)
		(fp_poly
			(pts
				(xy -0.925 0.47) (xy -0.925 -0.47) (xy 0.925 -0.47) (xy 0.925 0.47)
			)
			(stroke
				(width 0.05)
				(type default)
			)
			(fill no)
			(layer "B.CrtYd")
		)
		(fp_line
			(start -0.494 -0.248)
			(end -0.494 0.25)
			(stroke
				(width 0.15)
				(type solid)
			)
			(layer "B.Fab")
		)
		(fp_line
			(start -0.494 0.25)
			(end 0.504 0.25)
			(stroke
				(width 0.15)
				(type solid)
			)
			(layer "B.Fab")
		)
		(fp_line
			(start 0.504 -0.248)
			(end -0.494 -0.248)
			(stroke
				(width 0.15)
				(type solid)
			)
			(layer "B.Fab")
		)
		(fp_line
			(start 0.504 0.25)
			(end 0.504 -0.248)
			(stroke
				(width 0.15)
				(type solid)
			)
			(layer "B.Fab")
		)
		(fp_text user "Author: Antmicro"
			(at -0.939 -3.399 0)
			(layer "B.Fab")
			(effects
				(font
					(size 0.7 0.7)
					(thickness 0.15)
				)
				(justify right top mirror)
			)
		)
		(fp_text user "License: Apache-2.0"
			(at -0.939 -5.799 0)
			(layer "B.Fab")
			(effects
				(font
					(size 0.7 0.7)
					(thickness 0.15)
				)
				(justify right top mirror)
			)
		)
		(fp_text user "${REFERENCE}"
			(at -0.939 -4.599 0)
			(layer "B.Fab")
			(effects
				(font
					(size 0.7 0.7)
					(thickness 0.15)
				)
				(justify right top mirror)
			)
		)
		(pad "1" smd roundrect
			(at -0.48 0)
			(size 0.59 0.64)
			(layers "B.Cu" "B.Mask" "B.Paste")
			(roundrect_rratio 0.25)
			(net 334 "/USB Debug, PD/FTDI_3V3")
			(pintype "passive")
		)
		(pad "2" smd roundrect
			(at 0.48 0)
			(size 0.59 0.64)
			(layers "B.Cu" "B.Mask" "B.Paste")
			(roundrect_rratio 0.25)
			(net 1 "GND")
			(pintype "passive")
		)
	)
	(footprint "antmicro-footprints:C_0402_1005Metric"
		(layer "B.Cu")
		(at 180.24 88.85)
		(descr "Capacitor SMD 0402")
		(tags "capacitor SMD 0402")
		(property "Reference" "C265"
			(at -5.54 -0.35 0)
			(layer "B.SilkS")
			(effects
				(font
					(size 0.7 0.7)
					(thickness 0.15)
				)
				(justify right top mirror)
			)
		)
		(property "Value" "C_1u_25V_0402"
			(at -1.022927 -2.155213 0)
			(layer "B.Fab")
			(effects
				(font
					(size 0.7 0.7)
					(thickness 0.15)
				)
				(justify right top mirror)
			)
		)
		(property "Datasheet" "https://www.murata.com/products/productdetail?partno=GRM155R61E105KE11%23"
			(at 0 0 0)
			(layer "B.Fab")
			(hide yes)
			(effects
				(font
					(size 1.27 1.27)
					(thickness 0.15)
				)
				(justify mirror)
			)
		)
		(property "Description" "SMD Multilayer Ceramic Capacitor, 1 µF, 25 V, 0402 [1005 Metric], ± 10%, X5R, GRM Series"
			(at 0 0 0)
			(layer "B.Fab")
			(hide yes)
			(effects
				(font
					(size 1.27 1.27)
					(thickness 0.15)
				)
				(justify mirror)
			)
		)
		(property "MPN" "GRM155R61E105KE11J"
			(at 0 0 180)
			(unlocked yes)
			(layer "B.Fab")
			(hide yes)
			(effects
				(font
					(size 1 1)
					(thickness 0.15)
				)
				(justify mirror)
			)
		)
		(property "Manufacturer" "Murata"
			(at 0 0 180)
			(unlocked yes)
			(layer "B.Fab")
			(hide yes)
			(effects
				(font
					(size 1 1)
					(thickness 0.15)
				)
				(justify mirror)
			)
		)
		(property "License" "Apache-2.0"
			(at 0 0 180)
			(unlocked yes)
			(layer "B.Fab")
			(hide yes)
			(effects
				(font
					(size 1 1)
					(thickness 0.15)
				)
				(justify mirror)
			)
		)
		(property "Author" "Antmicro"
			(at 0 0 180)
			(unlocked yes)
			(layer "B.Fab")
			(hide yes)
			(effects
				(font
					(size 1 1)
					(thickness 0.15)
				)
				(justify mirror)
			)
		)
		(property "Val" "1u"
			(at 0 0 180)
			(unlocked yes)
			(layer "B.Fab")
			(hide yes)
			(effects
				(font
					(size 1 1)
					(thickness 0.15)
				)
				(justify mirror)
			)
		)
		(property "Voltage" "25V"
			(at 0 0 180)
			(unlocked yes)
			(layer "B.Fab")
			(hide yes)
			(effects
				(font
					(size 1 1)
					(thickness 0.15)
				)
				(justify mirror)
			)
		)
		(property "Dielectric" "X5R"
			(at 0 0 180)
			(unlocked yes)
			(layer "B.Fab")
			(hide yes)
			(effects
				(font
					(size 1 1)
					(thickness 0.15)
				)
				(justify mirror)
			)
		)
		(sheetname "/Power/")
		(sheetfile "power.kicad_sch")
		(attr smd)
		(fp_rect
			(start -0.925 0.47)
			(end 0.925 -0.47)
			(stroke
				(width 0.05)
				(type default)
			)
			(fill no)
			(layer "B.CrtYd")
		)
		(fp_line
			(start -0.494 -0.248)
			(end -0.494 0.25)
			(stroke
				(width 0.15)
				(type solid)
			)
			(layer "B.Fab")
		)
		(fp_line
			(start -0.494 0.25)
			(end 0.504 0.25)
			(stroke
				(width 0.15)
				(type solid)
			)
			(layer "B.Fab")
		)
		(fp_line
			(start 0.504 -0.248)
			(end -0.494 -0.248)
			(stroke
				(width 0.15)
				(type solid)
			)
			(layer "B.Fab")
		)
		(fp_line
			(start 0.504 0.25)
			(end 0.504 -0.248)
			(stroke
				(width 0.15)
				(type solid)
			)
			(layer "B.Fab")
		)
		(fp_text user "License: Apache-2.0"
			(at -0.939 -5.799 0)
			(layer "B.Fab")
			(effects
				(font
					(size 0.7 0.7)
					(thickness 0.15)
				)
				(justify right top mirror)
			)
		)
		(fp_text user "${REFERENCE}"
			(at -0.939 -4.599 0)
			(layer "B.Fab")
			(effects
				(font
					(size 0.7 0.7)
					(thickness 0.15)
				)
				(justify right top mirror)
			)
		)
		(fp_text user "Author: Antmicro"
			(at -0.939 -3.399 0)
			(layer "B.Fab")
			(effects
				(font
					(size 0.7 0.7)
					(thickness 0.15)
				)
				(justify right top mirror)
			)
		)
		(pad "1" smd roundrect
			(at -0.48 0)
			(size 0.59 0.64)
			(layers "B.Cu" "B.Mask" "B.Paste")
			(roundrect_rratio 0.25)
			(net 1 "GND")
			(pintype "passive")
		)
		(pad "2" smd roundrect
			(at 0.48 0)
			(size 0.59 0.64)
			(layers "B.Cu" "B.Mask" "B.Paste")
			(roundrect_rratio 0.25)
			(net 522 "/Power/USBPD1_HV")
			(pintype "passive")
		)
	)
	(footprint "antmicro-footprints:R_0402_1005Metric"
		(layer "B.Cu")
		(at 207.8 81.3 180)
		(descr "Resistor SMD 0402")
		(tags "resistor SMD 0402")
		(property "Reference" "R96"
			(at -3.1 -1.4 0)
			(layer "B.SilkS")
			(effects
				(font
					(size 0.7 0.7)
					(thickness 0.15)
				)
				(justify left bottom mirror)
			)
		)
		(property "Value" "R_10k_0402"
			(at -1.011843 -1.772046 0)
			(layer "B.Fab")
			(effects
				(font
					(size 0.7 0.7)
					(thickness 0.15)
				)
				(justify left bottom mirror)
			)
		)
		(property "Datasheet" "https://www.bourns.com/docs/product-datasheets/cr.pdf"
			(at 0 0 0)
			(layer "B.Fab")
			(hide yes)
			(effects
				(font
					(size 1.27 1.27)
					(thickness 0.15)
				)
				(justify mirror)
			)
		)
		(property "Description" "SMD Chip Resistor, 10 kohm, ± 1%, 62.5 mW, 0402 [1005 Metric], Thick Film, General Purpose"
			(at 0 0 0)
			(layer "B.Fab")
			(hide yes)
			(effects
				(font
					(size 1.27 1.27)
					(thickness 0.15)
				)
				(justify mirror)
			)
		)
		(property "Manufacturer" "Bourns"
			(at 0 0 0)
			(unlocked yes)
			(layer "B.Fab")
			(hide yes)
			(effects
				(font
					(size 1 1)
					(thickness 0.15)
				)
				(justify mirror)
			)
		)
		(property "MPN" "CR0402-FX-1002GLF"
			(at 0 0 0)
			(unlocked yes)
			(layer "B.Fab")
			(hide yes)
			(effects
				(font
					(size 1 1)
					(thickness 0.15)
				)
				(justify mirror)
			)
		)
		(property "Val" "10k"
			(at 0 0 0)
			(unlocked yes)
			(layer "B.Fab")
			(hide yes)
			(effects
				(font
					(size 1 1)
					(thickness 0.15)
				)
				(justify mirror)
			)
		)
		(property "License" "Apache-2.0"
			(at 0 0 0)
			(unlocked yes)
			(layer "B.Fab")
			(hide yes)
			(effects
				(font
					(size 1 1)
					(thickness 0.15)
				)
				(justify mirror)
			)
		)
		(property "Author" "Antmicro"
			(at 0 0 0)
			(unlocked yes)
			(layer "B.Fab")
			(hide yes)
			(effects
				(font
					(size 1 1)
					(thickness 0.15)
				)
				(justify mirror)
			)
		)
		(property "Tolerance" "1%"
			(at 0 0 0)
			(unlocked yes)
			(layer "B.Fab")
			(hide yes)
			(effects
				(font
					(size 1 1)
					(thickness 0.15)
				)
				(justify mirror)
			)
		)
		(sheetname "/USB Debug, PD/")
		(sheetfile "usb_debug_pd.kicad_sch")
		(attr smd)
		(fp_poly
			(pts
				(xy -0.925 0.47) (xy 0.925 0.47) (xy 0.925 -0.47) (xy -0.925 -0.47)
			)
			(stroke
				(width 0.05)
				(type default)
			)
			(fill no)
			(layer "B.CrtYd")
		)
		(fp_poly
			(pts
				(xy -0.5 0.25) (xy 0.5 0.25) (xy 0.5 -0.25) (xy -0.5 -0.25)
			)
			(stroke
				(width 0.15)
				(type solid)
			)
			(fill no)
			(layer "B.Fab")
		)
		(fp_text user "Author: Antmicro"
			(at -0.95 -4.169 0)
			(layer "B.Fab")
			(effects
				(font
					(size 0.7 0.7)
					(thickness 0.15)
				)
				(justify left bottom mirror)
			)
		)
		(fp_text user "License: Apache-2.0"
			(at -0.949999 -5.169 0)
			(layer "B.Fab")
			(effects
				(font
					(size 0.7 0.7)
					(thickness 0.15)
				)
				(justify left bottom mirror)
			)
		)
		(fp_text user "${REFERENCE}"
			(at -0.95 -3.168 0)
			(layer "B.Fab")
			(effects
				(font
					(size 0.7 0.7)
					(thickness 0.15)
				)
				(justify left bottom mirror)
			)
		)
		(pad "1" smd roundrect
			(at -0.48 0 180)
			(size 0.59 0.64)
			(layers "B.Cu" "B.Mask" "B.Paste")
			(roundrect_rratio 0.25)
			(net 294 "/USB Debug, PD/PDC_LDO_3V3")
			(pintype "passive")
		)
		(pad "2" smd roundrect
			(at 0.48 0 180)
			(size 0.59 0.64)
			(layers "B.Cu" "B.Mask" "B.Paste")
			(roundrect_rratio 0.25)
			(net 935 "/USB Debug, PD/PDC_ADCIN2")
			(pintype "passive")
		)
	)
	(footprint "antmicro-footprints:TP_SMD_0.75mm"
		(layer "B.Cu")
		(at 63.5 120.5)
		(property "Reference" "TP114"
			(at -0.5 2.200001 0)
			(layer "B.SilkS")
			(effects
				(font
					(size 0.7 0.7)
					(thickness 0.15)
				)
				(justify right top mirror)
			)
		)
		(property "Value" "TP_0.75mm_SMD"
			(at 0 -1.2 0)
			(layer "B.Fab")
			(effects
				(font
					(size 0.7 0.7)
					(thickness 0.15)
				)
				(justify right top mirror)
			)
		)
		(property "Description" "SMT test point"
			(at 0 0 0)
			(layer "B.Fab")
			(hide yes)
			(effects
				(font
					(size 1.27 1.27)
					(thickness 0.15)
				)
				(justify mirror)
			)
		)
		(property "MPN" ""
			(at 0 0 180)
			(unlocked yes)
			(layer "B.Fab")
			(hide yes)
			(effects
				(font
					(size 1 1)
					(thickness 0.15)
				)
				(justify mirror)
			)
		)
		(property "Manufacturer" ""
			(at 0 0 180)
			(unlocked yes)
			(layer "B.Fab")
			(hide yes)
			(effects
				(font
					(size 1 1)
					(thickness 0.15)
				)
				(justify mirror)
			)
		)
		(property "Author" "Antmicro"
			(at 0 0 180)
			(unlocked yes)
			(layer "B.Fab")
			(hide yes)
			(effects
				(font
					(size 1 1)
					(thickness 0.15)
				)
				(justify mirror)
			)
		)
		(property "License" "Apache-2.0"
			(at 0 0 180)
			(unlocked yes)
			(layer "B.Fab")
			(hide yes)
			(effects
				(font
					(size 1 1)
					(thickness 0.15)
				)
				(justify mirror)
			)
		)
		(sheetname "/Expansion connector/")
		(sheetfile "expansion_connector.kicad_sch")
		(attr exclude_from_pos_files exclude_from_bom)
		(fp_circle
			(center 0 0)
			(end 0.475 0)
			(stroke
				(width 0.05)
				(type default)
			)
			(fill no)
			(layer "B.CrtYd")
		)
		(fp_text user "Author: Antmicro"
			(at -0.4 -3.901 0)
			(layer "B.Fab")
			(effects
				(font
					(size 0.7 0.7)
					(thickness 0.15)
				)
				(justify right top mirror)
			)
		)
		(fp_text user "License: Apache-2.0"
			(at -0.4 -5.101 0)
			(layer "B.Fab")
			(effects
				(font
					(size 0.7 0.7)
					(thickness 0.15)
				)
				(justify right top mirror)
			)
		)
		(fp_text user "${REFERENCE}"
			(at -0.4 -2.7 0)
			(layer "B.Fab")
			(effects
				(font
					(size 0.7 0.7)
					(thickness 0.15)
				)
				(justify right top mirror)
			)
		)
		(pad "1" smd circle
			(at 0 0)
			(size 0.75 0.75)
			(layers "B.Cu" "B.Mask")
			(net 571 "Net-(J18-PadL32)")
			(pinfunction "1")
			(pintype "passive")
		)
	)
	(footprint "antmicro-footprints:QFN-2L_1.6x1x0.55mm"
		(layer "B.Cu")
		(at 230.87 90.2 180)
		(property "Reference" "D22"
			(at 1.2 -0.7 0)
			(layer "B.SilkS")
			(effects
				(font
					(size 0.7 0.7)
					(thickness 0.15)
				)
				(justify left bottom mirror)
			)
		)
		(property "Value" "ESDA25P35-1U1M"
			(at 0 -1.7 0)
			(layer "B.Fab")
			(effects
				(font
					(size 0.7 0.7)
					(thickness 0.15)
				)
				(justify left bottom mirror)
			)
		)
		(property "Datasheet" "https://www.st.com/resource/en/datasheet/esda25p35-1u1m.pdf"
			(at 0 0 0)
			(layer "B.Fab")
			(hide yes)
			(effects
				(font
					(size 1.27 1.27)
					(thickness 0.15)
				)
				(justify mirror)
			)
		)
		(property "Description" "Unidirectional TVS, 30 kV, QFN-2L, 22 V, 195 pF"
			(at 0 0 0)
			(layer "B.Fab")
			(hide yes)
			(effects
				(font
					(size 1.27 1.27)
					(thickness 0.15)
				)
				(justify mirror)
			)
		)
		(property "Manufacturer" "STMicroelectronics"
			(at 0 0 180)
			(unlocked yes)
			(layer "B.Fab")
			(hide yes)
			(effects
				(font
					(size 1 1)
					(thickness 0.15)
				)
				(justify mirror)
			)
		)
		(property "MPN" "ESDA25P35-1U1M"
			(at 0 0 180)
			(unlocked yes)
			(layer "B.Fab")
			(hide yes)
			(effects
				(font
					(size 1 1)
					(thickness 0.15)
				)
				(justify mirror)
			)
		)
		(property "Author" "Antmicro"
			(at 0 0 180)
			(unlocked yes)
			(layer "B.Fab")
			(hide yes)
			(effects
				(font
					(size 1 1)
					(thickness 0.15)
				)
				(justify mirror)
			)
		)
		(property "License" "Apache-2.0"
			(at 0 0 180)
			(unlocked yes)
			(layer "B.Fab")
			(hide yes)
			(effects
				(font
					(size 1 1)
					(thickness 0.15)
				)
				(justify mirror)
			)
		)
		(sheetname "/USB DP Alt mode/")
		(sheetfile "usb_dp.kicad_sch")
		(attr smd)
		(fp_line
			(start 0.23 0.45)
			(end -0.23 0.45)
			(stroke
				(width 0.15)
				(type solid)
			)
			(layer "B.SilkS")
		)
		(fp_line
			(start 0.23 -0.45)
			(end -0.23 -0.45)
			(stroke
				(width 0.15)
				(type solid)
			)
			(layer "B.SilkS")
		)
		(fp_line
			(start -1.2 0.4)
			(end -1.2 -0.4)
			(stroke
				(width 0.15)
				(type solid)
			)
			(layer "B.SilkS")
		)
		(fp_rect
			(start 1.25 -0.65)
			(end -1.25 0.65)
			(stroke
				(width 0.05)
				(type solid)
			)
			(fill no)
			(layer "B.CrtYd")
		)
		(fp_line
			(start 0.599 0)
			(end 0.201 0)
			(stroke
				(width 0.15)
				(type solid)
			)
			(layer "B.Fab")
		)
		(fp_line
			(start 0.201 0.202)
			(end -0.101 0)
			(stroke
				(width 0.15)
				(type solid)
			)
			(layer "B.Fab")
		)
		(fp_line
			(start 0.201 0)
			(end 0.201 0.202)
			(stroke
				(width 0.15)
				(type solid)
			)
			(layer "B.Fab")
		)
		(fp_line
			(start 0.201 -0.2)
			(end 0.201 0)
			(stroke
				(width 0.15)
				(type solid)
			)
			(layer "B.Fab")
		)
		(fp_line
			(start -0.101 0)
			(end 0.201 -0.2)
			(stroke
				(width 0.15)
				(type solid)
			)
			(layer "B.Fab")
		)
		(fp_line
			(start -0.199 0.202)
			(end -0.199 -0.1)
			(stroke
				(width 0.15)
				(type solid)
			)
			(layer "B.Fab")
		)
		(fp_line
			(start -0.199 0)
			(end -0.597 0)
			(stroke
				(width 0.15)
				(type solid)
			)
			(layer "B.Fab")
		)
		(fp_line
			(start -0.199 -0.2)
			(end -0.199 -0.1)
			(stroke
				(width 0.15)
				(type solid)
			)
			(layer "B.Fab")
		)
		(fp_rect
			(start 0.848 -0.4)
			(end -0.85 0.402)
			(stroke
				(width 0.15)
				(type solid)
			)
			(fill no)
			(layer "B.Fab")
		)
		(fp_text user "Author: Antmicro"
			(at -1.31 -4.769 0)
			(layer "B.Fab")
			(effects
				(font
					(size 0.7 0.7)
					(thickness 0.15)
				)
				(justify left bottom mirror)
			)
		)
		(fp_text user "License: Apache-2.0"
			(at -1.31 -5.769 0)
			(layer "B.Fab")
			(effects
				(font
					(size 0.7 0.7)
					(thickness 0.15)
				)
				(justify left bottom mirror)
			)
		)
		(fp_text user "${REFERENCE}"
			(at -1.31 -3.769 0)
			(layer "B.Fab")
			(effects
				(font
					(size 0.7 0.7)
					(thickness 0.15)
				)
				(justify left bottom mirror)
			)
		)
		(pad "1" smd roundrect
			(at -0.7 0)
			(size 0.8 1)
			(layers "B.Cu" "B.Mask" "B.Paste")
			(roundrect_rratio 0.2)
			(net 376 "/USB DP Alt mode/USBC1_VBUS")
			(pinfunction "C")
			(pintype "passive")
		)
		(pad "2" smd roundrect
			(at 0.7 0)
			(size 0.8 1)
			(layers "B.Cu" "B.Mask" "B.Paste")
			(roundrect_rratio 0.2)
			(net 1 "GND")
			(pinfunction "A")
			(pintype "passive")
		)
	)
	(footprint "antmicro-footprints:SOT-523"
		(layer "B.Cu")
		(at 225.5 109.2 180)
		(property "Reference" "Q19"
			(at 0.995 -3.4 270)
			(layer "B.SilkS")
			(effects
				(font
					(size 0.7 0.7)
					(thickness 0.15)
				)
				(justify right top mirror)
			)
		)
		(property "Value" "DMG1012T-7"
			(at 0.1 -1.824 0)
			(layer "B.Fab")
			(effects
				(font
					(size 0.7 0.7)
					(thickness 0.15)
				)
				(justify left bottom mirror)
			)
		)
		(property "Datasheet" "https://www.diodes.com/assets/Datasheets/ds31783.pdf"
			(at 0 0 0)
			(layer "B.Fab")
			(hide yes)
			(effects
				(font
					(size 1.27 1.27)
					(thickness 0.15)
				)
				(justify mirror)
			)
		)
		(property "Description" "Power MOSFET, N Channel, 20 V, 630 mA, 0.3 ohm, SOT-523, Surface Mount"
			(at 0 0 0)
			(layer "B.Fab")
			(hide yes)
			(effects
				(font
					(size 1.27 1.27)
					(thickness 0.15)
				)
				(justify mirror)
			)
		)
		(property "MPN" "DMG1012T-7"
			(at 0 0 0)
			(unlocked yes)
			(layer "B.Fab")
			(hide yes)
			(effects
				(font
					(size 1 1)
					(thickness 0.15)
				)
				(justify mirror)
			)
		)
		(property "Manufacturer" "Diodes Incorporated"
			(at 0 0 0)
			(unlocked yes)
			(layer "B.Fab")
			(hide yes)
			(effects
				(font
					(size 1 1)
					(thickness 0.15)
				)
				(justify mirror)
			)
		)
		(property "Author" "Antmicro"
			(at 0 0 0)
			(unlocked yes)
			(layer "B.Fab")
			(hide yes)
			(effects
				(font
					(size 1 1)
					(thickness 0.15)
				)
				(justify mirror)
			)
		)
		(property "License" "Apache-2.0"
			(at 0 0 0)
			(unlocked yes)
			(layer "B.Fab")
			(hide yes)
			(effects
				(font
					(size 1 1)
					(thickness 0.15)
				)
				(justify mirror)
			)
		)
		(sheetname "/Recovery USB/")
		(sheetfile "recovery_usb.kicad_sch")
		(attr smd)
		(fp_line
			(start -0.277 0.551)
			(end -0.277 0.75)
			(stroke
				(width 0.15)
				(type solid)
			)
			(layer "B.SilkS")
		)
		(fp_line
			(start -0.725 0.551)
			(end -0.277 0.551)
			(stroke
				(width 0.15)
				(type solid)
			)
			(layer "B.SilkS")
		)
		(fp_line
			(start -0.927 0.351)
			(end -0.725 0.551)
			(stroke
				(width 0.15)
				(type solid)
			)
			(layer "B.SilkS")
		)
		(fp_line
			(start -0.927 0.051)
			(end -0.927 0.351)
			(stroke
				(width 0.15)
				(type solid)
			)
			(layer "B.SilkS")
		)
		(fp_circle
			(center -0.9652 -0.9652)
			(end -0.9152 -0.9652)
			(stroke
				(width 0.15)
				(type solid)
			)
			(fill yes)
			(layer "B.SilkS")
		)
		(fp_line
			(start 1.1 1.16)
			(end 1.1 -1.15)
			(stroke
				(width 0.05)
				(type solid)
			)
			(layer "B.CrtYd")
		)
		(fp_line
			(start -1.12 1.16)
			(end 1.1 1.16)
			(stroke
				(width 0.05)
				(type solid)
			)
			(layer "B.CrtYd")
		)
		(fp_line
			(start -1.12 1.16)
			(end -1.12 -1.15)
			(stroke
				(width 0.05)
				(type solid)
			)
			(layer "B.CrtYd")
		)
		(fp_line
			(start -1.12 -1.15)
			(end 1.1 -1.15)
			(stroke
				(width 0.05)
				(type solid)
			)
			(layer "B.CrtYd")
		)
		(fp_line
			(start 0.8 0.425)
			(end 0.8 -0.424)
			(stroke
				(width 0.15)
				(type solid)
			)
			(layer "B.Fab")
		)
		(fp_line
			(start 0.8 0.425)
			(end -0.652 0.425)
			(stroke
				(width 0.15)
				(type solid)
			)
			(layer "B.Fab")
		)
		(fp_line
			(start 0.8 -0.424)
			(end -0.802 -0.424)
			(stroke
				(width 0.15)
				(type solid)
			)
			(layer "B.Fab")
		)
		(fp_line
			(start -0.652 0.425)
			(end -0.802 0.276)
			(stroke
				(width 0.15)
				(type solid)
			)
			(layer "B.Fab")
		)
		(fp_line
			(start -0.802 0.276)
			(end -0.802 -0.424)
			(stroke
				(width 0.15)
				(type solid)
			)
			(layer "B.Fab")
		)
		(fp_circle
			(center -0.9652 -0.9652)
			(end -0.9144 -0.9652)
			(stroke
				(width 0.15)
				(type solid)
			)
			(fill no)
			(layer "B.Fab")
		)
		(fp_text user "${REFERENCE}"
			(at -1.12 -3.824 0)
			(layer "B.Fab")
			(effects
				(font
					(size 0.7 0.7)
					(thickness 0.15)
				)
				(justify left bottom mirror)
			)
		)
		(fp_text user "License: Apache-2.0"
			(at -1.12 -5.024 0)
			(layer "B.Fab")
			(effects
				(font
					(size 0.7 0.7)
					(thickness 0.15)
				)
				(justify left bottom mirror)
			)
		)
		(fp_text user "Author: Antmicro"
			(at -1.12 -6.224 0)
			(layer "B.Fab")
			(effects
				(font
					(size 0.7 0.7)
					(thickness 0.15)
				)
				(justify left bottom mirror)
			)
		)
		(pad "1" smd rect
			(at -0.5 -0.65 180)
			(size 0.4 0.51)
			(layers "B.Cu" "B.Mask" "B.Paste")
			(net 889 "/Recovery USB/USBC2_ID")
			(pinfunction "G")
			(pintype "input")
		)
		(pad "2" smd rect
			(at 0.498 -0.65 180)
			(size 0.4 0.51)
			(layers "B.Cu" "B.Mask" "B.Paste")
			(net 1 "GND")
			(pinfunction "S")
			(pintype "passive")
		)
		(pad "3" smd rect
			(at 0 0.652 180)
			(size 0.4 0.51)
			(layers "B.Cu" "B.Mask" "B.Paste")
			(net 890 "Net-(Q19-D)")
			(pinfunction "D")
			(pintype "passive")
		)
	)
	(footprint "antmicro-footprints:USON-10_2.5x1mm_P0.5mm"
		(layer "B.Cu")
		(at 147.13 60.91 90)
		(descr "USON-10 2.5x1mm_ Pitch 0.5mm")
		(tags "USON-10 2.5x1mm Pitch 0.5mm")
		(property "Reference" "U68"
			(at -0.99 -0.03 0)
			(layer "B.SilkS")
			(effects
				(font
					(size 0.7 0.7)
					(thickness 0.15)
				)
				(justify right top mirror)
			)
		)
		(property "Value" "TPD4E05U06QDQARQ1"
			(at 0.018 -2.499 90)
			(layer "B.Fab")
			(effects
				(font
					(size 0.7 0.7)
					(thickness 0.15)
				)
				(justify right top mirror)
			)
		)
		(property "Datasheet" "https://www.ti.com/lit/ds/symlink/tpd4e05u06-q1.pdf?HQS=dis-mous-null-mousermode-dsf-pf-null-wwe&ts=1663591265741&ref_url=https%253A%252F%252Fwww.mouser.com%252F"
			(at 0 0 90)
			(layer "B.Fab")
			(hide yes)
			(effects
				(font
					(size 1.27 1.27)
					(thickness 0.15)
				)
				(justify mirror)
			)
		)
		(property "Description" "TVS diode array, 12 kV, USON-10, 5.5 V, 0.5 pF"
			(at 0 0 90)
			(layer "B.Fab")
			(hide yes)
			(effects
				(font
					(size 1.27 1.27)
					(thickness 0.15)
				)
				(justify mirror)
			)
		)
		(property "Manufacturer" "Texas Instruments"
			(at 0 0 270)
			(unlocked yes)
			(layer "B.Fab")
			(hide yes)
			(effects
				(font
					(size 1 1)
					(thickness 0.15)
				)
				(justify mirror)
			)
		)
		(property "MPN" "TPD4E05U06QDQARQ1"
			(at 0 0 270)
			(unlocked yes)
			(layer "B.Fab")
			(hide yes)
			(effects
				(font
					(size 1 1)
					(thickness 0.15)
				)
				(justify mirror)
			)
		)
		(property "Author" "Antmicro"
			(at 0 0 270)
			(unlocked yes)
			(layer "B.Fab")
			(hide yes)
			(effects
				(font
					(size 1 1)
					(thickness 0.15)
				)
				(justify mirror)
			)
		)
		(property "License" "Apache-2.0"
			(at 0 0 270)
			(unlocked yes)
			(layer "B.Fab")
			(hide yes)
			(effects
				(font
					(size 1 1)
					(thickness 0.15)
				)
				(justify mirror)
			)
		)
		(sheetname "/Peripherals/")
		(sheetfile "peripherals.kicad_sch")
		(attr smd)
		(fp_line
			(start 0.498 -1.398)
			(end -0.5 -1.398)
			(stroke
				(width 0.15)
				(type solid)
			)
			(layer "B.SilkS")
		)
		(fp_line
			(start 0.498 1.401)
			(end -0.5 1.401)
			(stroke
				(width 0.15)
				(type solid)
			)
			(layer "B.SilkS")
		)
		(fp_circle
			(center -0.68 1.27)
			(end -0.63 1.27)
			(stroke
				(width 0.15)
				(type solid)
			)
			(fill yes)
			(layer "B.SilkS")
		)
		(fp_rect
			(start -0.8 1.5)
			(end 0.8 -1.499)
			(stroke
				(width 0.05)
				(type solid)
			)
			(fill no)
			(layer "B.CrtYd")
		)
		(fp_line
			(start -0.5 -1.249)
			(end 0.498 -1.249)
			(stroke
				(width 0.15)
				(type solid)
			)
			(layer "B.Fab")
		)
		(fp_line
			(start -0.5 1)
			(end -0.5 -1.249)
			(stroke
				(width 0.15)
				(type solid)
			)
			(layer "B.Fab")
		)
		(fp_line
			(start 0.498 1.25)
			(end 0.498 -1.249)
			(stroke
				(width 0.15)
				(type solid)
			)
			(layer "B.Fab")
		)
		(fp_line
			(start 0.498 1.25)
			(end -0.25 1.25)
			(stroke
				(width 0.15)
				(type solid)
			)
			(layer "B.Fab")
		)
		(fp_line
			(start -0.25 1.25)
			(end -0.5 1)
			(stroke
				(width 0.15)
				(type solid)
			)
			(layer "B.Fab")
		)
		(fp_text user "Author: Antmicro"
			(at -0.802 -5.7 90)
			(layer "B.Fab")
			(effects
				(font
					(size 0.7 0.7)
					(thickness 0.15)
				)
				(justify right top mirror)
			)
		)
		(fp_text user "${REFERENCE}"
			(at -0.802 -4.498 90)
			(layer "B.Fab")
			(effects
				(font
					(size 0.7 0.7)
					(thickness 0.15)
				)
				(justify right top mirror)
			)
		)
		(fp_text user "License: Apache-2.0"
			(at -0.802 -6.9 90)
			(layer "B.Fab")
			(effects
				(font
					(size 0.7 0.7)
					(thickness 0.15)
				)
				(justify right top mirror)
			)
		)
		(pad "1" smd roundrect
			(at -0.387 1 180)
			(size 0.25 0.55)
			(layers "B.Cu" "B.Mask" "B.Paste")
			(roundrect_rratio 0.25)
			(net 42 "/Peripherals/I2C_{CONN}.SCL")
			(pintype "passive")
		)
		(pad "2" smd roundrect
			(at -0.387 0.5 180)
			(size 0.25 0.55)
			(layers "B.Cu" "B.Mask" "B.Paste")
			(roundrect_rratio 0.25)
			(net 43 "/Peripherals/I2C_{CONN}.SDA")
			(pintype "passive")
		)
		(pad "3" smd roundrect
			(at -0.387 0 180)
			(size 0.4 0.55)
			(layers "B.Cu" "B.Mask" "B.Paste")
			(roundrect_rratio 0.25)
			(net 1 "GND")
			(pintype "power_in")
		)
		(pad "4" smd roundrect
			(at -0.387 -0.498 180)
			(size 0.25 0.55)
			(layers "B.Cu" "B.Mask" "B.Paste")
			(roundrect_rratio 0.25)
			(net 839 "/Peripherals/I2C_CONN2_3V3")
			(pintype "passive")
		)
		(pad "5" smd roundrect
			(at -0.387 -0.998 180)
			(size 0.25 0.55)
			(layers "B.Cu" "B.Mask" "B.Paste")
			(roundrect_rratio 0.25)
			(net 1 "GND")
			(pintype "passive")
		)
		(pad "6" smd roundrect
			(at 0.385 -0.998 180)
			(size 0.25 0.55)
			(layers "B.Cu" "B.Mask" "B.Paste")
			(roundrect_rratio 0.25)
			(net 1 "GND")
			(pintype "passive")
		)
		(pad "7" smd roundrect
			(at 0.385 -0.498 180)
			(size 0.25 0.55)
			(layers "B.Cu" "B.Mask" "B.Paste")
			(roundrect_rratio 0.25)
			(net 839 "/Peripherals/I2C_CONN2_3V3")
			(pintype "passive")
		)
		(pad "8" smd roundrect
			(at 0.385 0 180)
			(size 0.4 0.55)
			(layers "B.Cu" "B.Mask" "B.Paste")
			(roundrect_rratio 0.25)
			(net 1 "GND")
			(pintype "passive")
		)
		(pad "9" smd roundrect
			(at 0.385 0.5 180)
			(size 0.25 0.55)
			(layers "B.Cu" "B.Mask" "B.Paste")
			(roundrect_rratio 0.25)
			(net 43 "/Peripherals/I2C_{CONN}.SDA")
			(pintype "passive")
		)
		(pad "10" smd roundrect
			(at 0.385 1 180)
			(size 0.25 0.55)
			(layers "B.Cu" "B.Mask" "B.Paste")
			(roundrect_rratio 0.25)
			(net 42 "/Peripherals/I2C_{CONN}.SCL")
			(pintype "passive")
		)
	)
	(footprint "antmicro-footprints:C_0402_1005Metric"
		(layer "B.Cu")
		(at 89.8 74.8 90)
		(descr "Capacitor SMD 0402")
		(tags "capacitor SMD 0402")
		(property "Reference" "C366"
			(at -0.9 0.7 90)
			(layer "B.SilkS")
			(effects
				(font
					(size 0.7 0.7)
					(thickness 0.15)
				)
				(justify right top mirror)
			)
		)
		(property "Value" "C_1u_25V_0402"
			(at -1.022927 -2.155213 90)
			(layer "B.Fab")
			(effects
				(font
					(size 0.7 0.7)
					(thickness 0.15)
				)
				(justify right top mirror)
			)
		)
		(property "Datasheet" "https://www.murata.com/products/productdetail?partno=GRM155R61E105KE11%23"
			(at 0 0 90)
			(layer "B.Fab")
			(hide yes)
			(effects
				(font
					(size 1.27 1.27)
					(thickness 0.15)
				)
				(justify mirror)
			)
		)
		(property "Description" "SMD Multilayer Ceramic Capacitor, 1 µF, 25 V, 0402 [1005 Metric], ± 10%, X5R, GRM Series"
			(at 0 0 90)
			(layer "B.Fab")
			(hide yes)
			(effects
				(font
					(size 1.27 1.27)
					(thickness 0.15)
				)
				(justify mirror)
			)
		)
		(property "MPN" "GRM155R61E105KE11J"
			(at 0 0 270)
			(unlocked yes)
			(layer "B.Fab")
			(hide yes)
			(effects
				(font
					(size 1 1)
					(thickness 0.15)
				)
				(justify mirror)
			)
		)
		(property "Manufacturer" "Murata"
			(at 0 0 270)
			(unlocked yes)
			(layer "B.Fab")
			(hide yes)
			(effects
				(font
					(size 1 1)
					(thickness 0.15)
				)
				(justify mirror)
			)
		)
		(property "License" "Apache-2.0"
			(at 0 0 270)
			(unlocked yes)
			(layer "B.Fab")
			(hide yes)
			(effects
				(font
					(size 1 1)
					(thickness 0.15)
				)
				(justify mirror)
			)
		)
		(property "Author" "Antmicro"
			(at 0 0 270)
			(unlocked yes)
			(layer "B.Fab")
			(hide yes)
			(effects
				(font
					(size 1 1)
					(thickness 0.15)
				)
				(justify mirror)
			)
		)
		(property "Val" "1u"
			(at 0 0 270)
			(unlocked yes)
			(layer "B.Fab")
			(hide yes)
			(effects
				(font
					(size 1 1)
					(thickness 0.15)
				)
				(justify mirror)
			)
		)
		(property "Voltage" "25V"
			(at 0 0 270)
			(unlocked yes)
			(layer "B.Fab")
			(hide yes)
			(effects
				(font
					(size 1 1)
					(thickness 0.15)
				)
				(justify mirror)
			)
		)
		(property "Dielectric" "X5R"
			(at 0 0 270)
			(unlocked yes)
			(layer "B.Fab")
			(hide yes)
			(effects
				(font
					(size 1 1)
					(thickness 0.15)
				)
				(justify mirror)
			)
		)
		(sheetname "/SoM_Power/")
		(sheetfile "som_power.kicad_sch")
		(attr smd)
		(fp_poly
			(pts
				(xy -0.925 0.47) (xy 0.925 0.47) (xy 0.925 -0.47) (xy -0.925 -0.47)
			)
			(stroke
				(width 0.05)
				(type default)
			)
			(fill no)
			(layer "B.CrtYd")
		)
		(fp_line
			(start 0.504 -0.248)
			(end -0.494 -0.248)
			(stroke
				(width 0.15)
				(type solid)
			)
			(layer "B.Fab")
		)
		(fp_line
			(start -0.494 -0.248)
			(end -0.494 0.25)
			(stroke
				(width 0.15)
				(type solid)
			)
			(layer "B.Fab")
		)
		(fp_line
			(start 0.504 0.25)
			(end 0.504 -0.248)
			(stroke
				(width 0.15)
				(type solid)
			)
			(layer "B.Fab")
		)
		(fp_line
			(start -0.494 0.25)
			(end 0.504 0.25)
			(stroke
				(width 0.15)
				(type solid)
			)
			(layer "B.Fab")
		)
		(fp_text user "Author: Antmicro"
			(at -0.939 -3.399 90)
			(layer "B.Fab")
			(effects
				(font
					(size 0.7 0.7)
					(thickness 0.15)
				)
				(justify right top mirror)
			)
		)
		(fp_text user "${REFERENCE}"
			(at -0.939 -4.599 90)
			(layer "B.Fab")
			(effects
				(font
					(size 0.7 0.7)
					(thickness 0.15)
				)
				(justify right top mirror)
			)
		)
		(fp_text user "License: Apache-2.0"
			(at -0.939 -5.799 90)
			(layer "B.Fab")
			(effects
				(font
					(size 0.7 0.7)
					(thickness 0.15)
				)
				(justify right top mirror)
			)
		)
		(pad "1" smd roundrect
			(at -0.48 0 90)
			(size 0.59 0.64)
			(layers "B.Cu" "B.Mask" "B.Paste")
			(roundrect_rratio 0.25)
			(net 1 "GND")
			(pintype "passive")
		)
		(pad "2" smd roundrect
			(at 0.48 0 90)
			(size 0.59 0.64)
			(layers "B.Cu" "B.Mask" "B.Paste")
			(roundrect_rratio 0.25)
			(net 12 "SYS_VIN_HV")
			(pintype "passive")
		)
	)
	(footprint "antmicro-footprints:R_0402_1005Metric"
		(layer "B.Cu")
		(at 143.8 71.7 -90)
		(descr "Resistor SMD 0402")
		(tags "resistor SMD 0402")
		(property "Reference" "R291"
			(at -1 -2.5 90)
			(layer "B.SilkS")
			(effects
				(font
					(size 0.7 0.7)
					(thickness 0.15)
				)
				(justify left bottom mirror)
			)
		)
		(property "Value" "R_0R_0402"
			(at -1.011843 -1.772047 90)
			(layer "B.Fab")
			(effects
				(font
					(size 0.7 0.7)
					(thickness 0.15)
				)
				(justify left bottom mirror)
			)
		)
		(property "Datasheet" "https://industrial.panasonic.com/cdbs/www-data/pdf/RDA0000/AOA0000C301.pdf"
			(at 0 0 90)
			(layer "B.Fab")
			(hide yes)
			(effects
				(font
					(size 1.27 1.27)
					(thickness 0.15)
				)
				(justify mirror)
			)
		)
		(property "Description" "SMD Chip Resistor, Jumper, 0 ohm, 100 mW, 0402 [1005 Metric], Thick Film, General Purpose"
			(at 0 0 90)
			(layer "B.Fab")
			(hide yes)
			(effects
				(font
					(size 1.27 1.27)
					(thickness 0.15)
				)
				(justify mirror)
			)
		)
		(property "MPN" "ERJ2GE0R00X"
			(at 0 0 90)
			(unlocked yes)
			(layer "B.Fab")
			(hide yes)
			(effects
				(font
					(size 1 1)
					(thickness 0.15)
				)
				(justify mirror)
			)
		)
		(property "Manufacturer" "Panasonic"
			(at 0 0 90)
			(unlocked yes)
			(layer "B.Fab")
			(hide yes)
			(effects
				(font
					(size 1 1)
					(thickness 0.15)
				)
				(justify mirror)
			)
		)
		(property "License" "Apache-2.0"
			(at 0 0 90)
			(unlocked yes)
			(layer "B.Fab")
			(hide yes)
			(effects
				(font
					(size 1 1)
					(thickness 0.15)
				)
				(justify mirror)
			)
		)
		(property "Author" "Antmicro"
			(at 0 0 90)
			(unlocked yes)
			(layer "B.Fab")
			(hide yes)
			(effects
				(font
					(size 1 1)
					(thickness 0.15)
				)
				(justify mirror)
			)
		)
		(property "Val" "0R"
			(at 0 0 90)
			(unlocked yes)
			(layer "B.Fab")
			(hide yes)
			(effects
				(font
					(size 1 1)
					(thickness 0.15)
				)
				(justify mirror)
			)
		)
		(property "Tolerance" "~"
			(at 0 0 90)
			(unlocked yes)
			(layer "B.Fab")
			(hide yes)
			(effects
				(font
					(size 1 1)
					(thickness 0.15)
				)
				(justify mirror)
			)
		)
		(property "Current" "1A"
			(at 0 0 90)
			(unlocked yes)
			(layer "B.Fab")
			(hide yes)
			(effects
				(font
					(size 1 1)
					(thickness 0.15)
				)
				(justify mirror)
			)
		)
		(sheetname "/SoM_IO2/")
		(sheetfile "som_io2.kicad_sch")
		(attr smd exclude_from_pos_files exclude_from_bom dnp)
		(fp_rect
			(start -0.925 0.47)
			(end 0.925 -0.47)
			(stroke
				(width 0.05)
				(type default)
			)
			(fill no)
			(layer "B.CrtYd")
		)
		(fp_rect
			(start -0.5 0.25)
			(end 0.5 -0.25)
			(stroke
				(width 0.15)
				(type solid)
			)
			(fill no)
			(layer "B.Fab")
		)
		(fp_text user "License: Apache-2.0"
			(at -0.95 -5.169 90)
			(layer "B.Fab")
			(effects
				(font
					(size 0.7 0.7)
					(thickness 0.15)
				)
				(justify left bottom mirror)
			)
		)
		(fp_text user "${REFERENCE}"
			(at -0.95 -3.168 90)
			(layer "B.Fab")
			(effects
				(font
					(size 0.7 0.7)
					(thickness 0.15)
				)
				(justify left bottom mirror)
			)
		)
		(fp_text user "Author: Antmicro"
			(at -0.95 -4.169 90)
			(layer "B.Fab")
			(effects
				(font
					(size 0.7 0.7)
					(thickness 0.15)
				)
				(justify left bottom mirror)
			)
		)
		(pad "1" smd roundrect
			(at -0.48 0 270)
			(size 0.59 0.64)
			(layers "B.Cu" "B.Mask" "B.Paste")
			(roundrect_rratio 0.25)
			(net 11 "+1V8")
			(pintype "passive")
		)
		(pad "2" smd roundrect
			(at 0.48 0 270)
			(size 0.59 0.64)
			(layers "B.Cu" "B.Mask" "B.Paste")
			(roundrect_rratio 0.25)
			(net 652 "/SoM_IO2/NVDBG_SEL")
			(pintype "passive")
		)
	)
	(footprint "antmicro-footprints:R_0402_1005Metric"
		(layer "B.Cu")
		(at 71.1 66.3)
		(descr "Resistor SMD 0402")
		(tags "resistor SMD 0402")
		(property "Reference" "R396"
			(at 0.9 -0.3 0)
			(layer "B.SilkS")
			(effects
				(font
					(size 0.7 0.7)
					(thickness 0.15)
				)
				(justify right top mirror)
			)
		)
		(property "Value" "R_0R_0402"
			(at -1.011843 -1.772047 0)
			(layer "B.Fab")
			(effects
				(font
					(size 0.7 0.7)
					(thickness 0.15)
				)
				(justify right top mirror)
			)
		)
		(property "Datasheet" "https://industrial.panasonic.com/cdbs/www-data/pdf/RDA0000/AOA0000C301.pdf"
			(at 0 0 0)
			(layer "B.Fab")
			(hide yes)
			(effects
				(font
					(size 1.27 1.27)
					(thickness 0.15)
				)
				(justify mirror)
			)
		)
		(property "Description" "SMD Chip Resistor, Jumper, 0 ohm, 100 mW, 0402 [1005 Metric], Thick Film, General Purpose"
			(at 0 0 0)
			(layer "B.Fab")
			(hide yes)
			(effects
				(font
					(size 1.27 1.27)
					(thickness 0.15)
				)
				(justify mirror)
			)
		)
		(property "MPN" "ERJ2GE0R00X"
			(at 0 0 180)
			(unlocked yes)
			(layer "B.Fab")
			(hide yes)
			(effects
				(font
					(size 1 1)
					(thickness 0.15)
				)
				(justify mirror)
			)
		)
		(property "Manufacturer" "Panasonic"
			(at 0 0 180)
			(unlocked yes)
			(layer "B.Fab")
			(hide yes)
			(effects
				(font
					(size 1 1)
					(thickness 0.15)
				)
				(justify mirror)
			)
		)
		(property "License" "Apache-2.0"
			(at 0 0 180)
			(unlocked yes)
			(layer "B.Fab")
			(hide yes)
			(effects
				(font
					(size 1 1)
					(thickness 0.15)
				)
				(justify mirror)
			)
		)
		(property "Author" "Antmicro"
			(at 0 0 180)
			(unlocked yes)
			(layer "B.Fab")
			(hide yes)
			(effects
				(font
					(size 1 1)
					(thickness 0.15)
				)
				(justify mirror)
			)
		)
		(property "Val" "0R"
			(at 0 0 180)
			(unlocked yes)
			(layer "B.Fab")
			(hide yes)
			(effects
				(font
					(size 1 1)
					(thickness 0.15)
				)
				(justify mirror)
			)
		)
		(property "Tolerance" "~"
			(at 0 0 180)
			(unlocked yes)
			(layer "B.Fab")
			(hide yes)
			(effects
				(font
					(size 1 1)
					(thickness 0.15)
				)
				(justify mirror)
			)
		)
		(property "Current" "1A"
			(at 0 0 180)
			(unlocked yes)
			(layer "B.Fab")
			(hide yes)
			(effects
				(font
					(size 1 1)
					(thickness 0.15)
				)
				(justify mirror)
			)
		)
		(sheetname "/CSI/")
		(sheetfile "csi.kicad_sch")
		(attr smd)
		(fp_rect
			(start -0.925 0.47)
			(end 0.925 -0.47)
			(stroke
				(width 0.05)
				(type default)
			)
			(fill no)
			(layer "B.CrtYd")
		)
		(fp_rect
			(start -0.5 0.25)
			(end 0.5 -0.25)
			(stroke
				(width 0.15)
				(type solid)
			)
			(fill no)
			(layer "B.Fab")
		)
		(fp_text user "Author: Antmicro"
			(at -0.95 -4.169 0)
			(layer "B.Fab")
			(effects
				(font
					(size 0.7 0.7)
					(thickness 0.15)
				)
				(justify right top mirror)
			)
		)
		(fp_text user "${REFERENCE}"
			(at -0.95 -3.168 0)
			(layer "B.Fab")
			(effects
				(font
					(size 0.7 0.7)
					(thickness 0.15)
				)
				(justify right top mirror)
			)
		)
		(fp_text user "License: Apache-2.0"
			(at -0.95 -5.169 0)
			(layer "B.Fab")
			(effects
				(font
					(size 0.7 0.7)
					(thickness 0.15)
				)
				(justify right top mirror)
			)
		)
		(pad "1" smd roundrect
			(at -0.48 0)
			(size 0.59 0.64)
			(layers "B.Cu" "B.Mask" "B.Paste")
			(roundrect_rratio 0.25)
			(net 994 "/CSI/SCL_CAM2")
			(pintype "passive")
		)
		(pad "2" smd roundrect
			(at 0.48 0)
			(size 0.59 0.64)
			(layers "B.Cu" "B.Mask" "B.Paste")
			(roundrect_rratio 0.25)
			(net 1372 "Net-(J10-Pad40)")
			(pintype "passive")
		)
	)
	(footprint "antmicro-footprints:C_0603_1608Metric_EIA"
		(layer "B.Cu")
		(at 115.55 69.46 180)
		(descr "Capacitor SMD 0603, IPC-7351 Density Level A")
		(tags "Capacitor 0603")
		(property "Reference" "C23"
			(at -1.05 0.86 0)
			(layer "B.SilkS")
			(effects
				(font
					(size 0.7 0.7)
					(thickness 0.15)
				)
				(justify left bottom mirror)
			)
		)
		(property "Value" "C_22u_16V_0603"
			(at -1.42757 -1.770288 0)
			(layer "B.Fab")
			(effects
				(font
					(size 0.7 0.7)
					(thickness 0.15)
				)
				(justify left bottom mirror)
			)
		)
		(property "Datasheet" "https://product.samsungsem.com/mlcc/CL10A226MO7JZN.do"
			(at 0 0 0)
			(layer "B.Fab")
			(hide yes)
			(effects
				(font
					(size 1.27 1.27)
					(thickness 0.15)
				)
				(justify mirror)
			)
		)
		(property "Description" "SMD Multilayer Ceramic Capacitor"
			(at 0 0 0)
			(layer "B.Fab")
			(hide yes)
			(effects
				(font
					(size 1.27 1.27)
					(thickness 0.15)
				)
				(justify mirror)
			)
		)
		(property "MPN" "CL10A226MO7JZNC"
			(at 0 0 180)
			(unlocked yes)
			(layer "B.Fab")
			(hide yes)
			(effects
				(font
					(size 1 1)
					(thickness 0.15)
				)
				(justify mirror)
			)
		)
		(property "Manufacturer" "Samsung Electro-Mechanics"
			(at 0 0 180)
			(unlocked yes)
			(layer "B.Fab")
			(hide yes)
			(effects
				(font
					(size 1 1)
					(thickness 0.15)
				)
				(justify mirror)
			)
		)
		(property "License" "Apache-2.0"
			(at 0 0 180)
			(unlocked yes)
			(layer "B.Fab")
			(hide yes)
			(effects
				(font
					(size 1 1)
					(thickness 0.15)
				)
				(justify mirror)
			)
		)
		(property "Author" "Antmicro"
			(at 0 0 180)
			(unlocked yes)
			(layer "B.Fab")
			(hide yes)
			(effects
				(font
					(size 1 1)
					(thickness 0.15)
				)
				(justify mirror)
			)
		)
		(property "Val" "22u"
			(at 0 0 180)
			(unlocked yes)
			(layer "B.Fab")
			(hide yes)
			(effects
				(font
					(size 1 1)
					(thickness 0.15)
				)
				(justify mirror)
			)
		)
		(property "Voltage" "16V"
			(at 0 0 180)
			(unlocked yes)
			(layer "B.Fab")
			(hide yes)
			(effects
				(font
					(size 1 1)
					(thickness 0.15)
				)
				(justify mirror)
			)
		)
		(property "Dielectric" "X7R"
			(at 0 0 180)
			(unlocked yes)
			(layer "B.Fab")
			(hide yes)
			(effects
				(font
					(size 1 1)
					(thickness 0.15)
				)
				(justify mirror)
			)
		)
		(property "Public" "False"
			(at 0 0 180)
			(unlocked yes)
			(layer "B.Fab")
			(hide yes)
			(effects
				(font
					(size 1 1)
					(thickness 0.15)
				)
				(justify mirror)
			)
		)
		(sheetname "/SoM_Power/")
		(sheetfile "som_power.kicad_sch")
		(attr smd)
		(fp_line
			(start -0.15 0.55)
			(end 0.15 0.55)
			(stroke
				(width 0.15)
				(type solid)
			)
			(layer "B.SilkS")
		)
		(fp_line
			(start -0.15 -0.55)
			(end 0.15 -0.55)
			(stroke
				(width 0.15)
				(type solid)
			)
			(layer "B.SilkS")
		)
		(fp_rect
			(start -1.25 0.65)
			(end 1.25 -0.65)
			(stroke
				(width 0.05)
				(type solid)
			)
			(fill no)
			(layer "B.CrtYd")
		)
		(fp_rect
			(start -0.8 0.45)
			(end 0.8 -0.45)
			(stroke
				(width 0.15)
				(type solid)
			)
			(fill no)
			(layer "B.Fab")
		)
		(fp_text user "License: Apache-2.0"
			(at -1.682 -5.895 0)
			(layer "B.Fab")
			(effects
				(font
					(size 0.7 0.7)
					(thickness 0.15)
				)
				(justify left bottom mirror)
			)
		)
		(fp_text user "Author: Antmicro"
			(at -1.682 -4.894 0)
			(layer "B.Fab")
			(effects
				(font
					(size 0.7 0.7)
					(thickness 0.15)
				)
				(justify left bottom mirror)
			)
		)
		(fp_text user "${REFERENCE}"
			(at -1.682 -3.895 0)
			(layer "B.Fab")
			(effects
				(font
					(size 0.7 0.7)
					(thickness 0.15)
				)
				(justify left bottom mirror)
			)
		)
		(pad "1" smd roundrect
			(at -0.7 0 180)
			(size 0.8 1.1)
			(layers "B.Cu" "B.Mask" "B.Paste")
			(roundrect_rratio 0.2)
			(net 1 "GND")
			(pintype "passive")
		)
		(pad "2" smd roundrect
			(at 0.7 0 180)
			(size 0.8 1.1)
			(layers "B.Cu" "B.Mask" "B.Paste")
			(roundrect_rratio 0.2)
			(net 213 "+5V_SOM")
			(pintype "passive")
		)
	)
	(footprint "antmicro-footprints:R_0402_1005Metric"
		(layer "B.Cu")
		(at 220.426 152.2)
		(descr "Resistor SMD 0402")
		(tags "resistor SMD 0402")
		(property "Reference" "R200"
			(at -1.8 -1.5 0)
			(layer "B.SilkS")
			(effects
				(font
					(size 0.7 0.7)
					(thickness 0.15)
				)
				(justify right top mirror)
			)
		)
		(property "Value" "R_330R_0402"
			(at -1.011843 -1.772046 0)
			(layer "B.Fab")
			(effects
				(font
					(size 0.7 0.7)
					(thickness 0.15)
				)
				(justify right top mirror)
			)
		)
		(property "Datasheet" "https://www.bourns.com/docs/product-datasheets/cr.pdf"
			(at 0 0 0)
			(layer "B.Fab")
			(hide yes)
			(effects
				(font
					(size 1.27 1.27)
					(thickness 0.15)
				)
				(justify mirror)
			)
		)
		(property "Description" "SMD Chip Resistor, 330 ohm, ± 1%, 62.5 mW, 0402 [1005 Metric], Thick Film, General Purpose"
			(at 0 0 0)
			(layer "B.Fab")
			(hide yes)
			(effects
				(font
					(size 1.27 1.27)
					(thickness 0.15)
				)
				(justify mirror)
			)
		)
		(property "MPN" "CR0402-FX-3300GLF"
			(at 0 0 180)
			(unlocked yes)
			(layer "B.Fab")
			(hide yes)
			(effects
				(font
					(size 1 1)
					(thickness 0.15)
				)
				(justify mirror)
			)
		)
		(property "Manufacturer" "Bourns"
			(at 0 0 180)
			(unlocked yes)
			(layer "B.Fab")
			(hide yes)
			(effects
				(font
					(size 1 1)
					(thickness 0.15)
				)
				(justify mirror)
			)
		)
		(property "License" "Apache-2.0"
			(at 0 0 180)
			(unlocked yes)
			(layer "B.Fab")
			(hide yes)
			(effects
				(font
					(size 1 1)
					(thickness 0.15)
				)
				(justify mirror)
			)
		)
		(property "Author" "Antmicro"
			(at 0 0 180)
			(unlocked yes)
			(layer "B.Fab")
			(hide yes)
			(effects
				(font
					(size 1 1)
					(thickness 0.15)
				)
				(justify mirror)
			)
		)
		(property "Val" "330R"
			(at 0 0 180)
			(unlocked yes)
			(layer "B.Fab")
			(hide yes)
			(effects
				(font
					(size 1 1)
					(thickness 0.15)
				)
				(justify mirror)
			)
		)
		(property "Tolerance" "1%"
			(at 0 0 180)
			(unlocked yes)
			(layer "B.Fab")
			(hide yes)
			(effects
				(font
					(size 1 1)
					(thickness 0.15)
				)
				(justify mirror)
			)
		)
		(sheetname "/SFP/")
		(sheetfile "sfp.kicad_sch")
		(attr smd)
		(fp_poly
			(pts
				(xy -0.925 0.47) (xy 0.925 0.47) (xy 0.925 -0.47) (xy -0.925 -0.47)
			)
			(stroke
				(width 0.05)
				(type default)
			)
			(fill no)
			(layer "B.CrtYd")
		)
		(fp_poly
			(pts
				(xy -0.5 0.25) (xy 0.5 0.25) (xy 0.5 -0.25) (xy -0.5 -0.25)
			)
			(stroke
				(width 0.15)
				(type solid)
			)
			(fill no)
			(layer "B.Fab")
		)
		(fp_text user "Author: Antmicro"
			(at -0.95 -4.169 0)
			(layer "B.Fab")
			(effects
				(font
					(size 0.7 0.7)
					(thickness 0.15)
				)
				(justify right top mirror)
			)
		)
		(fp_text user "${REFERENCE}"
			(at -0.95 -3.168 0)
			(layer "B.Fab")
			(effects
				(font
					(size 0.7 0.7)
					(thickness 0.15)
				)
				(justify right top mirror)
			)
		)
		(fp_text user "License: Apache-2.0"
			(at -0.949999 -5.169 0)
			(layer "B.Fab")
			(effects
				(font
					(size 0.7 0.7)
					(thickness 0.15)
				)
				(justify right top mirror)
			)
		)
		(pad "1" smd roundrect
			(at -0.48 0)
			(size 0.59 0.64)
			(layers "B.Cu" "B.Mask" "B.Paste")
			(roundrect_rratio 0.25)
			(net 1 "GND")
			(pintype "passive")
		)
		(pad "2" smd roundrect
			(at 0.48 0)
			(size 0.59 0.64)
			(layers "B.Cu" "B.Mask" "B.Paste")
			(roundrect_rratio 0.25)
			(net 379 "/SFP/SH")
			(pintype "passive")
		)
	)
	(footprint "antmicro-footprints:C_0402_1005Metric"
		(layer "B.Cu")
		(at 235.8 96.6)
		(descr "Capacitor SMD 0402")
		(tags "capacitor SMD 0402")
		(property "Reference" "C137"
			(at 1.1 0.4 0)
			(layer "B.SilkS")
			(effects
				(font
					(size 0.7 0.7)
					(thickness 0.15)
				)
				(justify right top mirror)
			)
		)
		(property "Value" "C_100n_0402"
			(at -1.022927 -2.155213 0)
			(layer "B.Fab")
			(effects
				(font
					(size 0.7 0.7)
					(thickness 0.15)
				)
				(justify right top mirror)
			)
		)
		(property "Datasheet" "https://www.murata.com/products/productdetail?partno=GRM155R61H104KE14%23"
			(at 0 0 0)
			(layer "B.Fab")
			(hide yes)
			(effects
				(font
					(size 1.27 1.27)
					(thickness 0.15)
				)
				(justify mirror)
			)
		)
		(property "Description" "SMD Multilayer Ceramic Capacitor, 0.1 µF, 50 V, 0402 [1005 Metric], ± 10%, X5R, GRM Series"
			(at 0 0 0)
			(layer "B.Fab")
			(hide yes)
			(effects
				(font
					(size 1.27 1.27)
					(thickness 0.15)
				)
				(justify mirror)
			)
		)
		(property "Manufacturer" "Murata"
			(at 0 0 180)
			(unlocked yes)
			(layer "B.Fab")
			(hide yes)
			(effects
				(font
					(size 1 1)
					(thickness 0.15)
				)
				(justify mirror)
			)
		)
		(property "MPN" "GRM155R61H104KE14D"
			(at 0 0 180)
			(unlocked yes)
			(layer "B.Fab")
			(hide yes)
			(effects
				(font
					(size 1 1)
					(thickness 0.15)
				)
				(justify mirror)
			)
		)
		(property "Val" "100n"
			(at 0 0 180)
			(unlocked yes)
			(layer "B.Fab")
			(hide yes)
			(effects
				(font
					(size 1 1)
					(thickness 0.15)
				)
				(justify mirror)
			)
		)
		(property "License" "Apache-2.0"
			(at 0 0 180)
			(unlocked yes)
			(layer "B.Fab")
			(hide yes)
			(effects
				(font
					(size 1 1)
					(thickness 0.15)
				)
				(justify mirror)
			)
		)
		(property "Author" "Antmicro"
			(at 0 0 180)
			(unlocked yes)
			(layer "B.Fab")
			(hide yes)
			(effects
				(font
					(size 1 1)
					(thickness 0.15)
				)
				(justify mirror)
			)
		)
		(property "Voltage" "50V"
			(at 0 0 180)
			(unlocked yes)
			(layer "B.Fab")
			(hide yes)
			(effects
				(font
					(size 1 1)
					(thickness 0.15)
				)
				(justify mirror)
			)
		)
		(property "Dielectric" "X5R"
			(at 0 0 180)
			(unlocked yes)
			(layer "B.Fab")
			(hide yes)
			(effects
				(font
					(size 1 1)
					(thickness 0.15)
				)
				(justify mirror)
			)
		)
		(sheetname "/USB DP Alt mode/")
		(sheetfile "usb_dp.kicad_sch")
		(attr smd)
		(fp_poly
			(pts
				(xy -0.925 0.47) (xy -0.925 -0.47) (xy 0.925 -0.47) (xy 0.925 0.47)
			)
			(stroke
				(width 0.05)
				(type default)
			)
			(fill no)
			(layer "B.CrtYd")
		)
		(fp_line
			(start -0.494 -0.248)
			(end -0.494 0.25)
			(stroke
				(width 0.15)
				(type solid)
			)
			(layer "B.Fab")
		)
		(fp_line
			(start -0.494 0.25)
			(end 0.504 0.25)
			(stroke
				(width 0.15)
				(type solid)
			)
			(layer "B.Fab")
		)
		(fp_line
			(start 0.504 -0.248)
			(end -0.494 -0.248)
			(stroke
				(width 0.15)
				(type solid)
			)
			(layer "B.Fab")
		)
		(fp_line
			(start 0.504 0.25)
			(end 0.504 -0.248)
			(stroke
				(width 0.15)
				(type solid)
			)
			(layer "B.Fab")
		)
		(fp_text user "${REFERENCE}"
			(at -0.939 -4.599 0)
			(layer "B.Fab")
			(effects
				(font
					(size 0.7 0.7)
					(thickness 0.15)
				)
				(justify right top mirror)
			)
		)
		(fp_text user "License: Apache-2.0"
			(at -0.939 -5.799 0)
			(layer "B.Fab")
			(effects
				(font
					(size 0.7 0.7)
					(thickness 0.15)
				)
				(justify right top mirror)
			)
		)
		(fp_text user "Author: Antmicro"
			(at -0.939 -3.399 0)
			(layer "B.Fab")
			(effects
				(font
					(size 0.7 0.7)
					(thickness 0.15)
				)
				(justify right top mirror)
			)
		)
		(pad "1" smd roundrect
			(at -0.48 0)
			(size 0.59 0.64)
			(layers "B.Cu" "B.Mask" "B.Paste")
			(roundrect_rratio 0.25)
			(net 5 "+5V")
			(pintype "passive")
		)
		(pad "2" smd roundrect
			(at 0.48 0)
			(size 0.59 0.64)
			(layers "B.Cu" "B.Mask" "B.Paste")
			(roundrect_rratio 0.25)
			(net 1 "GND")
			(pintype "passive")
		)
	)
	(footprint "antmicro-footprints:SOT-523"
		(layer "B.Cu")
		(at 161.16 59.78 -90)
		(property "Reference" "Q4"
			(at 0.12 1.26 90)
			(layer "B.SilkS")
			(effects
				(font
					(size 0.7 0.7)
					(thickness 0.15)
				)
				(justify left bottom mirror)
			)
		)
		(property "Value" "DMG1012T-7"
			(at 0.1 -1.824 90)
			(layer "B.Fab")
			(effects
				(font
					(size 0.7 0.7)
					(thickness 0.15)
				)
				(justify left bottom mirror)
			)
		)
		(property "Datasheet" "https://www.diodes.com/assets/Datasheets/ds31783.pdf"
			(at 0 0 90)
			(layer "B.Fab")
			(hide yes)
			(effects
				(font
					(size 1.27 1.27)
					(thickness 0.15)
				)
				(justify mirror)
			)
		)
		(property "Description" "Power MOSFET, N Channel, 20 V, 630 mA, 0.3 ohm, SOT-523, Surface Mount"
			(at 0 0 90)
			(layer "B.Fab")
			(hide yes)
			(effects
				(font
					(size 1.27 1.27)
					(thickness 0.15)
				)
				(justify mirror)
			)
		)
		(property "MPN" "DMG1012T-7"
			(at 0 0 90)
			(unlocked yes)
			(layer "B.Fab")
			(hide yes)
			(effects
				(font
					(size 1 1)
					(thickness 0.15)
				)
				(justify mirror)
			)
		)
		(property "Manufacturer" "Diodes Incorporated"
			(at 0 0 90)
			(unlocked yes)
			(layer "B.Fab")
			(hide yes)
			(effects
				(font
					(size 1 1)
					(thickness 0.15)
				)
				(justify mirror)
			)
		)
		(property "Author" "Antmicro"
			(at 0 0 90)
			(unlocked yes)
			(layer "B.Fab")
			(hide yes)
			(effects
				(font
					(size 1 1)
					(thickness 0.15)
				)
				(justify mirror)
			)
		)
		(property "License" "Apache-2.0"
			(at 0 0 90)
			(unlocked yes)
			(layer "B.Fab")
			(hide yes)
			(effects
				(font
					(size 1 1)
					(thickness 0.15)
				)
				(justify mirror)
			)
		)
		(sheetname "/Power/")
		(sheetfile "power.kicad_sch")
		(attr smd)
		(fp_line
			(start -0.725 0.551)
			(end -0.277 0.551)
			(stroke
				(width 0.15)
				(type solid)
			)
			(layer "B.SilkS")
		)
		(fp_line
			(start -0.277 0.551)
			(end -0.277 0.75)
			(stroke
				(width 0.15)
				(type solid)
			)
			(layer "B.SilkS")
		)
		(fp_line
			(start -0.927 0.351)
			(end -0.725 0.551)
			(stroke
				(width 0.15)
				(type solid)
			)
			(layer "B.SilkS")
		)
		(fp_line
			(start -0.927 0.051)
			(end -0.927 0.351)
			(stroke
				(width 0.15)
				(type solid)
			)
			(layer "B.SilkS")
		)
		(fp_circle
			(center -0.9652 -0.9652)
			(end -0.9152 -0.9652)
			(stroke
				(width 0.15)
				(type solid)
			)
			(fill yes)
			(layer "B.SilkS")
		)
		(fp_line
			(start -1.12 1.16)
			(end 1.1 1.16)
			(stroke
				(width 0.05)
				(type solid)
			)
			(layer "B.CrtYd")
		)
		(fp_line
			(start -1.12 1.16)
			(end -1.12 -1.15)
			(stroke
				(width 0.05)
				(type solid)
			)
			(layer "B.CrtYd")
		)
		(fp_line
			(start 1.1 1.16)
			(end 1.1 -1.15)
			(stroke
				(width 0.05)
				(type solid)
			)
			(layer "B.CrtYd")
		)
		(fp_line
			(start -1.12 -1.15)
			(end 1.1 -1.15)
			(stroke
				(width 0.05)
				(type solid)
			)
			(layer "B.CrtYd")
		)
		(fp_line
			(start -0.652 0.425)
			(end -0.802 0.276)
			(stroke
				(width 0.15)
				(type solid)
			)
			(layer "B.Fab")
		)
		(fp_line
			(start 0.8 0.425)
			(end -0.652 0.425)
			(stroke
				(width 0.15)
				(type solid)
			)
			(layer "B.Fab")
		)
		(fp_line
			(start 0.8 0.425)
			(end 0.8 -0.424)
			(stroke
				(width 0.15)
				(type solid)
			)
			(layer "B.Fab")
		)
		(fp_line
			(start -0.802 0.276)
			(end -0.802 -0.424)
			(stroke
				(width 0.15)
				(type solid)
			)
			(layer "B.Fab")
		)
		(fp_line
			(start 0.8 -0.424)
			(end -0.802 -0.424)
			(stroke
				(width 0.15)
				(type solid)
			)
			(layer "B.Fab")
		)
		(fp_circle
			(center -0.9652 -0.9652)
			(end -0.9144 -0.9652)
			(stroke
				(width 0.15)
				(type solid)
			)
			(fill no)
			(layer "B.Fab")
		)
		(fp_text user "License: Apache-2.0"
			(at -1.12 -5.024 90)
			(layer "B.Fab")
			(effects
				(font
					(size 0.7 0.7)
					(thickness 0.15)
				)
				(justify left bottom mirror)
			)
		)
		(fp_text user "${REFERENCE}"
			(at -1.12 -3.824 90)
			(layer "B.Fab")
			(effects
				(font
					(size 0.7 0.7)
					(thickness 0.15)
				)
				(justify left bottom mirror)
			)
		)
		(fp_text user "Author: Antmicro"
			(at -1.12 -6.224 90)
			(layer "B.Fab")
			(effects
				(font
					(size 0.7 0.7)
					(thickness 0.15)
				)
				(justify left bottom mirror)
			)
		)
		(pad "1" smd rect
			(at -0.5 -0.65 270)
			(size 0.4 0.51)
			(layers "B.Cu" "B.Mask" "B.Paste")
			(net 282 "+1V15")
			(pinfunction "G")
			(pintype "input")
		)
		(pad "2" smd rect
			(at 0.498 -0.65 270)
			(size 0.4 0.51)
			(layers "B.Cu" "B.Mask" "B.Paste")
			(net 1 "GND")
			(pinfunction "S")
			(pintype "passive")
		)
		(pad "3" smd rect
			(at 0 0.652 270)
			(size 0.4 0.51)
			(layers "B.Cu" "B.Mask" "B.Paste")
			(net 891 "Net-(D40-C)")
			(pinfunction "D")
			(pintype "passive")
		)
	)
	(footprint "antmicro-footprints:TP_SMD_0.75mm"
		(layer "B.Cu")
		(at 185.54 85.47)
		(property "Reference" "TP123"
			(at 0.48 -0.4 0)
			(layer "B.SilkS")
			(effects
				(font
					(size 0.7 0.7)
					(thickness 0.15)
				)
				(justify right top mirror)
			)
		)
		(property "Value" "TP_0.75mm_SMD"
			(at 0 -1.2 0)
			(layer "B.Fab")
			(effects
				(font
					(size 0.7 0.7)
					(thickness 0.15)
				)
				(justify right top mirror)
			)
		)
		(property "Description" "SMT test point"
			(at 0 0 0)
			(layer "B.Fab")
			(hide yes)
			(effects
				(font
					(size 1.27 1.27)
					(thickness 0.15)
				)
				(justify mirror)
			)
		)
		(property "MPN" ""
			(at 0 0 180)
			(unlocked yes)
			(layer "B.Fab")
			(hide yes)
			(effects
				(font
					(size 1 1)
					(thickness 0.15)
				)
				(justify mirror)
			)
		)
		(property "Manufacturer" ""
			(at 0 0 180)
			(unlocked yes)
			(layer "B.Fab")
			(hide yes)
			(effects
				(font
					(size 1 1)
					(thickness 0.15)
				)
				(justify mirror)
			)
		)
		(property "Author" "Antmicro"
			(at 0 0 180)
			(unlocked yes)
			(layer "B.Fab")
			(hide yes)
			(effects
				(font
					(size 1 1)
					(thickness 0.15)
				)
				(justify mirror)
			)
		)
		(property "License" "Apache-2.0"
			(at 0 0 180)
			(unlocked yes)
			(layer "B.Fab")
			(hide yes)
			(effects
				(font
					(size 1 1)
					(thickness 0.15)
				)
				(justify mirror)
			)
		)
		(sheetname "/Power/")
		(sheetfile "power.kicad_sch")
		(attr exclude_from_pos_files exclude_from_bom)
		(fp_circle
			(center 0 0)
			(end 0.475 0)
			(stroke
				(width 0.05)
				(type default)
			)
			(fill no)
			(layer "B.CrtYd")
		)
		(fp_text user "License: Apache-2.0"
			(at -0.4 -5.101 0)
			(layer "B.Fab")
			(effects
				(font
					(size 0.7 0.7)
					(thickness 0.15)
				)
				(justify right top mirror)
			)
		)
		(fp_text user "Author: Antmicro"
			(at -0.4 -3.901 0)
			(layer "B.Fab")
			(effects
				(font
					(size 0.7 0.7)
					(thickness 0.15)
				)
				(justify right top mirror)
			)
		)
		(fp_text user "${REFERENCE}"
			(at -0.4 -2.7 0)
			(layer "B.Fab")
			(effects
				(font
					(size 0.7 0.7)
					(thickness 0.15)
				)
				(justify right top mirror)
			)
		)
		(pad "1" smd circle
			(at 0 0)
			(size 0.75 0.75)
			(layers "B.Cu" "B.Mask")
			(net 522 "/Power/USBPD1_HV")
			(pinfunction "1")
			(pintype "passive")
		)
	)
	(footprint "antmicro-footprints:TP_SMD_0.75mm"
		(layer "B.Cu")
		(at 124.5 103)
		(property "Reference" "TP37"
			(at 0.64 -0.52 0)
			(layer "B.SilkS")
			(effects
				(font
					(size 0.7 0.7)
					(thickness 0.15)
				)
				(justify right top mirror)
			)
		)
		(property "Value" "TP_0.75mm_SMD"
			(at 0 -1.2 0)
			(layer "B.Fab")
			(effects
				(font
					(size 0.7 0.7)
					(thickness 0.15)
				)
				(justify right top mirror)
			)
		)
		(property "Description" "SMT test point"
			(at 0 0 0)
			(layer "B.Fab")
			(hide yes)
			(effects
				(font
					(size 1.27 1.27)
					(thickness 0.15)
				)
				(justify mirror)
			)
		)
		(property "MPN" ""
			(at 0 0 180)
			(unlocked yes)
			(layer "B.Fab")
			(hide yes)
			(effects
				(font
					(size 1 1)
					(thickness 0.15)
				)
				(justify mirror)
			)
		)
		(property "Manufacturer" ""
			(at 0 0 180)
			(unlocked yes)
			(layer "B.Fab")
			(hide yes)
			(effects
				(font
					(size 1 1)
					(thickness 0.15)
				)
				(justify mirror)
			)
		)
		(property "Author" "Antmicro"
			(at 0 0 180)
			(unlocked yes)
			(layer "B.Fab")
			(hide yes)
			(effects
				(font
					(size 1 1)
					(thickness 0.15)
				)
				(justify mirror)
			)
		)
		(property "License" "Apache-2.0"
			(at 0 0 180)
			(unlocked yes)
			(layer "B.Fab")
			(hide yes)
			(effects
				(font
					(size 1 1)
					(thickness 0.15)
				)
				(justify mirror)
			)
		)
		(sheetname "/M.2/")
		(sheetfile "m2.kicad_sch")
		(attr exclude_from_pos_files exclude_from_bom)
		(fp_circle
			(center 0 0)
			(end 0.475 0)
			(stroke
				(width 0.05)
				(type default)
			)
			(fill no)
			(layer "B.CrtYd")
		)
		(fp_text user "License: Apache-2.0"
			(at -0.4 -5.101 0)
			(layer "B.Fab")
			(effects
				(font
					(size 0.7 0.7)
					(thickness 0.15)
				)
				(justify right top mirror)
			)
		)
		(fp_text user "Author: Antmicro"
			(at -0.4 -3.901 0)
			(layer "B.Fab")
			(effects
				(font
					(size 0.7 0.7)
					(thickness 0.15)
				)
				(justify right top mirror)
			)
		)
		(fp_text user "${REFERENCE}"
			(at -0.4 -2.7 0)
			(layer "B.Fab")
			(effects
				(font
					(size 0.7 0.7)
					(thickness 0.15)
				)
				(justify right top mirror)
			)
		)
		(pad "1" smd circle
			(at 0 0)
			(size 0.75 0.75)
			(layers "B.Cu" "B.Mask")
			(net 217 "/M.2/M2_M_SMB_DATA")
			(pinfunction "1")
			(pintype "passive")
		)
	)
	(footprint "antmicro-footprints:C_0402_1005Metric"
		(layer "B.Cu")
		(at 224.05 79.9)
		(descr "Capacitor SMD 0402")
		(tags "capacitor SMD 0402")
		(property "Reference" "C134"
			(at -1.75 0.6 0)
			(layer "B.SilkS")
			(effects
				(font
					(size 0.7 0.7)
					(thickness 0.15)
				)
				(justify right top mirror)
			)
		)
		(property "Value" "C_100n_0402"
			(at -1.022927 -2.155213 0)
			(layer "B.Fab")
			(effects
				(font
					(size 0.7 0.7)
					(thickness 0.15)
				)
				(justify right top mirror)
			)
		)
		(property "Datasheet" "https://www.murata.com/products/productdetail?partno=GRM155R61H104KE14%23"
			(at 0 0 0)
			(layer "B.Fab")
			(hide yes)
			(effects
				(font
					(size 1.27 1.27)
					(thickness 0.15)
				)
				(justify mirror)
			)
		)
		(property "Description" "SMD Multilayer Ceramic Capacitor, 0.1 µF, 50 V, 0402 [1005 Metric], ± 10%, X5R, GRM Series"
			(at 0 0 0)
			(layer "B.Fab")
			(hide yes)
			(effects
				(font
					(size 1.27 1.27)
					(thickness 0.15)
				)
				(justify mirror)
			)
		)
		(property "Manufacturer" "Murata"
			(at 0 0 180)
			(unlocked yes)
			(layer "B.Fab")
			(hide yes)
			(effects
				(font
					(size 1 1)
					(thickness 0.15)
				)
				(justify mirror)
			)
		)
		(property "MPN" "GRM155R61H104KE14D"
			(at 0 0 180)
			(unlocked yes)
			(layer "B.Fab")
			(hide yes)
			(effects
				(font
					(size 1 1)
					(thickness 0.15)
				)
				(justify mirror)
			)
		)
		(property "Val" "100n"
			(at 0 0 180)
			(unlocked yes)
			(layer "B.Fab")
			(hide yes)
			(effects
				(font
					(size 1 1)
					(thickness 0.15)
				)
				(justify mirror)
			)
		)
		(property "License" "Apache-2.0"
			(at 0 0 180)
			(unlocked yes)
			(layer "B.Fab")
			(hide yes)
			(effects
				(font
					(size 1 1)
					(thickness 0.15)
				)
				(justify mirror)
			)
		)
		(property "Author" "Antmicro"
			(at 0 0 180)
			(unlocked yes)
			(layer "B.Fab")
			(hide yes)
			(effects
				(font
					(size 1 1)
					(thickness 0.15)
				)
				(justify mirror)
			)
		)
		(property "Voltage" "50V"
			(at 0 0 180)
			(unlocked yes)
			(layer "B.Fab")
			(hide yes)
			(effects
				(font
					(size 1 1)
					(thickness 0.15)
				)
				(justify mirror)
			)
		)
		(property "Dielectric" "X5R"
			(at 0 0 180)
			(unlocked yes)
			(layer "B.Fab")
			(hide yes)
			(effects
				(font
					(size 1 1)
					(thickness 0.15)
				)
				(justify mirror)
			)
		)
		(sheetname "/USB Debug, PD/")
		(sheetfile "usb_debug_pd.kicad_sch")
		(attr smd)
		(fp_poly
			(pts
				(xy -0.925 0.47) (xy -0.925 -0.47) (xy 0.925 -0.47) (xy 0.925 0.47)
			)
			(stroke
				(width 0.05)
				(type default)
			)
			(fill no)
			(layer "B.CrtYd")
		)
		(fp_line
			(start -0.494 -0.248)
			(end -0.494 0.25)
			(stroke
				(width 0.15)
				(type solid)
			)
			(layer "B.Fab")
		)
		(fp_line
			(start -0.494 0.25)
			(end 0.504 0.25)
			(stroke
				(width 0.15)
				(type solid)
			)
			(layer "B.Fab")
		)
		(fp_line
			(start 0.504 -0.248)
			(end -0.494 -0.248)
			(stroke
				(width 0.15)
				(type solid)
			)
			(layer "B.Fab")
		)
		(fp_line
			(start 0.504 0.25)
			(end 0.504 -0.248)
			(stroke
				(width 0.15)
				(type solid)
			)
			(layer "B.Fab")
		)
		(fp_text user "${REFERENCE}"
			(at -0.939 -4.599 0)
			(layer "B.Fab")
			(effects
				(font
					(size 0.7 0.7)
					(thickness 0.15)
				)
				(justify right top mirror)
			)
		)
		(fp_text user "License: Apache-2.0"
			(at -0.939 -5.799 0)
			(layer "B.Fab")
			(effects
				(font
					(size 0.7 0.7)
					(thickness 0.15)
				)
				(justify right top mirror)
			)
		)
		(fp_text user "Author: Antmicro"
			(at -0.939 -3.399 0)
			(layer "B.Fab")
			(effects
				(font
					(size 0.7 0.7)
					(thickness 0.15)
				)
				(justify right top mirror)
			)
		)
		(pad "1" smd roundrect
			(at -0.48 0)
			(size 0.59 0.64)
			(layers "B.Cu" "B.Mask" "B.Paste")
			(roundrect_rratio 0.25)
			(net 334 "/USB Debug, PD/FTDI_3V3")
			(pintype "passive")
		)
		(pad "2" smd roundrect
			(at 0.48 0)
			(size 0.59 0.64)
			(layers "B.Cu" "B.Mask" "B.Paste")
			(roundrect_rratio 0.25)
			(net 1 "GND")
			(pintype "passive")
		)
	)
	(footprint "antmicro-footprints:C_0402_1005Metric"
		(layer "B.Cu")
		(at 111.81 70.62 180)
		(descr "Capacitor SMD 0402")
		(tags "capacitor SMD 0402")
		(property "Reference" "C18"
			(at -1.39 -1.48 0)
			(layer "B.SilkS")
			(effects
				(font
					(size 0.7 0.7)
					(thickness 0.15)
				)
				(justify left bottom mirror)
			)
		)
		(property "Value" "C_100n_0402"
			(at -1.022927 -2.155213 0)
			(layer "B.Fab")
			(effects
				(font
					(size 0.7 0.7)
					(thickness 0.15)
				)
				(justify left bottom mirror)
			)
		)
		(property "Datasheet" "https://www.murata.com/products/productdetail?partno=GRM155R61H104KE14%23"
			(at 0 0 0)
			(layer "B.Fab")
			(hide yes)
			(effects
				(font
					(size 1.27 1.27)
					(thickness 0.15)
				)
				(justify mirror)
			)
		)
		(property "Description" "SMD Multilayer Ceramic Capacitor, 0.1 µF, 50 V, 0402 [1005 Metric], ± 10%, X5R, GRM Series"
			(at 0 0 0)
			(layer "B.Fab")
			(hide yes)
			(effects
				(font
					(size 1.27 1.27)
					(thickness 0.15)
				)
				(justify mirror)
			)
		)
		(property "MPN" "GRM155R61H104KE14D"
			(at 0 0 0)
			(unlocked yes)
			(layer "B.Fab")
			(hide yes)
			(effects
				(font
					(size 1 1)
					(thickness 0.15)
				)
				(justify mirror)
			)
		)
		(property "Val" "100n"
			(at 0 0 0)
			(unlocked yes)
			(layer "B.Fab")
			(hide yes)
			(effects
				(font
					(size 1 1)
					(thickness 0.15)
				)
				(justify mirror)
			)
		)
		(property "Voltage" "50V"
			(at 0 0 0)
			(unlocked yes)
			(layer "B.Fab")
			(hide yes)
			(effects
				(font
					(size 1 1)
					(thickness 0.15)
				)
				(justify mirror)
			)
		)
		(property "Dielectric" "X5R"
			(at 0 0 0)
			(unlocked yes)
			(layer "B.Fab")
			(hide yes)
			(effects
				(font
					(size 1 1)
					(thickness 0.15)
				)
				(justify mirror)
			)
		)
		(property "Manufacturer" "Murata"
			(at 0 0 0)
			(unlocked yes)
			(layer "B.Fab")
			(hide yes)
			(effects
				(font
					(size 1 1)
					(thickness 0.15)
				)
				(justify mirror)
			)
		)
		(property "License" "Apache-2.0"
			(at 0 0 0)
			(unlocked yes)
			(layer "B.Fab")
			(hide yes)
			(effects
				(font
					(size 1 1)
					(thickness 0.15)
				)
				(justify mirror)
			)
		)
		(property "Author" "Antmicro"
			(at 0 0 0)
			(unlocked yes)
			(layer "B.Fab")
			(hide yes)
			(effects
				(font
					(size 1 1)
					(thickness 0.15)
				)
				(justify mirror)
			)
		)
		(sheetname "/SoM_Power/")
		(sheetfile "som_power.kicad_sch")
		(attr smd)
		(fp_rect
			(start -0.925 0.47)
			(end 0.925 -0.47)
			(stroke
				(width 0.05)
				(type default)
			)
			(fill no)
			(layer "B.CrtYd")
		)
		(fp_line
			(start 0.504 0.25)
			(end 0.504 -0.248)
			(stroke
				(width 0.15)
				(type solid)
			)
			(layer "B.Fab")
		)
		(fp_line
			(start 0.504 -0.248)
			(end -0.494 -0.248)
			(stroke
				(width 0.15)
				(type solid)
			)
			(layer "B.Fab")
		)
		(fp_line
			(start -0.494 0.25)
			(end 0.504 0.25)
			(stroke
				(width 0.15)
				(type solid)
			)
			(layer "B.Fab")
		)
		(fp_line
			(start -0.494 -0.248)
			(end -0.494 0.25)
			(stroke
				(width 0.15)
				(type solid)
			)
			(layer "B.Fab")
		)
		(fp_text user "${REFERENCE}"
			(at -0.939 -4.599 0)
			(layer "B.Fab")
			(effects
				(font
					(size 0.7 0.7)
					(thickness 0.15)
				)
				(justify left bottom mirror)
			)
		)
		(fp_text user "Author: Antmicro"
			(at -0.939 -3.399 0)
			(layer "B.Fab")
			(effects
				(font
					(size 0.7 0.7)
					(thickness 0.15)
				)
				(justify left bottom mirror)
			)
		)
		(fp_text user "License: Apache-2.0"
			(at -0.939 -5.799 0)
			(layer "B.Fab")
			(effects
				(font
					(size 0.7 0.7)
					(thickness 0.15)
				)
				(justify left bottom mirror)
			)
		)
		(pad "1" smd roundrect
			(at -0.48 0 180)
			(size 0.59 0.64)
			(layers "B.Cu" "B.Mask" "B.Paste")
			(roundrect_rratio 0.25)
			(net 1 "GND")
			(pintype "passive")
		)
		(pad "2" smd roundrect
			(at 0.48 0 180)
			(size 0.59 0.64)
			(layers "B.Cu" "B.Mask" "B.Paste")
			(roundrect_rratio 0.25)
			(net 213 "+5V_SOM")
			(pintype "passive")
		)
	)
	(footprint "antmicro-footprints:C_0402_1005Metric"
		(layer "B.Cu")
		(at 119.7 151.2 180)
		(descr "Capacitor SMD 0402")
		(tags "capacitor SMD 0402")
		(property "Reference" "C209"
			(at -3.7035 -0.33 0)
			(layer "B.SilkS")
			(effects
				(font
					(size 0.7 0.7)
					(thickness 0.15)
				)
				(justify left bottom mirror)
			)
		)
		(property "Value" "C_100n_0402"
			(at -1.022927 -2.155213 0)
			(layer "B.Fab")
			(effects
				(font
					(size 0.7 0.7)
					(thickness 0.15)
				)
				(justify left bottom mirror)
			)
		)
		(property "Datasheet" "https://www.murata.com/products/productdetail?partno=GRM155R61H104KE14%23"
			(at 0 0 0)
			(layer "B.Fab")
			(hide yes)
			(effects
				(font
					(size 1.27 1.27)
					(thickness 0.15)
				)
				(justify mirror)
			)
		)
		(property "Description" "SMD Multilayer Ceramic Capacitor, 0.1 µF, 50 V, 0402 [1005 Metric], ± 10%, X5R, GRM Series"
			(at 0 0 0)
			(layer "B.Fab")
			(hide yes)
			(effects
				(font
					(size 1.27 1.27)
					(thickness 0.15)
				)
				(justify mirror)
			)
		)
		(property "MPN" "GRM155R61H104KE14D"
			(at 0 0 0)
			(unlocked yes)
			(layer "B.Fab")
			(hide yes)
			(effects
				(font
					(size 1 1)
					(thickness 0.15)
				)
				(justify mirror)
			)
		)
		(property "Manufacturer" "Murata"
			(at 0 0 0)
			(unlocked yes)
			(layer "B.Fab")
			(hide yes)
			(effects
				(font
					(size 1 1)
					(thickness 0.15)
				)
				(justify mirror)
			)
		)
		(property "License" "Apache-2.0"
			(at 0 0 0)
			(unlocked yes)
			(layer "B.Fab")
			(hide yes)
			(effects
				(font
					(size 1 1)
					(thickness 0.15)
				)
				(justify mirror)
			)
		)
		(property "Author" "Antmicro"
			(at 0 0 0)
			(unlocked yes)
			(layer "B.Fab")
			(hide yes)
			(effects
				(font
					(size 1 1)
					(thickness 0.15)
				)
				(justify mirror)
			)
		)
		(property "Val" "100n"
			(at 0 0 0)
			(unlocked yes)
			(layer "B.Fab")
			(hide yes)
			(effects
				(font
					(size 1 1)
					(thickness 0.15)
				)
				(justify mirror)
			)
		)
		(property "Voltage" "50V"
			(at 0 0 0)
			(unlocked yes)
			(layer "B.Fab")
			(hide yes)
			(effects
				(font
					(size 1 1)
					(thickness 0.15)
				)
				(justify mirror)
			)
		)
		(property "Dielectric" "X5R"
			(at 0 0 0)
			(unlocked yes)
			(layer "B.Fab")
			(hide yes)
			(effects
				(font
					(size 1 1)
					(thickness 0.15)
				)
				(justify mirror)
			)
		)
		(sheetname "/Peripherals/")
		(sheetfile "peripherals.kicad_sch")
		(attr smd)
		(fp_poly
			(pts
				(xy -0.925 0.47) (xy 0.925 0.47) (xy 0.925 -0.47) (xy -0.925 -0.47)
			)
			(stroke
				(width 0.05)
				(type default)
			)
			(fill no)
			(layer "B.CrtYd")
		)
		(fp_line
			(start 0.504 0.25)
			(end 0.504 -0.248)
			(stroke
				(width 0.15)
				(type solid)
			)
			(layer "B.Fab")
		)
		(fp_line
			(start 0.504 -0.248)
			(end -0.494 -0.248)
			(stroke
				(width 0.15)
				(type solid)
			)
			(layer "B.Fab")
		)
		(fp_line
			(start -0.494 0.25)
			(end 0.504 0.25)
			(stroke
				(width 0.15)
				(type solid)
			)
			(layer "B.Fab")
		)
		(fp_line
			(start -0.494 -0.248)
			(end -0.494 0.25)
			(stroke
				(width 0.15)
				(type solid)
			)
			(layer "B.Fab")
		)
		(fp_text user "${REFERENCE}"
			(at -0.939 -4.599 0)
			(layer "B.Fab")
			(effects
				(font
					(size 0.7 0.7)
					(thickness 0.15)
				)
				(justify left bottom mirror)
			)
		)
		(fp_text user "Author: Antmicro"
			(at -0.939 -3.399 0)
			(layer "B.Fab")
			(effects
				(font
					(size 0.7 0.7)
					(thickness 0.15)
				)
				(justify left bottom mirror)
			)
		)
		(fp_text user "License: Apache-2.0"
			(at -0.939 -5.799 0)
			(layer "B.Fab")
			(effects
				(font
					(size 0.7 0.7)
					(thickness 0.15)
				)
				(justify left bottom mirror)
			)
		)
		(pad "1" smd roundrect
			(at -0.48 0 180)
			(size 0.59 0.64)
			(layers "B.Cu" "B.Mask" "B.Paste")
			(roundrect_rratio 0.25)
			(net 1 "GND")
			(pintype "passive")
		)
		(pad "2" smd roundrect
			(at 0.48 0 180)
			(size 0.59 0.64)
			(layers "B.Cu" "B.Mask" "B.Paste")
			(roundrect_rratio 0.25)
			(net 4 "+3V3_AON")
			(pintype "passive")
		)
	)
	(footprint "antmicro-footprints:R_0402_1005Metric"
		(layer "B.Cu")
		(at 179.75 57.5 -90)
		(descr "Resistor SMD 0402")
		(tags "resistor SMD 0402")
		(property "Reference" "R51"
			(at -3.48 -0.365532 90)
			(layer "B.SilkS")
			(effects
				(font
					(size 0.7 0.7)
					(thickness 0.15)
				)
				(justify left bottom mirror)
			)
		)
		(property "Value" "R_2k2_0402"
			(at -1.011843 -1.772047 90)
			(layer "B.Fab")
			(effects
				(font
					(size 0.7 0.7)
					(thickness 0.15)
				)
				(justify left bottom mirror)
			)
		)
		(property "Datasheet" "https://www.bourns.com/docs/product-datasheets/cr.pdf"
			(at 0 0 90)
			(layer "B.Fab")
			(hide yes)
			(effects
				(font
					(size 1.27 1.27)
					(thickness 0.15)
				)
				(justify mirror)
			)
		)
		(property "Description" "SMD Chip Resistor, 2.2 kohm, ± 1%, 62.5 mW, 0402 [1005 Metric], Thick Film, General Purpose"
			(at 0 0 90)
			(layer "B.Fab")
			(hide yes)
			(effects
				(font
					(size 1.27 1.27)
					(thickness 0.15)
				)
				(justify mirror)
			)
		)
		(property "MPN" "CR0402-FX-2201GLF"
			(at 0 0 90)
			(unlocked yes)
			(layer "B.Fab")
			(hide yes)
			(effects
				(font
					(size 1 1)
					(thickness 0.15)
				)
				(justify mirror)
			)
		)
		(property "Manufacturer" "Bourns"
			(at 0 0 90)
			(unlocked yes)
			(layer "B.Fab")
			(hide yes)
			(effects
				(font
					(size 1 1)
					(thickness 0.15)
				)
				(justify mirror)
			)
		)
		(property "License" "Apache-2.0"
			(at 0 0 90)
			(unlocked yes)
			(layer "B.Fab")
			(hide yes)
			(effects
				(font
					(size 1 1)
					(thickness 0.15)
				)
				(justify mirror)
			)
		)
		(property "Author" "Antmicro"
			(at 0 0 90)
			(unlocked yes)
			(layer "B.Fab")
			(hide yes)
			(effects
				(font
					(size 1 1)
					(thickness 0.15)
				)
				(justify mirror)
			)
		)
		(property "Val" "2k2"
			(at 0 0 90)
			(unlocked yes)
			(layer "B.Fab")
			(hide yes)
			(effects
				(font
					(size 1 1)
					(thickness 0.15)
				)
				(justify mirror)
			)
		)
		(property "Tolerance" "1%"
			(at 0 0 90)
			(unlocked yes)
			(layer "B.Fab")
			(hide yes)
			(effects
				(font
					(size 1 1)
					(thickness 0.15)
				)
				(justify mirror)
			)
		)
		(sheetname "/Power/")
		(sheetfile "power.kicad_sch")
		(attr smd)
		(fp_rect
			(start -0.925 0.47)
			(end 0.925 -0.47)
			(stroke
				(width 0.05)
				(type default)
			)
			(fill no)
			(layer "B.CrtYd")
		)
		(fp_rect
			(start -0.5 0.25)
			(end 0.5 -0.25)
			(stroke
				(width 0.15)
				(type solid)
			)
			(fill no)
			(layer "B.Fab")
		)
		(fp_text user "License: Apache-2.0"
			(at -0.95 -5.169 90)
			(layer "B.Fab")
			(effects
				(font
					(size 0.7 0.7)
					(thickness 0.15)
				)
				(justify left bottom mirror)
			)
		)
		(fp_text user "Author: Antmicro"
			(at -0.95 -4.169 90)
			(layer "B.Fab")
			(effects
				(font
					(size 0.7 0.7)
					(thickness 0.15)
				)
				(justify left bottom mirror)
			)
		)
		(fp_text user "${REFERENCE}"
			(at -0.95 -3.168 90)
			(layer "B.Fab")
			(effects
				(font
					(size 0.7 0.7)
					(thickness 0.15)
				)
				(justify left bottom mirror)
			)
		)
		(pad "1" smd roundrect
			(at -0.48 0 270)
			(size 0.59 0.64)
			(layers "B.Cu" "B.Mask" "B.Paste")
			(roundrect_rratio 0.25)
			(net 529 "Net-(D10-A)")
			(pintype "passive")
		)
		(pad "2" smd roundrect
			(at 0.48 0 270)
			(size 0.59 0.64)
			(layers "B.Cu" "B.Mask" "B.Paste")
			(roundrect_rratio 0.25)
			(net 12 "SYS_VIN_HV")
			(pintype "passive")
		)
	)
	(footprint "antmicro-footprints:R_0402_1005Metric"
		(layer "B.Cu")
		(at 219.4 95.4)
		(descr "Resistor SMD 0402")
		(tags "resistor SMD 0402")
		(property "Reference" "R273"
			(at -1.5 -2.5 0)
			(layer "B.SilkS")
			(effects
				(font
					(size 0.7 0.7)
					(thickness 0.15)
				)
				(justify right top mirror)
			)
		)
		(property "Value" "R_10k_0402"
			(at -1.011843 -1.772047 0)
			(layer "B.Fab")
			(effects
				(font
					(size 0.7 0.7)
					(thickness 0.15)
				)
				(justify right top mirror)
			)
		)
		(property "Datasheet" "https://www.bourns.com/docs/product-datasheets/cr.pdf"
			(at 0 0 0)
			(layer "B.Fab")
			(hide yes)
			(effects
				(font
					(size 1.27 1.27)
					(thickness 0.15)
				)
				(justify mirror)
			)
		)
		(property "Description" "SMD Chip Resistor, 10 kohm, ± 1%, 62.5 mW, 0402 [1005 Metric], Thick Film, General Purpose"
			(at 0 0 0)
			(layer "B.Fab")
			(hide yes)
			(effects
				(font
					(size 1.27 1.27)
					(thickness 0.15)
				)
				(justify mirror)
			)
		)
		(property "MPN" "CR0402-FX-1002GLF"
			(at 0 0 180)
			(unlocked yes)
			(layer "B.Fab")
			(hide yes)
			(effects
				(font
					(size 1 1)
					(thickness 0.15)
				)
				(justify mirror)
			)
		)
		(property "Manufacturer" "Bourns"
			(at 0 0 180)
			(unlocked yes)
			(layer "B.Fab")
			(hide yes)
			(effects
				(font
					(size 1 1)
					(thickness 0.15)
				)
				(justify mirror)
			)
		)
		(property "License" "Apache-2.0"
			(at 0 0 180)
			(unlocked yes)
			(layer "B.Fab")
			(hide yes)
			(effects
				(font
					(size 1 1)
					(thickness 0.15)
				)
				(justify mirror)
			)
		)
		(property "Author" "Antmicro"
			(at 0 0 180)
			(unlocked yes)
			(layer "B.Fab")
			(hide yes)
			(effects
				(font
					(size 1 1)
					(thickness 0.15)
				)
				(justify mirror)
			)
		)
		(property "Val" "10k"
			(at 0 0 180)
			(unlocked yes)
			(layer "B.Fab")
			(hide yes)
			(effects
				(font
					(size 1 1)
					(thickness 0.15)
				)
				(justify mirror)
			)
		)
		(property "Tolerance" "1%"
			(at 0 0 180)
			(unlocked yes)
			(layer "B.Fab")
			(hide yes)
			(effects
				(font
					(size 1 1)
					(thickness 0.15)
				)
				(justify mirror)
			)
		)
		(sheetname "/USB DP Alt mode/")
		(sheetfile "usb_dp.kicad_sch")
		(attr smd)
		(fp_rect
			(start -0.925 0.47)
			(end 0.925 -0.47)
			(stroke
				(width 0.05)
				(type default)
			)
			(fill no)
			(layer "B.CrtYd")
		)
		(fp_rect
			(start -0.5 0.25)
			(end 0.5 -0.25)
			(stroke
				(width 0.15)
				(type solid)
			)
			(fill no)
			(layer "B.Fab")
		)
		(fp_text user "${REFERENCE}"
			(at -0.95 -3.168 0)
			(layer "B.Fab")
			(effects
				(font
					(size 0.7 0.7)
					(thickness 0.15)
				)
				(justify right top mirror)
			)
		)
		(fp_text user "License: Apache-2.0"
			(at -0.95 -5.169 0)
			(layer "B.Fab")
			(effects
				(font
					(size 0.7 0.7)
					(thickness 0.15)
				)
				(justify right top mirror)
			)
		)
		(fp_text user "Author: Antmicro"
			(at -0.95 -4.169 0)
			(layer "B.Fab")
			(effects
				(font
					(size 0.7 0.7)
					(thickness 0.15)
				)
				(justify right top mirror)
			)
		)
		(pad "1" smd roundrect
			(at -0.48 0)
			(size 0.59 0.64)
			(layers "B.Cu" "B.Mask" "B.Paste")
			(roundrect_rratio 0.25)
			(net 1300 "Net-(Q34-D)")
			(pintype "passive")
		)
		(pad "2" smd roundrect
			(at 0.48 0)
			(size 0.59 0.64)
			(layers "B.Cu" "B.Mask" "B.Paste")
			(roundrect_rratio 0.25)
			(net 11 "+1V8")
			(pintype "passive")
		)
	)
	(footprint "antmicro-footprints:R_0402_1005Metric"
		(layer "B.Cu")
		(at 220.66 114.01)
		(descr "Resistor SMD 0402")
		(tags "resistor SMD 0402")
		(property "Reference" "R330"
			(at -1.06 1.77 0)
			(layer "B.SilkS")
			(effects
				(font
					(size 0.7 0.7)
					(thickness 0.15)
				)
				(justify right top mirror)
			)
		)
		(property "Value" "R_2R2_0402"
			(at -1.011843 -1.772047 0)
			(layer "B.Fab")
			(effects
				(font
					(size 0.7 0.7)
					(thickness 0.15)
				)
				(justify right top mirror)
			)
		)
		(property "Datasheet" "https://www.bourns.com/docs/product-datasheets/cr.pdf"
			(at 0 0 0)
			(layer "B.Fab")
			(hide yes)
			(effects
				(font
					(size 1.27 1.27)
					(thickness 0.15)
				)
				(justify mirror)
			)
		)
		(property "Description" "SMD Chip Resistor, 2.2 ohm, ± 1%, 62.5 mW, 0402 [1005 Metric], Thick Film, General Purpose"
			(at 0 0 0)
			(layer "B.Fab")
			(hide yes)
			(effects
				(font
					(size 1.27 1.27)
					(thickness 0.15)
				)
				(justify mirror)
			)
		)
		(property "MPN" "CR0402-FX-2R20GLF"
			(at 0 0 180)
			(unlocked yes)
			(layer "B.Fab")
			(hide yes)
			(effects
				(font
					(size 1 1)
					(thickness 0.15)
				)
				(justify mirror)
			)
		)
		(property "Manufacturer" "Bourns"
			(at 0 0 180)
			(unlocked yes)
			(layer "B.Fab")
			(hide yes)
			(effects
				(font
					(size 1 1)
					(thickness 0.15)
				)
				(justify mirror)
			)
		)
		(property "License" "Apache-2.0"
			(at 0 0 180)
			(unlocked yes)
			(layer "B.Fab")
			(hide yes)
			(effects
				(font
					(size 1 1)
					(thickness 0.15)
				)
				(justify mirror)
			)
		)
		(property "Author" "Antmicro"
			(at 0 0 180)
			(unlocked yes)
			(layer "B.Fab")
			(hide yes)
			(effects
				(font
					(size 1 1)
					(thickness 0.15)
				)
				(justify mirror)
			)
		)
		(property "Val" "2R2"
			(at 0 0 180)
			(unlocked yes)
			(layer "B.Fab")
			(hide yes)
			(effects
				(font
					(size 1 1)
					(thickness 0.15)
				)
				(justify mirror)
			)
		)
		(property "Tolerance" "1%"
			(at 0 0 180)
			(unlocked yes)
			(layer "B.Fab")
			(hide yes)
			(effects
				(font
					(size 1 1)
					(thickness 0.15)
				)
				(justify mirror)
			)
		)
		(sheetname "/USB Hub/")
		(sheetfile "usb_hub.kicad_sch")
		(attr smd)
		(fp_rect
			(start -0.925 0.47)
			(end 0.925 -0.47)
			(stroke
				(width 0.05)
				(type default)
			)
			(fill no)
			(layer "B.CrtYd")
		)
		(fp_rect
			(start -0.5 0.25)
			(end 0.5 -0.25)
			(stroke
				(width 0.15)
				(type solid)
			)
			(fill no)
			(layer "B.Fab")
		)
		(fp_text user "License: Apache-2.0"
			(at -0.95 -5.169 0)
			(layer "B.Fab")
			(effects
				(font
					(size 0.7 0.7)
					(thickness 0.15)
				)
				(justify right top mirror)
			)
		)
		(fp_text user "${REFERENCE}"
			(at -0.95 -3.168 0)
			(layer "B.Fab")
			(effects
				(font
					(size 0.7 0.7)
					(thickness 0.15)
				)
				(justify right top mirror)
			)
		)
		(fp_text user "Author: Antmicro"
			(at -0.95 -4.169 0)
			(layer "B.Fab")
			(effects
				(font
					(size 0.7 0.7)
					(thickness 0.15)
				)
				(justify right top mirror)
			)
		)
		(pad "1" smd roundrect
			(at -0.48 0)
			(size 0.59 0.64)
			(layers "B.Cu" "B.Mask" "B.Paste")
			(roundrect_rratio 0.25)
			(net 633 "Net-(D57-C)")
			(pintype "passive")
		)
		(pad "2" smd roundrect
			(at 0.48 0)
			(size 0.59 0.64)
			(layers "B.Cu" "B.Mask" "B.Paste")
			(roundrect_rratio 0.25)
			(net 510 "/USB Hub/USBC3_CC_{1}")
			(pintype "passive")
		)
	)
	(footprint "antmicro-footprints:C_0402_1005Metric"
		(layer "B.Cu")
		(at 234.6 84.1 180)
		(descr "Capacitor SMD 0402")
		(tags "capacitor SMD 0402")
		(property "Reference" "C148"
			(at -1.6 -1.4 0)
			(layer "B.SilkS")
			(effects
				(font
					(size 0.7 0.7)
					(thickness 0.15)
				)
				(justify left bottom mirror)
			)
		)
		(property "Value" "C_100n_0402"
			(at -1.022927 -2.155213 0)
			(layer "B.Fab")
			(effects
				(font
					(size 0.7 0.7)
					(thickness 0.15)
				)
				(justify left bottom mirror)
			)
		)
		(property "Datasheet" "https://www.murata.com/products/productdetail?partno=GRM155R61H104KE14%23"
			(at 0 0 0)
			(layer "B.Fab")
			(hide yes)
			(effects
				(font
					(size 1.27 1.27)
					(thickness 0.15)
				)
				(justify mirror)
			)
		)
		(property "Description" "SMD Multilayer Ceramic Capacitor, 0.1 µF, 50 V, 0402 [1005 Metric], ± 10%, X5R, GRM Series"
			(at 0 0 0)
			(layer "B.Fab")
			(hide yes)
			(effects
				(font
					(size 1.27 1.27)
					(thickness 0.15)
				)
				(justify mirror)
			)
		)
		(property "Manufacturer" "Murata"
			(at 0 0 0)
			(unlocked yes)
			(layer "B.Fab")
			(hide yes)
			(effects
				(font
					(size 1 1)
					(thickness 0.15)
				)
				(justify mirror)
			)
		)
		(property "MPN" "GRM155R61H104KE14D"
			(at 0 0 0)
			(unlocked yes)
			(layer "B.Fab")
			(hide yes)
			(effects
				(font
					(size 1 1)
					(thickness 0.15)
				)
				(justify mirror)
			)
		)
		(property "Val" "100n"
			(at 0 0 0)
			(unlocked yes)
			(layer "B.Fab")
			(hide yes)
			(effects
				(font
					(size 1 1)
					(thickness 0.15)
				)
				(justify mirror)
			)
		)
		(property "License" "Apache-2.0"
			(at 0 0 0)
			(unlocked yes)
			(layer "B.Fab")
			(hide yes)
			(effects
				(font
					(size 1 1)
					(thickness 0.15)
				)
				(justify mirror)
			)
		)
		(property "Author" "Antmicro"
			(at 0 0 0)
			(unlocked yes)
			(layer "B.Fab")
			(hide yes)
			(effects
				(font
					(size 1 1)
					(thickness 0.15)
				)
				(justify mirror)
			)
		)
		(property "Voltage" "50V"
			(at 0 0 0)
			(unlocked yes)
			(layer "B.Fab")
			(hide yes)
			(effects
				(font
					(size 1 1)
					(thickness 0.15)
				)
				(justify mirror)
			)
		)
		(property "Dielectric" "X5R"
			(at 0 0 0)
			(unlocked yes)
			(layer "B.Fab")
			(hide yes)
			(effects
				(font
					(size 1 1)
					(thickness 0.15)
				)
				(justify mirror)
			)
		)
		(sheetname "/USB Debug, PD/")
		(sheetfile "usb_debug_pd.kicad_sch")
		(attr smd)
		(fp_poly
			(pts
				(xy -0.925 0.47) (xy -0.925 -0.47) (xy 0.925 -0.47) (xy 0.925 0.47)
			)
			(stroke
				(width 0.05)
				(type default)
			)
			(fill no)
			(layer "B.CrtYd")
		)
		(fp_line
			(start 0.504 0.25)
			(end 0.504 -0.248)
			(stroke
				(width 0.15)
				(type solid)
			)
			(layer "B.Fab")
		)
		(fp_line
			(start 0.504 -0.248)
			(end -0.494 -0.248)
			(stroke
				(width 0.15)
				(type solid)
			)
			(layer "B.Fab")
		)
		(fp_line
			(start -0.494 0.25)
			(end 0.504 0.25)
			(stroke
				(width 0.15)
				(type solid)
			)
			(layer "B.Fab")
		)
		(fp_line
			(start -0.494 -0.248)
			(end -0.494 0.25)
			(stroke
				(width 0.15)
				(type solid)
			)
			(layer "B.Fab")
		)
		(fp_text user "License: Apache-2.0"
			(at -0.939 -5.799 0)
			(layer "B.Fab")
			(effects
				(font
					(size 0.7 0.7)
					(thickness 0.15)
				)
				(justify left bottom mirror)
			)
		)
		(fp_text user "Author: Antmicro"
			(at -0.939 -3.399 0)
			(layer "B.Fab")
			(effects
				(font
					(size 0.7 0.7)
					(thickness 0.15)
				)
				(justify left bottom mirror)
			)
		)
		(fp_text user "${REFERENCE}"
			(at -0.939 -4.599 0)
			(layer "B.Fab")
			(effects
				(font
					(size 0.7 0.7)
					(thickness 0.15)
				)
				(justify left bottom mirror)
			)
		)
		(pad "1" smd roundrect
			(at -0.48 0 180)
			(size 0.59 0.64)
			(layers "B.Cu" "B.Mask" "B.Paste")
			(roundrect_rratio 0.25)
			(net 5 "+5V")
			(pintype "passive")
		)
		(pad "2" smd roundrect
			(at 0.48 0 180)
			(size 0.59 0.64)
			(layers "B.Cu" "B.Mask" "B.Paste")
			(roundrect_rratio 0.25)
			(net 1 "GND")
			(pintype "passive")
		)
	)
	(footprint "antmicro-footprints:R_0402_1005Metric"
		(layer "B.Cu")
		(at 62.8 86 -90)
		(descr "Resistor SMD 0402")
		(tags "resistor SMD 0402")
		(property "Reference" "R182"
			(at -1.75 -2.45 90)
			(layer "B.SilkS")
			(effects
				(font
					(size 0.7 0.7)
					(thickness 0.15)
				)
				(justify left bottom mirror)
			)
		)
		(property "Value" "R_200R_0402"
			(at -1.011843 -1.772046 90)
			(layer "B.Fab")
			(effects
				(font
					(size 0.7 0.7)
					(thickness 0.15)
				)
				(justify left bottom mirror)
			)
		)
		(property "Datasheet" "https://www.bourns.com/docs/product-datasheets/cr.pdf"
			(at 0 0 90)
			(layer "B.Fab")
			(hide yes)
			(effects
				(font
					(size 1.27 1.27)
					(thickness 0.15)
				)
				(justify mirror)
			)
		)
		(property "Description" "SMD Chip Resistor, 200 ohm, ± 1%, 62.5 mW, 0402 [1005 Metric], Thick Film, General Purpose"
			(at 0 0 90)
			(layer "B.Fab")
			(hide yes)
			(effects
				(font
					(size 1.27 1.27)
					(thickness 0.15)
				)
				(justify mirror)
			)
		)
		(property "Manufacturer" "Bourns"
			(at 0 0 90)
			(unlocked yes)
			(layer "B.Fab")
			(hide yes)
			(effects
				(font
					(size 1 1)
					(thickness 0.15)
				)
				(justify mirror)
			)
		)
		(property "MPN" "CR0402-FX-2000GLF"
			(at 0 0 90)
			(unlocked yes)
			(layer "B.Fab")
			(hide yes)
			(effects
				(font
					(size 1 1)
					(thickness 0.15)
				)
				(justify mirror)
			)
		)
		(property "Val" "200R"
			(at 0 0 90)
			(unlocked yes)
			(layer "B.Fab")
			(hide yes)
			(effects
				(font
					(size 1 1)
					(thickness 0.15)
				)
				(justify mirror)
			)
		)
		(property "License" "Apache-2.0"
			(at 0 0 90)
			(unlocked yes)
			(layer "B.Fab")
			(hide yes)
			(effects
				(font
					(size 1 1)
					(thickness 0.15)
				)
				(justify mirror)
			)
		)
		(property "Author" "Antmicro"
			(at 0 0 90)
			(unlocked yes)
			(layer "B.Fab")
			(hide yes)
			(effects
				(font
					(size 1 1)
					(thickness 0.15)
				)
				(justify mirror)
			)
		)
		(property "Tolerance" "1%"
			(at 0 0 90)
			(unlocked yes)
			(layer "B.Fab")
			(hide yes)
			(effects
				(font
					(size 1 1)
					(thickness 0.15)
				)
				(justify mirror)
			)
		)
		(sheetname "/CSI/")
		(sheetfile "csi.kicad_sch")
		(attr smd)
		(fp_poly
			(pts
				(xy -0.925 0.47) (xy 0.925 0.47) (xy 0.925 -0.47) (xy -0.925 -0.47)
			)
			(stroke
				(width 0.05)
				(type default)
			)
			(fill no)
			(layer "B.CrtYd")
		)
		(fp_poly
			(pts
				(xy -0.5 0.25) (xy 0.5 0.25) (xy 0.5 -0.25) (xy -0.5 -0.25)
			)
			(stroke
				(width 0.15)
				(type solid)
			)
			(fill no)
			(layer "B.Fab")
		)
		(fp_text user "Author: Antmicro"
			(at -0.95 -4.169 90)
			(layer "B.Fab")
			(effects
				(font
					(size 0.7 0.7)
					(thickness 0.15)
				)
				(justify left bottom mirror)
			)
		)
		(fp_text user "License: Apache-2.0"
			(at -0.949999 -5.169 90)
			(layer "B.Fab")
			(effects
				(font
					(size 0.7 0.7)
					(thickness 0.15)
				)
				(justify left bottom mirror)
			)
		)
		(fp_text user "${REFERENCE}"
			(at -0.95 -3.168 90)
			(layer "B.Fab")
			(effects
				(font
					(size 0.7 0.7)
					(thickness 0.15)
				)
				(justify left bottom mirror)
			)
		)
		(pad "1" smd roundrect
			(at -0.48 0 270)
			(size 0.59 0.64)
			(layers "B.Cu" "B.Mask" "B.Paste")
			(roundrect_rratio 0.25)
			(net 541 "Net-(D28-A)")
			(pintype "passive")
		)
		(pad "2" smd roundrect
			(at 0.48 0 270)
			(size 0.59 0.64)
			(layers "B.Cu" "B.Mask" "B.Paste")
			(roundrect_rratio 0.25)
			(net 6 "/CSI/CSIA_3V3")
			(pintype "passive")
		)
	)
	(footprint "antmicro-footprints:R_0402_1005Metric"
		(layer "B.Cu")
		(at 129.1 151.2 -90)
		(descr "Resistor SMD 0402")
		(tags "resistor SMD 0402")
		(property "Reference" "R230"
			(at -1.1 -6.29 90)
			(layer "B.SilkS")
			(effects
				(font
					(size 0.7 0.7)
					(thickness 0.15)
				)
				(justify left bottom mirror)
			)
		)
		(property "Value" "R_10k_0402"
			(at -1.011843 -1.772047 90)
			(layer "B.Fab")
			(effects
				(font
					(size 0.7 0.7)
					(thickness 0.15)
				)
				(justify left bottom mirror)
			)
		)
		(property "Datasheet" "https://www.bourns.com/docs/product-datasheets/cr.pdf"
			(at 0 0 90)
			(layer "B.Fab")
			(hide yes)
			(effects
				(font
					(size 1.27 1.27)
					(thickness 0.15)
				)
				(justify mirror)
			)
		)
		(property "Description" "SMD Chip Resistor, 10 kohm, ± 1%, 62.5 mW, 0402 [1005 Metric], Thick Film, General Purpose"
			(at 0 0 90)
			(layer "B.Fab")
			(hide yes)
			(effects
				(font
					(size 1.27 1.27)
					(thickness 0.15)
				)
				(justify mirror)
			)
		)
		(property "MPN" "CR0402-FX-1002GLF"
			(at 0 0 90)
			(unlocked yes)
			(layer "B.Fab")
			(hide yes)
			(effects
				(font
					(size 1 1)
					(thickness 0.15)
				)
				(justify mirror)
			)
		)
		(property "Manufacturer" "Bourns"
			(at 0 0 90)
			(unlocked yes)
			(layer "B.Fab")
			(hide yes)
			(effects
				(font
					(size 1 1)
					(thickness 0.15)
				)
				(justify mirror)
			)
		)
		(property "License" "Apache-2.0"
			(at 0 0 90)
			(unlocked yes)
			(layer "B.Fab")
			(hide yes)
			(effects
				(font
					(size 1 1)
					(thickness 0.15)
				)
				(justify mirror)
			)
		)
		(property "Author" "Antmicro"
			(at 0 0 90)
			(unlocked yes)
			(layer "B.Fab")
			(hide yes)
			(effects
				(font
					(size 1 1)
					(thickness 0.15)
				)
				(justify mirror)
			)
		)
		(property "Val" "10k"
			(at 0 0 90)
			(unlocked yes)
			(layer "B.Fab")
			(hide yes)
			(effects
				(font
					(size 1 1)
					(thickness 0.15)
				)
				(justify mirror)
			)
		)
		(property "Tolerance" "1%"
			(at 0 0 90)
			(unlocked yes)
			(layer "B.Fab")
			(hide yes)
			(effects
				(font
					(size 1 1)
					(thickness 0.15)
				)
				(justify mirror)
			)
		)
		(sheetname "/Peripherals/")
		(sheetfile "peripherals.kicad_sch")
		(attr smd)
		(fp_rect
			(start -0.925 0.47)
			(end 0.925 -0.47)
			(stroke
				(width 0.05)
				(type default)
			)
			(fill no)
			(layer "B.CrtYd")
		)
		(fp_rect
			(start -0.5 0.25)
			(end 0.5 -0.25)
			(stroke
				(width 0.15)
				(type solid)
			)
			(fill no)
			(layer "B.Fab")
		)
		(fp_text user "${REFERENCE}"
			(at -0.95 -3.168 90)
			(layer "B.Fab")
			(effects
				(font
					(size 0.7 0.7)
					(thickness 0.15)
				)
				(justify left bottom mirror)
			)
		)
		(fp_text user "License: Apache-2.0"
			(at -0.95 -5.169 90)
			(layer "B.Fab")
			(effects
				(font
					(size 0.7 0.7)
					(thickness 0.15)
				)
				(justify left bottom mirror)
			)
		)
		(fp_text user "Author: Antmicro"
			(at -0.95 -4.169 90)
			(layer "B.Fab")
			(effects
				(font
					(size 0.7 0.7)
					(thickness 0.15)
				)
				(justify left bottom mirror)
			)
		)
		(pad "1" smd roundrect
			(at -0.48 0 270)
			(size 0.59 0.64)
			(layers "B.Cu" "B.Mask" "B.Paste")
			(roundrect_rratio 0.25)
			(net 149 "/Peripherals/TPM_IRQ")
			(pintype "passive")
		)
		(pad "2" smd roundrect
			(at 0.48 0 270)
			(size 0.59 0.64)
			(layers "B.Cu" "B.Mask" "B.Paste")
			(roundrect_rratio 0.25)
			(net 2 "+3V3")
			(pintype "passive")
		)
	)
	(footprint "antmicro-footprints:R_0402_1005Metric"
		(layer "B.Cu")
		(at 206.7 121)
		(descr "Resistor SMD 0402")
		(tags "resistor SMD 0402")
		(property "Reference" "R263"
			(at 1.04 -0.35 0)
			(layer "B.SilkS")
			(effects
				(font
					(size 0.7 0.7)
					(thickness 0.15)
				)
				(justify right top mirror)
			)
		)
		(property "Value" "R_43k_0402"
			(at -1.011843 -1.772047 0)
			(layer "B.Fab")
			(effects
				(font
					(size 0.7 0.7)
					(thickness 0.15)
				)
				(justify right top mirror)
			)
		)
		(property "Datasheet" "https://www.bourns.com/docs/product-datasheets/cr.pdf"
			(at 0 0 0)
			(layer "B.Fab")
			(hide yes)
			(effects
				(font
					(size 1.27 1.27)
					(thickness 0.15)
				)
				(justify mirror)
			)
		)
		(property "Description" "SMD Chip Resistor"
			(at 0 0 0)
			(layer "B.Fab")
			(hide yes)
			(effects
				(font
					(size 1.27 1.27)
					(thickness 0.15)
				)
				(justify mirror)
			)
		)
		(property "MPN" "CR0402-FX-4302GLF"
			(at 0 0 180)
			(unlocked yes)
			(layer "B.Fab")
			(hide yes)
			(effects
				(font
					(size 1 1)
					(thickness 0.15)
				)
				(justify mirror)
			)
		)
		(property "Manufacturer" "Bourns"
			(at 0 0 180)
			(unlocked yes)
			(layer "B.Fab")
			(hide yes)
			(effects
				(font
					(size 1 1)
					(thickness 0.15)
				)
				(justify mirror)
			)
		)
		(property "License" "Apache-2.0"
			(at 0 0 180)
			(unlocked yes)
			(layer "B.Fab")
			(hide yes)
			(effects
				(font
					(size 1 1)
					(thickness 0.15)
				)
				(justify mirror)
			)
		)
		(property "Author" "Antmicro"
			(at 0 0 180)
			(unlocked yes)
			(layer "B.Fab")
			(hide yes)
			(effects
				(font
					(size 1 1)
					(thickness 0.15)
				)
				(justify mirror)
			)
		)
		(property "Val" "43k"
			(at 0 0 180)
			(unlocked yes)
			(layer "B.Fab")
			(hide yes)
			(effects
				(font
					(size 1 1)
					(thickness 0.15)
				)
				(justify mirror)
			)
		)
		(property "Tolerance" "1%"
			(at 0 0 180)
			(unlocked yes)
			(layer "B.Fab")
			(hide yes)
			(effects
				(font
					(size 1 1)
					(thickness 0.15)
				)
				(justify mirror)
			)
		)
		(sheetname "/USB Hub/")
		(sheetfile "usb_hub.kicad_sch")
		(attr smd)
		(fp_rect
			(start -0.925 0.47)
			(end 0.925 -0.47)
			(stroke
				(width 0.05)
				(type default)
			)
			(fill no)
			(layer "B.CrtYd")
		)
		(fp_rect
			(start -0.5 0.25)
			(end 0.5 -0.25)
			(stroke
				(width 0.15)
				(type solid)
			)
			(fill no)
			(layer "B.Fab")
		)
		(fp_text user "Author: Antmicro"
			(at -0.95 -4.169 0)
			(layer "B.Fab")
			(effects
				(font
					(size 0.7 0.7)
					(thickness 0.15)
				)
				(justify right top mirror)
			)
		)
		(fp_text user "License: Apache-2.0"
			(at -0.95 -5.169 0)
			(layer "B.Fab")
			(effects
				(font
					(size 0.7 0.7)
					(thickness 0.15)
				)
				(justify right top mirror)
			)
		)
		(fp_text user "${REFERENCE}"
			(at -0.95 -3.168 0)
			(layer "B.Fab")
			(effects
				(font
					(size 0.7 0.7)
					(thickness 0.15)
				)
				(justify right top mirror)
			)
		)
		(pad "1" smd roundrect
			(at -0.48 0)
			(size 0.59 0.64)
			(layers "B.Cu" "B.Mask" "B.Paste")
			(roundrect_rratio 0.25)
			(net 1016 "/USB Hub/USBC3_VBUS_MON")
			(pintype "passive")
		)
		(pad "2" smd roundrect
			(at 0.48 0)
			(size 0.59 0.64)
			(layers "B.Cu" "B.Mask" "B.Paste")
			(roundrect_rratio 0.25)
			(net 71 "/USB Hub/USBC3_VBUS")
			(pintype "passive")
		)
	)
	(footprint "antmicro-footprints:R_0402_1005Metric"
		(layer "B.Cu")
		(at 190 121.7 90)
		(descr "Resistor SMD 0402")
		(tags "resistor SMD 0402")
		(property "Reference" "R101"
			(at -3.7 -0.4 90)
			(layer "B.SilkS")
			(effects
				(font
					(size 0.7 0.7)
					(thickness 0.15)
				)
				(justify right top mirror)
			)
		)
		(property "Value" "R_0R_0402"
			(at -1.011843 -1.772047 90)
			(layer "B.Fab")
			(effects
				(font
					(size 0.7 0.7)
					(thickness 0.15)
				)
				(justify right top mirror)
			)
		)
		(property "Datasheet" "https://industrial.panasonic.com/cdbs/www-data/pdf/RDA0000/AOA0000C301.pdf"
			(at 0 0 90)
			(layer "B.Fab")
			(hide yes)
			(effects
				(font
					(size 1.27 1.27)
					(thickness 0.15)
				)
				(justify mirror)
			)
		)
		(property "Description" "SMD Chip Resistor, Jumper, 0 ohm, 100 mW, 0402 [1005 Metric], Thick Film, General Purpose"
			(at 0 0 90)
			(layer "B.Fab")
			(hide yes)
			(effects
				(font
					(size 1.27 1.27)
					(thickness 0.15)
				)
				(justify mirror)
			)
		)
		(property "MPN" "ERJ2GE0R00X"
			(at 0 0 270)
			(unlocked yes)
			(layer "B.Fab")
			(hide yes)
			(effects
				(font
					(size 1 1)
					(thickness 0.15)
				)
				(justify mirror)
			)
		)
		(property "Manufacturer" "Panasonic"
			(at 0 0 270)
			(unlocked yes)
			(layer "B.Fab")
			(hide yes)
			(effects
				(font
					(size 1 1)
					(thickness 0.15)
				)
				(justify mirror)
			)
		)
		(property "License" "Apache-2.0"
			(at 0 0 270)
			(unlocked yes)
			(layer "B.Fab")
			(hide yes)
			(effects
				(font
					(size 1 1)
					(thickness 0.15)
				)
				(justify mirror)
			)
		)
		(property "Author" "Antmicro"
			(at 0 0 270)
			(unlocked yes)
			(layer "B.Fab")
			(hide yes)
			(effects
				(font
					(size 1 1)
					(thickness 0.15)
				)
				(justify mirror)
			)
		)
		(property "Val" "0R"
			(at 0 0 270)
			(unlocked yes)
			(layer "B.Fab")
			(hide yes)
			(effects
				(font
					(size 1 1)
					(thickness 0.15)
				)
				(justify mirror)
			)
		)
		(property "Tolerance" "~"
			(at 0 0 270)
			(unlocked yes)
			(layer "B.Fab")
			(hide yes)
			(effects
				(font
					(size 1 1)
					(thickness 0.15)
				)
				(justify mirror)
			)
		)
		(property "Current" "1A"
			(at 0 0 270)
			(unlocked yes)
			(layer "B.Fab")
			(hide yes)
			(effects
				(font
					(size 1 1)
					(thickness 0.15)
				)
				(justify mirror)
			)
		)
		(sheetname "/USB Debug, PD/")
		(sheetfile "usb_debug_pd.kicad_sch")
		(attr smd exclude_from_pos_files exclude_from_bom dnp)
		(fp_rect
			(start -0.925 0.47)
			(end 0.925 -0.47)
			(stroke
				(width 0.05)
				(type default)
			)
			(fill no)
			(layer "B.CrtYd")
		)
		(fp_rect
			(start -0.5 0.25)
			(end 0.5 -0.25)
			(stroke
				(width 0.15)
				(type solid)
			)
			(fill no)
			(layer "B.Fab")
		)
		(fp_text user "Author: Antmicro"
			(at -0.95 -4.169 90)
			(layer "B.Fab")
			(effects
				(font
					(size 0.7 0.7)
					(thickness 0.15)
				)
				(justify right top mirror)
			)
		)
		(fp_text user "License: Apache-2.0"
			(at -0.95 -5.169 90)
			(layer "B.Fab")
			(effects
				(font
					(size 0.7 0.7)
					(thickness 0.15)
				)
				(justify right top mirror)
			)
		)
		(fp_text user "${REFERENCE}"
			(at -0.95 -3.168 90)
			(layer "B.Fab")
			(effects
				(font
					(size 0.7 0.7)
					(thickness 0.15)
				)
				(justify right top mirror)
			)
		)
		(pad "1" smd roundrect
			(at -0.48 0 90)
			(size 0.59 0.64)
			(layers "B.Cu" "B.Mask" "B.Paste")
			(roundrect_rratio 0.25)
			(net 811 "/USB Debug, PD/MOSI")
			(pintype "passive")
		)
		(pad "2" smd roundrect
			(at 0.48 0 90)
			(size 0.59 0.64)
			(layers "B.Cu" "B.Mask" "B.Paste")
			(roundrect_rratio 0.25)
			(net 926 "/USB Debug, PD/SPI_{HUB_DEBUG}.MOSI")
			(pintype "passive")
		)
	)
	(footprint "antmicro-footprints:R_0402_1005Metric"
		(layer "B.Cu")
		(at 148.723313 149.115 90)
		(descr "Resistor SMD 0402")
		(tags "resistor SMD 0402")
		(property "Reference" "R6"
			(at -0.685 0.676687 90)
			(layer "B.SilkS")
			(effects
				(font
					(size 0.7 0.7)
					(thickness 0.15)
				)
				(justify right top mirror)
			)
		)
		(property "Value" "R_2k2_0402"
			(at -1.011843 -1.772046 90)
			(layer "B.Fab")
			(effects
				(font
					(size 0.7 0.7)
					(thickness 0.15)
				)
				(justify right top mirror)
			)
		)
		(property "Datasheet" "https://www.bourns.com/docs/product-datasheets/cr.pdf"
			(at 0 0 90)
			(layer "B.Fab")
			(hide yes)
			(effects
				(font
					(size 1.27 1.27)
					(thickness 0.15)
				)
				(justify mirror)
			)
		)
		(property "Description" "SMD Chip Resistor, 2.2 kohm, ± 1%, 62.5 mW, 0402 [1005 Metric], Thick Film, General Purpose"
			(at 0 0 90)
			(layer "B.Fab")
			(hide yes)
			(effects
				(font
					(size 1.27 1.27)
					(thickness 0.15)
				)
				(justify mirror)
			)
		)
		(property "Manufacturer" "Bourns"
			(at 0 0 270)
			(unlocked yes)
			(layer "B.Fab")
			(hide yes)
			(effects
				(font
					(size 1 1)
					(thickness 0.15)
				)
				(justify mirror)
			)
		)
		(property "MPN" "CR0402-FX-2201GLF"
			(at 0 0 270)
			(unlocked yes)
			(layer "B.Fab")
			(hide yes)
			(effects
				(font
					(size 1 1)
					(thickness 0.15)
				)
				(justify mirror)
			)
		)
		(property "Val" "2k2"
			(at 0 0 270)
			(unlocked yes)
			(layer "B.Fab")
			(hide yes)
			(effects
				(font
					(size 1 1)
					(thickness 0.15)
				)
				(justify mirror)
			)
		)
		(property "License" "Apache-2.0"
			(at 0 0 270)
			(unlocked yes)
			(layer "B.Fab")
			(hide yes)
			(effects
				(font
					(size 1 1)
					(thickness 0.15)
				)
				(justify mirror)
			)
		)
		(property "Author" "Antmicro"
			(at 0 0 270)
			(unlocked yes)
			(layer "B.Fab")
			(hide yes)
			(effects
				(font
					(size 1 1)
					(thickness 0.15)
				)
				(justify mirror)
			)
		)
		(property "Tolerance" "1%"
			(at 0 0 270)
			(unlocked yes)
			(layer "B.Fab")
			(hide yes)
			(effects
				(font
					(size 1 1)
					(thickness 0.15)
				)
				(justify mirror)
			)
		)
		(sheetname "/SoM_Power/")
		(sheetfile "som_power.kicad_sch")
		(attr smd)
		(fp_poly
			(pts
				(xy -0.925 0.47) (xy -0.925 -0.47) (xy 0.925 -0.47) (xy 0.925 0.47)
			)
			(stroke
				(width 0.05)
				(type default)
			)
			(fill no)
			(layer "B.CrtYd")
		)
		(fp_poly
			(pts
				(xy -0.5 0.25) (xy -0.5 -0.25) (xy 0.5 -0.25) (xy 0.5 0.25)
			)
			(stroke
				(width 0.15)
				(type solid)
			)
			(fill no)
			(layer "B.Fab")
		)
		(fp_text user "Author: Antmicro"
			(at -0.95 -4.169 90)
			(layer "B.Fab")
			(effects
				(font
					(size 0.7 0.7)
					(thickness 0.15)
				)
				(justify right top mirror)
			)
		)
		(fp_text user "${REFERENCE}"
			(at -0.95 -3.168 90)
			(layer "B.Fab")
			(effects
				(font
					(size 0.7 0.7)
					(thickness 0.15)
				)
				(justify right top mirror)
			)
		)
		(fp_text user "License: Apache-2.0"
			(at -0.949999 -5.169 90)
			(layer "B.Fab")
			(effects
				(font
					(size 0.7 0.7)
					(thickness 0.15)
				)
				(justify right top mirror)
			)
		)
		(pad "1" smd roundrect
			(at -0.48 0 90)
			(size 0.59 0.64)
			(layers "B.Cu" "B.Mask" "B.Paste")
			(roundrect_rratio 0.25)
			(net 10 "Net-(BT1-+)")
			(pintype "passive")
		)
		(pad "2" smd roundrect
			(at 0.48 0 90)
			(size 0.59 0.64)
			(layers "B.Cu" "B.Mask" "B.Paste")
			(roundrect_rratio 0.25)
			(net 32 "Net-(D1-C)")
			(pintype "passive")
		)
	)
	(footprint "antmicro-footprints:R_0402_1005Metric"
		(layer "B.Cu")
		(at 71.1 65.3)
		(descr "Resistor SMD 0402")
		(tags "resistor SMD 0402")
		(property "Reference" "R397"
			(at 0.9 -0.3 0)
			(layer "B.SilkS")
			(effects
				(font
					(size 0.7 0.7)
					(thickness 0.15)
				)
				(justify right top mirror)
			)
		)
		(property "Value" "R_0R_0402"
			(at -1.011843 -1.772047 0)
			(layer "B.Fab")
			(effects
				(font
					(size 0.7 0.7)
					(thickness 0.15)
				)
				(justify right top mirror)
			)
		)
		(property "Datasheet" "https://industrial.panasonic.com/cdbs/www-data/pdf/RDA0000/AOA0000C301.pdf"
			(at 0 0 0)
			(layer "B.Fab")
			(hide yes)
			(effects
				(font
					(size 1.27 1.27)
					(thickness 0.15)
				)
				(justify mirror)
			)
		)
		(property "Description" "SMD Chip Resistor, Jumper, 0 ohm, 100 mW, 0402 [1005 Metric], Thick Film, General Purpose"
			(at 0 0 0)
			(layer "B.Fab")
			(hide yes)
			(effects
				(font
					(size 1.27 1.27)
					(thickness 0.15)
				)
				(justify mirror)
			)
		)
		(property "MPN" "ERJ2GE0R00X"
			(at 0 0 180)
			(unlocked yes)
			(layer "B.Fab")
			(hide yes)
			(effects
				(font
					(size 1 1)
					(thickness 0.15)
				)
				(justify mirror)
			)
		)
		(property "Manufacturer" "Panasonic"
			(at 0 0 180)
			(unlocked yes)
			(layer "B.Fab")
			(hide yes)
			(effects
				(font
					(size 1 1)
					(thickness 0.15)
				)
				(justify mirror)
			)
		)
		(property "License" "Apache-2.0"
			(at 0 0 180)
			(unlocked yes)
			(layer "B.Fab")
			(hide yes)
			(effects
				(font
					(size 1 1)
					(thickness 0.15)
				)
				(justify mirror)
			)
		)
		(property "Author" "Antmicro"
			(at 0 0 180)
			(unlocked yes)
			(layer "B.Fab")
			(hide yes)
			(effects
				(font
					(size 1 1)
					(thickness 0.15)
				)
				(justify mirror)
			)
		)
		(property "Val" "0R"
			(at 0 0 180)
			(unlocked yes)
			(layer "B.Fab")
			(hide yes)
			(effects
				(font
					(size 1 1)
					(thickness 0.15)
				)
				(justify mirror)
			)
		)
		(property "Tolerance" "~"
			(at 0 0 180)
			(unlocked yes)
			(layer "B.Fab")
			(hide yes)
			(effects
				(font
					(size 1 1)
					(thickness 0.15)
				)
				(justify mirror)
			)
		)
		(property "Current" "1A"
			(at 0 0 180)
			(unlocked yes)
			(layer "B.Fab")
			(hide yes)
			(effects
				(font
					(size 1 1)
					(thickness 0.15)
				)
				(justify mirror)
			)
		)
		(sheetname "/CSI/")
		(sheetfile "csi.kicad_sch")
		(attr smd)
		(fp_rect
			(start -0.925 0.47)
			(end 0.925 -0.47)
			(stroke
				(width 0.05)
				(type default)
			)
			(fill no)
			(layer "B.CrtYd")
		)
		(fp_rect
			(start -0.5 0.25)
			(end 0.5 -0.25)
			(stroke
				(width 0.15)
				(type solid)
			)
			(fill no)
			(layer "B.Fab")
		)
		(fp_text user "${REFERENCE}"
			(at -0.95 -3.168 0)
			(layer "B.Fab")
			(effects
				(font
					(size 0.7 0.7)
					(thickness 0.15)
				)
				(justify right top mirror)
			)
		)
		(fp_text user "Author: Antmicro"
			(at -0.95 -4.169 0)
			(layer "B.Fab")
			(effects
				(font
					(size 0.7 0.7)
					(thickness 0.15)
				)
				(justify right top mirror)
			)
		)
		(fp_text user "License: Apache-2.0"
			(at -0.95 -5.169 0)
			(layer "B.Fab")
			(effects
				(font
					(size 0.7 0.7)
					(thickness 0.15)
				)
				(justify right top mirror)
			)
		)
		(pad "1" smd roundrect
			(at -0.48 0)
			(size 0.59 0.64)
			(layers "B.Cu" "B.Mask" "B.Paste")
			(roundrect_rratio 0.25)
			(net 991 "/CSI/SDA_CAM3")
			(pintype "passive")
		)
		(pad "2" smd roundrect
			(at 0.48 0)
			(size 0.59 0.64)
			(layers "B.Cu" "B.Mask" "B.Paste")
			(roundrect_rratio 0.25)
			(net 937 "Net-(J10-Pad41)")
			(pintype "passive")
		)
	)
	(footprint "antmicro-footprints:LED_0603_1608Metric_G"
		(layer "B.Cu")
		(at 226 54.75 180)
		(descr "LED SMD 0603 Green")
		(tags "LED SMD 0603 Green")
		(property "Reference" "D26"
			(at -3.5 -0.37 0)
			(layer "B.SilkS")
			(effects
				(font
					(size 0.7 0.7)
					(thickness 0.15)
				)
				(justify left bottom mirror)
			)
		)
		(property "Value" "LED_G_0603_LTST-C190GKT"
			(at -0.001 -1.599 0)
			(layer "B.Fab")
			(effects
				(font
					(size 0.7 0.7)
					(thickness 0.15)
				)
				(justify left bottom mirror)
			)
		)
		(property "Datasheet" "https://media.digikey.com/pdf/Data%20Sheets/Lite-On%20PDFs/LTST-C190GKT.pdf"
			(at 0 0 0)
			(layer "B.Fab")
			(hide yes)
			(effects
				(font
					(size 1.27 1.27)
					(thickness 0.15)
				)
				(justify mirror)
			)
		)
		(property "Description" "LED, Green, SMD, 0603, 20 mA, 2.1 V, 569 nm"
			(at 0 0 0)
			(layer "B.Fab")
			(hide yes)
			(effects
				(font
					(size 1.27 1.27)
					(thickness 0.15)
				)
				(justify mirror)
			)
		)
		(property "MPN" "LTST-C190GKT"
			(at 0 0 0)
			(unlocked yes)
			(layer "B.Fab")
			(hide yes)
			(effects
				(font
					(size 1 1)
					(thickness 0.15)
				)
				(justify mirror)
			)
		)
		(property "Manufacturer" "Lite-On"
			(at 0 0 0)
			(unlocked yes)
			(layer "B.Fab")
			(hide yes)
			(effects
				(font
					(size 1 1)
					(thickness 0.15)
				)
				(justify mirror)
			)
		)
		(property "Author" "Antmicro"
			(at 0 0 0)
			(unlocked yes)
			(layer "B.Fab")
			(hide yes)
			(effects
				(font
					(size 1 1)
					(thickness 0.15)
				)
				(justify mirror)
			)
		)
		(property "License" "Apache-2.0"
			(at 0 0 0)
			(unlocked yes)
			(layer "B.Fab")
			(hide yes)
			(effects
				(font
					(size 1 1)
					(thickness 0.15)
				)
				(justify mirror)
			)
		)
		(property "Color" "Green"
			(at 0 0 0)
			(unlocked yes)
			(layer "B.Fab")
			(hide yes)
			(effects
				(font
					(size 1 1)
					(thickness 0.15)
				)
				(justify mirror)
			)
		)
		(sheetname "/CSI/")
		(sheetfile "csi.kicad_sch")
		(attr smd)
		(fp_line
			(start 0.22 0.35)
			(end -0.22 0.35)
			(stroke
				(width 0.15)
				(type solid)
			)
			(layer "B.SilkS")
		)
		(fp_line
			(start 0.22 -0.35)
			(end -0.22 -0.35)
			(stroke
				(width 0.15)
				(type solid)
			)
			(layer "B.SilkS")
		)
		(fp_line
			(start 0.105328 -0.001008)
			(end 0.240001 -0.001)
			(stroke
				(width 0.1)
				(type solid)
			)
			(layer "B.SilkS")
		)
		(fp_line
			(start 0.105328 -0.201008)
			(end 0.105329 0.198992)
			(stroke
				(width 0.1)
				(type solid)
			)
			(layer "B.SilkS")
		)
		(fp_line
			(start 0.105328 -0.201008)
			(end -0.094672 -0.001008)
			(stroke
				(width 0.1)
				(type solid)
			)
			(layer "B.SilkS")
		)
		(fp_line
			(start -0.094672 -0.001008)
			(end 0.105329 0.198992)
			(stroke
				(width 0.1)
				(type solid)
			)
			(layer "B.SilkS")
		)
		(fp_line
			(start -0.094672 -0.001008)
			(end -0.24 -0.001008)
			(stroke
				(width 0.1)
				(type solid)
			)
			(layer "B.SilkS")
		)
		(fp_line
			(start -0.094672 -0.201008)
			(end -0.094672 0.198992)
			(stroke
				(width 0.1)
				(type solid)
			)
			(layer "B.SilkS")
		)
		(fp_line
			(start -1.18 0.319)
			(end -1.18 -0.321)
			(stroke
				(width 0.15)
				(type solid)
			)
			(layer "B.SilkS")
		)
		(fp_poly
			(pts
				(xy 1.25 -0.65) (xy 1.25 0.65) (xy -1.25 0.65) (xy -1.25 -0.65)
			)
			(stroke
				(width 0.05)
				(type solid)
			)
			(fill no)
			(layer "B.CrtYd")
		)
		(fp_line
			(start 0.599 0)
			(end 0.200999 0)
			(stroke
				(width 0.15)
				(type solid)
			)
			(layer "B.Fab")
		)
		(fp_line
			(start 0.201 0.202)
			(end -0.101 0)
			(stroke
				(width 0.15)
				(type solid)
			)
			(layer "B.Fab")
		)
		(fp_line
			(start 0.201 -0.2)
			(end 0.200999 0)
			(stroke
				(width 0.15)
				(type solid)
			)
			(layer "B.Fab")
		)
		(fp_line
			(start 0.200999 0)
			(end 0.201 0.202)
			(stroke
				(width 0.15)
				(type solid)
			)
			(layer "B.Fab")
		)
		(fp_line
			(start -0.101 0)
			(end 0.201 -0.2)
			(stroke
				(width 0.15)
				(type solid)
			)
			(layer "B.Fab")
		)
		(fp_line
			(start -0.199 0.202)
			(end -0.199 -0.1)
			(stroke
				(width 0.15)
				(type solid)
			)
			(layer "B.Fab")
		)
		(fp_line
			(start -0.199 0)
			(end -0.597 0)
			(stroke
				(width 0.15)
				(type solid)
			)
			(layer "B.Fab")
		)
		(fp_line
			(start -0.199 -0.2)
			(end -0.199 -0.1)
			(stroke
				(width 0.15)
				(type solid)
			)
			(layer "B.Fab")
		)
		(fp_poly
			(pts
				(xy 0.848 -0.4) (xy 0.848 0.401999) (xy -0.85 0.402) (xy -0.85 -0.4)
			)
			(stroke
				(width 0.15)
				(type solid)
			)
			(fill no)
			(layer "B.Fab")
		)
		(fp_text user "Author: Antmicro"
			(at -1.4224 -4.799 0)
			(layer "B.Fab")
			(effects
				(font
					(size 0.7 0.7)
					(thickness 0.15)
				)
				(justify left bottom mirror)
			)
		)
		(fp_text user "${REFERENCE}"
			(at -1.4224 -5.999 0)
			(layer "B.Fab")
			(effects
				(font
					(size 0.7 0.7)
					(thickness 0.15)
				)
				(justify left bottom mirror)
			)
		)
		(fp_text user "License: Apache-2.0"
			(at -1.4224 -3.599 0)
			(layer "B.Fab")
			(effects
				(font
					(size 0.7 0.7)
					(thickness 0.15)
				)
				(justify left bottom mirror)
			)
		)
		(pad "1" smd roundrect
			(at -0.7 0)
			(size 0.8 1)
			(layers "B.Cu" "B.Mask" "B.Paste")
			(roundrect_rratio 0.2)
			(net 1 "GND")
			(pinfunction "C")
			(pintype "passive")
		)
		(pad "2" smd roundrect
			(at 0.7 0)
			(size 0.8 1)
			(layers "B.Cu" "B.Mask" "B.Paste")
			(roundrect_rratio 0.2)
			(net 539 "Net-(D26-A)")
			(pinfunction "A")
			(pintype "passive")
		)
	)
	(footprint "antmicro-footprints:TP_SMD_0.75mm"
		(layer "B.Cu")
		(at 196.4 118.4 90)
		(property "Reference" "TP70"
			(at 0.4 -3.2 0)
			(layer "B.SilkS")
			(effects
				(font
					(size 0.7 0.7)
					(thickness 0.15)
				)
				(justify right top mirror)
			)
		)
		(property "Value" "TP_0.75mm_SMD"
			(at 0 -1.2 90)
			(layer "B.Fab")
			(effects
				(font
					(size 0.7 0.7)
					(thickness 0.15)
				)
				(justify right top mirror)
			)
		)
		(property "Description" "SMT test point"
			(at 0 0 90)
			(layer "B.Fab")
			(hide yes)
			(effects
				(font
					(size 1.27 1.27)
					(thickness 0.15)
				)
				(justify mirror)
			)
		)
		(property "MPN" ""
			(at 0 0 270)
			(unlocked yes)
			(layer "B.Fab")
			(hide yes)
			(effects
				(font
					(size 1 1)
					(thickness 0.15)
				)
				(justify mirror)
			)
		)
		(property "Manufacturer" ""
			(at 0 0 270)
			(unlocked yes)
			(layer "B.Fab")
			(hide yes)
			(effects
				(font
					(size 1 1)
					(thickness 0.15)
				)
				(justify mirror)
			)
		)
		(property "Author" "Antmicro"
			(at 0 0 270)
			(unlocked yes)
			(layer "B.Fab")
			(hide yes)
			(effects
				(font
					(size 1 1)
					(thickness 0.15)
				)
				(justify mirror)
			)
		)
		(property "License" "Apache-2.0"
			(at 0 0 270)
			(unlocked yes)
			(layer "B.Fab")
			(hide yes)
			(effects
				(font
					(size 1 1)
					(thickness 0.15)
				)
				(justify mirror)
			)
		)
		(sheetname "/USB Hub/")
		(sheetfile "usb_hub.kicad_sch")
		(attr exclude_from_pos_files exclude_from_bom)
		(fp_circle
			(center 0 0)
			(end 0.475 0)
			(stroke
				(width 0.05)
				(type default)
			)
			(fill no)
			(layer "B.CrtYd")
		)
		(fp_text user "${REFERENCE}"
			(at -0.4 -2.7 90)
			(layer "B.Fab")
			(effects
				(font
					(size 0.7 0.7)
					(thickness 0.15)
				)
				(justify right top mirror)
			)
		)
		(fp_text user "Author: Antmicro"
			(at -0.4 -3.901 90)
			(layer "B.Fab")
			(effects
				(font
					(size 0.7 0.7)
					(thickness 0.15)
				)
				(justify right top mirror)
			)
		)
		(fp_text user "License: Apache-2.0"
			(at -0.4 -5.101 90)
			(layer "B.Fab")
			(effects
				(font
					(size 0.7 0.7)
					(thickness 0.15)
				)
				(justify right top mirror)
			)
		)
		(pad "1" smd circle
			(at 0 0 90)
			(size 0.75 0.75)
			(layers "B.Cu" "B.Mask")
			(net 1106 "/USB Hub/DP2_VCONN2")
			(pinfunction "1")
			(pintype "passive")
		)
	)
	(footprint "antmicro-footprints:R_0402_1005Metric"
		(layer "B.Cu")
		(at 124.6 106.8 180)
		(descr "Resistor SMD 0402")
		(tags "resistor SMD 0402")
		(property "Reference" "R206"
			(at -3.9 -0.36 0)
			(layer "B.SilkS")
			(effects
				(font
					(size 0.7 0.7)
					(thickness 0.15)
				)
				(justify left bottom mirror)
			)
		)
		(property "Value" "R_0R_0402"
			(at -1.011843 -1.772046 0)
			(layer "B.Fab")
			(effects
				(font
					(size 0.7 0.7)
					(thickness 0.15)
				)
				(justify left bottom mirror)
			)
		)
		(property "Datasheet" "https://industrial.panasonic.com/cdbs/www-data/pdf/RDA0000/AOA0000C301.pdf"
			(at 0 0 0)
			(layer "B.Fab")
			(hide yes)
			(effects
				(font
					(size 1.27 1.27)
					(thickness 0.15)
				)
				(justify mirror)
			)
		)
		(property "Description" "SMD Chip Resistor, Jumper, 0 ohm, 100 mW, 0402 [1005 Metric], Thick Film, General Purpose"
			(at 0 0 0)
			(layer "B.Fab")
			(hide yes)
			(effects
				(font
					(size 1.27 1.27)
					(thickness 0.15)
				)
				(justify mirror)
			)
		)
		(property "MPN" "ERJ2GE0R00X"
			(at 0 0 0)
			(unlocked yes)
			(layer "B.Fab")
			(hide yes)
			(effects
				(font
					(size 1 1)
					(thickness 0.15)
				)
				(justify mirror)
			)
		)
		(property "Manufacturer" "Panasonic"
			(at 0 0 0)
			(unlocked yes)
			(layer "B.Fab")
			(hide yes)
			(effects
				(font
					(size 1 1)
					(thickness 0.15)
				)
				(justify mirror)
			)
		)
		(property "License" "Apache-2.0"
			(at 0 0 0)
			(unlocked yes)
			(layer "B.Fab")
			(hide yes)
			(effects
				(font
					(size 1 1)
					(thickness 0.15)
				)
				(justify mirror)
			)
		)
		(property "Author" "Antmicro"
			(at 0 0 0)
			(unlocked yes)
			(layer "B.Fab")
			(hide yes)
			(effects
				(font
					(size 1 1)
					(thickness 0.15)
				)
				(justify mirror)
			)
		)
		(property "Val" "0R"
			(at 0 0 0)
			(unlocked yes)
			(layer "B.Fab")
			(hide yes)
			(effects
				(font
					(size 1 1)
					(thickness 0.15)
				)
				(justify mirror)
			)
		)
		(property "Tolerance" "~"
			(at 0 0 0)
			(unlocked yes)
			(layer "B.Fab")
			(hide yes)
			(effects
				(font
					(size 1 1)
					(thickness 0.15)
				)
				(justify mirror)
			)
		)
		(property "Current" "1A"
			(at 0 0 0)
			(unlocked yes)
			(layer "B.Fab")
			(hide yes)
			(effects
				(font
					(size 1 1)
					(thickness 0.15)
				)
				(justify mirror)
			)
		)
		(sheetname "/M.2/")
		(sheetfile "m2.kicad_sch")
		(attr smd)
		(fp_poly
			(pts
				(xy -0.925 0.47) (xy 0.925 0.47) (xy 0.925 -0.47) (xy -0.925 -0.47)
			)
			(stroke
				(width 0.05)
				(type default)
			)
			(fill no)
			(layer "B.CrtYd")
		)
		(fp_poly
			(pts
				(xy -0.5 0.25) (xy 0.5 0.25) (xy 0.5 -0.25) (xy -0.5 -0.25)
			)
			(stroke
				(width 0.15)
				(type solid)
			)
			(fill no)
			(layer "B.Fab")
		)
		(fp_text user "Author: Antmicro"
			(at -0.95 -4.169 0)
			(layer "B.Fab")
			(effects
				(font
					(size 0.7 0.7)
					(thickness 0.15)
				)
				(justify left bottom mirror)
			)
		)
		(fp_text user "License: Apache-2.0"
			(at -0.949999 -5.169 0)
			(layer "B.Fab")
			(effects
				(font
					(size 0.7 0.7)
					(thickness 0.15)
				)
				(justify left bottom mirror)
			)
		)
		(fp_text user "${REFERENCE}"
			(at -0.95 -3.168 0)
			(layer "B.Fab")
			(effects
				(font
					(size 0.7 0.7)
					(thickness 0.15)
				)
				(justify left bottom mirror)
			)
		)
		(pad "1" smd roundrect
			(at -0.48 0 180)
			(size 0.59 0.64)
			(layers "B.Cu" "B.Mask" "B.Paste")
			(roundrect_rratio 0.25)
			(net 775 "/M.2/PCIe_{C5x4}.~{RST}")
			(pintype "passive")
		)
		(pad "2" smd roundrect
			(at 0.48 0 180)
			(size 0.59 0.64)
			(layers "B.Cu" "B.Mask" "B.Paste")
			(roundrect_rratio 0.25)
			(net 827 "/M.2/~{PERST_M}")
			(pintype "passive")
		)
	)
	(footprint "antmicro-footprints:R_0402_1005Metric"
		(layer "B.Cu")
		(at 207 63.453001)
		(descr "Resistor SMD 0402")
		(tags "resistor SMD 0402")
		(property "Reference" "R175"
			(at -3.77 -0.48 0)
			(layer "B.SilkS")
			(effects
				(font
					(size 0.7 0.7)
					(thickness 0.15)
				)
				(justify right top mirror)
			)
		)
		(property "Value" "R_100k_0402"
			(at -1.011843 -1.772046 0)
			(layer "B.Fab")
			(effects
				(font
					(size 0.7 0.7)
					(thickness 0.15)
				)
				(justify right top mirror)
			)
		)
		(property "Datasheet" "https://www.bourns.com/docs/product-datasheets/cr.pdf"
			(at 0 0 0)
			(layer "B.Fab")
			(hide yes)
			(effects
				(font
					(size 1.27 1.27)
					(thickness 0.15)
				)
				(justify mirror)
			)
		)
		(property "Description" "SMD Chip Resistor, 100 kohm, ± 1%, 62.5 mW, 0402 [1005 Metric], Thick Film, General Purpose"
			(at 0 0 0)
			(layer "B.Fab")
			(hide yes)
			(effects
				(font
					(size 1.27 1.27)
					(thickness 0.15)
				)
				(justify mirror)
			)
		)
		(property "Manufacturer" "Bourns"
			(at 0 0 180)
			(unlocked yes)
			(layer "B.Fab")
			(hide yes)
			(effects
				(font
					(size 1 1)
					(thickness 0.15)
				)
				(justify mirror)
			)
		)
		(property "MPN" "CR0402-FX-1003GLF"
			(at 0 0 180)
			(unlocked yes)
			(layer "B.Fab")
			(hide yes)
			(effects
				(font
					(size 1 1)
					(thickness 0.15)
				)
				(justify mirror)
			)
		)
		(property "Val" "100k"
			(at 0 0 180)
			(unlocked yes)
			(layer "B.Fab")
			(hide yes)
			(effects
				(font
					(size 1 1)
					(thickness 0.15)
				)
				(justify mirror)
			)
		)
		(property "License" "Apache-2.0"
			(at 0 0 180)
			(unlocked yes)
			(layer "B.Fab")
			(hide yes)
			(effects
				(font
					(size 1 1)
					(thickness 0.15)
				)
				(justify mirror)
			)
		)
		(property "Author" "Antmicro"
			(at 0 0 180)
			(unlocked yes)
			(layer "B.Fab")
			(hide yes)
			(effects
				(font
					(size 1 1)
					(thickness 0.15)
				)
				(justify mirror)
			)
		)
		(property "Tolerance" "1%"
			(at 0 0 180)
			(unlocked yes)
			(layer "B.Fab")
			(hide yes)
			(effects
				(font
					(size 1 1)
					(thickness 0.15)
				)
				(justify mirror)
			)
		)
		(sheetname "/CSI/")
		(sheetfile "csi.kicad_sch")
		(attr smd)
		(fp_poly
			(pts
				(xy -0.925 0.47) (xy -0.925 -0.47) (xy 0.925 -0.47) (xy 0.925 0.47)
			)
			(stroke
				(width 0.05)
				(type default)
			)
			(fill no)
			(layer "B.CrtYd")
		)
		(fp_poly
			(pts
				(xy -0.5 0.25) (xy -0.5 -0.25) (xy 0.5 -0.25) (xy 0.5 0.25)
			)
			(stroke
				(width 0.15)
				(type solid)
			)
			(fill no)
			(layer "B.Fab")
		)
		(fp_text user "License: Apache-2.0"
			(at -0.949999 -5.169 0)
			(layer "B.Fab")
			(effects
				(font
					(size 0.7 0.7)
					(thickness 0.15)
				)
				(justify right top mirror)
			)
		)
		(fp_text user "${REFERENCE}"
			(at -0.95 -3.168 0)
			(layer "B.Fab")
			(effects
				(font
					(size 0.7 0.7)
					(thickness 0.15)
				)
				(justify right top mirror)
			)
		)
		(fp_text user "Author: Antmicro"
			(at -0.95 -4.169 0)
			(layer "B.Fab")
			(effects
				(font
					(size 0.7 0.7)
					(thickness 0.15)
				)
				(justify right top mirror)
			)
		)
		(pad "1" smd roundrect
			(at -0.48 0)
			(size 0.59 0.64)
			(layers "B.Cu" "B.Mask" "B.Paste")
			(roundrect_rratio 0.25)
			(net 1 "GND")
			(pintype "passive")
		)
		(pad "2" smd roundrect
			(at 0.48 0)
			(size 0.59 0.64)
			(layers "B.Cu" "B.Mask" "B.Paste")
			(roundrect_rratio 0.25)
			(net 123 "/CSI/CAM_CTRL.CSIB_PEN")
			(pintype "passive")
		)
	)
	(footprint "antmicro-footprints:C_0402_1005Metric"
		(layer "B.Cu")
		(at 199.41 64.82)
		(descr "Capacitor SMD 0402")
		(tags "capacitor SMD 0402")
		(property "Reference" "C167"
			(at -1.41 -1.362 0)
			(layer "B.SilkS")
			(effects
				(font
					(size 0.7 0.7)
					(thickness 0.15)
				)
				(justify right top mirror)
			)
		)
		(property "Value" "C_100n_0402"
			(at -1.022927 -2.155213 0)
			(layer "B.Fab")
			(effects
				(font
					(size 0.7 0.7)
					(thickness 0.15)
				)
				(justify right top mirror)
			)
		)
		(property "Datasheet" "https://www.murata.com/products/productdetail?partno=GRM155R61H104KE14%23"
			(at 0 0 0)
			(layer "B.Fab")
			(hide yes)
			(effects
				(font
					(size 1.27 1.27)
					(thickness 0.15)
				)
				(justify mirror)
			)
		)
		(property "Description" "SMD Multilayer Ceramic Capacitor, 0.1 µF, 50 V, 0402 [1005 Metric], ± 10%, X5R, GRM Series"
			(at 0 0 0)
			(layer "B.Fab")
			(hide yes)
			(effects
				(font
					(size 1.27 1.27)
					(thickness 0.15)
				)
				(justify mirror)
			)
		)
		(property "Manufacturer" "Murata"
			(at 0 0 180)
			(unlocked yes)
			(layer "B.Fab")
			(hide yes)
			(effects
				(font
					(size 1 1)
					(thickness 0.15)
				)
				(justify mirror)
			)
		)
		(property "MPN" "GRM155R61H104KE14D"
			(at 0 0 180)
			(unlocked yes)
			(layer "B.Fab")
			(hide yes)
			(effects
				(font
					(size 1 1)
					(thickness 0.15)
				)
				(justify mirror)
			)
		)
		(property "Val" "100n"
			(at 0 0 180)
			(unlocked yes)
			(layer "B.Fab")
			(hide yes)
			(effects
				(font
					(size 1 1)
					(thickness 0.15)
				)
				(justify mirror)
			)
		)
		(property "License" "Apache-2.0"
			(at 0 0 180)
			(unlocked yes)
			(layer "B.Fab")
			(hide yes)
			(effects
				(font
					(size 1 1)
					(thickness 0.15)
				)
				(justify mirror)
			)
		)
		(property "Author" "Antmicro"
			(at 0 0 180)
			(unlocked yes)
			(layer "B.Fab")
			(hide yes)
			(effects
				(font
					(size 1 1)
					(thickness 0.15)
				)
				(justify mirror)
			)
		)
		(property "Voltage" "50V"
			(at 0 0 180)
			(unlocked yes)
			(layer "B.Fab")
			(hide yes)
			(effects
				(font
					(size 1 1)
					(thickness 0.15)
				)
				(justify mirror)
			)
		)
		(property "Dielectric" "X5R"
			(at 0 0 180)
			(unlocked yes)
			(layer "B.Fab")
			(hide yes)
			(effects
				(font
					(size 1 1)
					(thickness 0.15)
				)
				(justify mirror)
			)
		)
		(sheetname "/CSI/")
		(sheetfile "csi.kicad_sch")
		(attr smd)
		(fp_poly
			(pts
				(xy -0.925 0.47) (xy -0.925 -0.47) (xy 0.925 -0.47) (xy 0.925 0.47)
			)
			(stroke
				(width 0.05)
				(type default)
			)
			(fill no)
			(layer "B.CrtYd")
		)
		(fp_line
			(start -0.494 -0.248)
			(end -0.494 0.25)
			(stroke
				(width 0.15)
				(type solid)
			)
			(layer "B.Fab")
		)
		(fp_line
			(start -0.494 0.25)
			(end 0.504 0.25)
			(stroke
				(width 0.15)
				(type solid)
			)
			(layer "B.Fab")
		)
		(fp_line
			(start 0.504 -0.248)
			(end -0.494 -0.248)
			(stroke
				(width 0.15)
				(type solid)
			)
			(layer "B.Fab")
		)
		(fp_line
			(start 0.504 0.25)
			(end 0.504 -0.248)
			(stroke
				(width 0.15)
				(type solid)
			)
			(layer "B.Fab")
		)
		(fp_text user "Author: Antmicro"
			(at -0.939 -3.399 0)
			(layer "B.Fab")
			(effects
				(font
					(size 0.7 0.7)
					(thickness 0.15)
				)
				(justify right top mirror)
			)
		)
		(fp_text user "${REFERENCE}"
			(at -0.939 -4.599 0)
			(layer "B.Fab")
			(effects
				(font
					(size 0.7 0.7)
					(thickness 0.15)
				)
				(justify right top mirror)
			)
		)
		(fp_text user "License: Apache-2.0"
			(at -0.939 -5.799 0)
			(layer "B.Fab")
			(effects
				(font
					(size 0.7 0.7)
					(thickness 0.15)
				)
				(justify right top mirror)
			)
		)
		(pad "1" smd roundrect
			(at -0.48 0)
			(size 0.59 0.64)
			(layers "B.Cu" "B.Mask" "B.Paste")
			(roundrect_rratio 0.25)
			(net 1 "GND")
			(pintype "passive")
		)
		(pad "2" smd roundrect
			(at 0.48 0)
			(size 0.59 0.64)
			(layers "B.Cu" "B.Mask" "B.Paste")
			(roundrect_rratio 0.25)
			(net 2 "+3V3")
			(pintype "passive")
		)
	)
	(footprint "antmicro-footprints:C_0402_1005Metric"
		(layer "B.Cu")
		(at 180.23 93.1)
		(descr "Capacitor SMD 0402")
		(tags "capacitor SMD 0402")
		(property "Reference" "C261"
			(at -1.03 0.6 0)
			(layer "B.SilkS")
			(effects
				(font
					(size 0.7 0.7)
					(thickness 0.15)
				)
				(justify right top mirror)
			)
		)
		(property "Value" "C_1u_25V_0402"
			(at -1.022927 -2.155213 0)
			(layer "B.Fab")
			(effects
				(font
					(size 0.7 0.7)
					(thickness 0.15)
				)
				(justify right top mirror)
			)
		)
		(property "Datasheet" "https://www.murata.com/products/productdetail?partno=GRM155R61E105KE11%23"
			(at 0 0 0)
			(layer "B.Fab")
			(hide yes)
			(effects
				(font
					(size 1.27 1.27)
					(thickness 0.15)
				)
				(justify mirror)
			)
		)
		(property "Description" "SMD Multilayer Ceramic Capacitor, 1 µF, 25 V, 0402 [1005 Metric], ± 10%, X5R, GRM Series"
			(at 0 0 0)
			(layer "B.Fab")
			(hide yes)
			(effects
				(font
					(size 1.27 1.27)
					(thickness 0.15)
				)
				(justify mirror)
			)
		)
		(property "MPN" "GRM155R61E105KE11J"
			(at 0 0 180)
			(unlocked yes)
			(layer "B.Fab")
			(hide yes)
			(effects
				(font
					(size 1 1)
					(thickness 0.15)
				)
				(justify mirror)
			)
		)
		(property "Manufacturer" "Murata"
			(at 0 0 180)
			(unlocked yes)
			(layer "B.Fab")
			(hide yes)
			(effects
				(font
					(size 1 1)
					(thickness 0.15)
				)
				(justify mirror)
			)
		)
		(property "License" "Apache-2.0"
			(at 0 0 180)
			(unlocked yes)
			(layer "B.Fab")
			(hide yes)
			(effects
				(font
					(size 1 1)
					(thickness 0.15)
				)
				(justify mirror)
			)
		)
		(property "Author" "Antmicro"
			(at 0 0 180)
			(unlocked yes)
			(layer "B.Fab")
			(hide yes)
			(effects
				(font
					(size 1 1)
					(thickness 0.15)
				)
				(justify mirror)
			)
		)
		(property "Val" "1u"
			(at 0 0 180)
			(unlocked yes)
			(layer "B.Fab")
			(hide yes)
			(effects
				(font
					(size 1 1)
					(thickness 0.15)
				)
				(justify mirror)
			)
		)
		(property "Voltage" "25V"
			(at 0 0 180)
			(unlocked yes)
			(layer "B.Fab")
			(hide yes)
			(effects
				(font
					(size 1 1)
					(thickness 0.15)
				)
				(justify mirror)
			)
		)
		(property "Dielectric" "X5R"
			(at 0 0 180)
			(unlocked yes)
			(layer "B.Fab")
			(hide yes)
			(effects
				(font
					(size 1 1)
					(thickness 0.15)
				)
				(justify mirror)
			)
		)
		(sheetname "/Power/")
		(sheetfile "power.kicad_sch")
		(attr smd exclude_from_pos_files exclude_from_bom dnp)
		(fp_rect
			(start -0.925 0.47)
			(end 0.925 -0.47)
			(stroke
				(width 0.05)
				(type default)
			)
			(fill no)
			(layer "B.CrtYd")
		)
		(fp_line
			(start -0.494 -0.248)
			(end -0.494 0.25)
			(stroke
				(width 0.15)
				(type solid)
			)
			(layer "B.Fab")
		)
		(fp_line
			(start -0.494 0.25)
			(end 0.504 0.25)
			(stroke
				(width 0.15)
				(type solid)
			)
			(layer "B.Fab")
		)
		(fp_line
			(start 0.504 -0.248)
			(end -0.494 -0.248)
			(stroke
				(width 0.15)
				(type solid)
			)
			(layer "B.Fab")
		)
		(fp_line
			(start 0.504 0.25)
			(end 0.504 -0.248)
			(stroke
				(width 0.15)
				(type solid)
			)
			(layer "B.Fab")
		)
		(fp_text user "${REFERENCE}"
			(at -0.939 -4.599 0)
			(layer "B.Fab")
			(effects
				(font
					(size 0.7 0.7)
					(thickness 0.15)
				)
				(justify right top mirror)
			)
		)
		(fp_text user "Author: Antmicro"
			(at -0.939 -3.399 0)
			(layer "B.Fab")
			(effects
				(font
					(size 0.7 0.7)
					(thickness 0.15)
				)
				(justify right top mirror)
			)
		)
		(fp_text user "License: Apache-2.0"
			(at -0.939 -5.799 0)
			(layer "B.Fab")
			(effects
				(font
					(size 0.7 0.7)
					(thickness 0.15)
				)
				(justify right top mirror)
			)
		)
		(pad "1" smd roundrect
			(at -0.48 0)
			(size 0.59 0.64)
			(layers "B.Cu" "B.Mask" "B.Paste")
			(roundrect_rratio 0.25)
			(net 1 "GND")
			(pintype "passive")
		)
		(pad "2" smd roundrect
			(at 0.48 0)
			(size 0.59 0.64)
			(layers "B.Cu" "B.Mask" "B.Paste")
			(roundrect_rratio 0.25)
			(net 13 "VCC")
			(pintype "passive")
		)
	)
	(footprint "antmicro-footprints:R_0402_1005Metric"
		(layer "B.Cu")
		(at 205.395 104.79 180)
		(descr "Resistor SMD 0402")
		(tags "resistor SMD 0402")
		(property "Reference" "R280"
			(at -6.505 -0.46 0)
			(layer "B.SilkS")
			(effects
				(font
					(size 0.7 0.7)
					(thickness 0.15)
				)
				(justify left bottom mirror)
			)
		)
		(property "Value" "R_200k_0402"
			(at -1.011843 -1.772046 0)
			(layer "B.Fab")
			(effects
				(font
					(size 0.7 0.7)
					(thickness 0.15)
				)
				(justify left bottom mirror)
			)
		)
		(property "Datasheet" "https://www.bourns.com/docs/product-datasheets/cr.pdf"
			(at 0 0 0)
			(layer "B.Fab")
			(hide yes)
			(effects
				(font
					(size 1.27 1.27)
					(thickness 0.15)
				)
				(justify mirror)
			)
		)
		(property "Description" "SMD Chip Resistor, 200 kohm, ± 1%, 62.5 mW, 0402 [1005 Metric], Thick Film, General Purpose"
			(at 0 0 0)
			(layer "B.Fab")
			(hide yes)
			(effects
				(font
					(size 1.27 1.27)
					(thickness 0.15)
				)
				(justify mirror)
			)
		)
		(property "Manufacturer" "Bourns"
			(at 0 0 0)
			(unlocked yes)
			(layer "B.Fab")
			(hide yes)
			(effects
				(font
					(size 1 1)
					(thickness 0.15)
				)
				(justify mirror)
			)
		)
		(property "MPN" "CR0402-FX-2003GLF"
			(at 0 0 0)
			(unlocked yes)
			(layer "B.Fab")
			(hide yes)
			(effects
				(font
					(size 1 1)
					(thickness 0.15)
				)
				(justify mirror)
			)
		)
		(property "Val" "200k"
			(at 0 0 0)
			(unlocked yes)
			(layer "B.Fab")
			(hide yes)
			(effects
				(font
					(size 1 1)
					(thickness 0.15)
				)
				(justify mirror)
			)
		)
		(property "License" "Apache-2.0"
			(at 0 0 0)
			(unlocked yes)
			(layer "B.Fab")
			(hide yes)
			(effects
				(font
					(size 1 1)
					(thickness 0.15)
				)
				(justify mirror)
			)
		)
		(property "Author" "Antmicro"
			(at 0 0 0)
			(unlocked yes)
			(layer "B.Fab")
			(hide yes)
			(effects
				(font
					(size 1 1)
					(thickness 0.15)
				)
				(justify mirror)
			)
		)
		(property "Tolerance" "1%"
			(at 0 0 0)
			(unlocked yes)
			(layer "B.Fab")
			(hide yes)
			(effects
				(font
					(size 1 1)
					(thickness 0.15)
				)
				(justify mirror)
			)
		)
		(sheetname "/Recovery USB/")
		(sheetfile "recovery_usb.kicad_sch")
		(attr smd)
		(fp_poly
			(pts
				(xy -0.925 0.47) (xy -0.925 -0.47) (xy 0.925 -0.47) (xy 0.925 0.47)
			)
			(stroke
				(width 0.05)
				(type default)
			)
			(fill no)
			(layer "B.CrtYd")
		)
		(fp_poly
			(pts
				(xy -0.5 0.25) (xy -0.5 -0.25) (xy 0.5 -0.25) (xy 0.5 0.25)
			)
			(stroke
				(width 0.15)
				(type solid)
			)
			(fill no)
			(layer "B.Fab")
		)
		(fp_text user "License: Apache-2.0"
			(at -0.949999 -5.169 0)
			(layer "B.Fab")
			(effects
				(font
					(size 0.7 0.7)
					(thickness 0.15)
				)
				(justify left bottom mirror)
			)
		)
		(fp_text user "${REFERENCE}"
			(at -0.95 -3.168 0)
			(layer "B.Fab")
			(effects
				(font
					(size 0.7 0.7)
					(thickness 0.15)
				)
				(justify left bottom mirror)
			)
		)
		(fp_text user "Author: Antmicro"
			(at -0.95 -4.169 0)
			(layer "B.Fab")
			(effects
				(font
					(size 0.7 0.7)
					(thickness 0.15)
				)
				(justify left bottom mirror)
			)
		)
		(pad "1" smd roundrect
			(at -0.48 0 180)
			(size 0.59 0.64)
			(layers "B.Cu" "B.Mask" "B.Paste")
			(roundrect_rratio 0.25)
			(net 2 "+3V3")
			(pintype "passive")
		)
		(pad "2" smd roundrect
			(at 0.48 0 180)
			(size 0.59 0.64)
			(layers "B.Cu" "B.Mask" "B.Paste")
			(roundrect_rratio 0.25)
			(net 1025 "/Recovery USB/USBC2_I2C_SCL")
			(pintype "passive")
		)
	)
	(footprint "antmicro-footprints:R_0402_1005Metric"
		(layer "B.Cu")
		(at 203.4 105.800001)
		(descr "Resistor SMD 0402")
		(tags "resistor SMD 0402")
		(property "Reference" "R281"
			(at 2.9 -0.400001 0)
			(layer "B.SilkS")
			(effects
				(font
					(size 0.7 0.7)
					(thickness 0.15)
				)
				(justify right top mirror)
			)
		)
		(property "Value" "R_0R_0402"
			(at -1.011843 -1.772046 0)
			(layer "B.Fab")
			(effects
				(font
					(size 0.7 0.7)
					(thickness 0.15)
				)
				(justify right top mirror)
			)
		)
		(property "Datasheet" "https://industrial.panasonic.com/cdbs/www-data/pdf/RDA0000/AOA0000C301.pdf"
			(at 0 0 0)
			(layer "B.Fab")
			(hide yes)
			(effects
				(font
					(size 1.27 1.27)
					(thickness 0.15)
				)
				(justify mirror)
			)
		)
		(property "Description" "SMD Chip Resistor, Jumper, 0 ohm, 100 mW, 0402 [1005 Metric], Thick Film, General Purpose"
			(at 0 0 0)
			(layer "B.Fab")
			(hide yes)
			(effects
				(font
					(size 1.27 1.27)
					(thickness 0.15)
				)
				(justify mirror)
			)
		)
		(property "Manufacturer" "Panasonic"
			(at 0 0 180)
			(unlocked yes)
			(layer "B.Fab")
			(hide yes)
			(effects
				(font
					(size 1 1)
					(thickness 0.15)
				)
				(justify mirror)
			)
		)
		(property "MPN" "ERJ2GE0R00X"
			(at 0 0 180)
			(unlocked yes)
			(layer "B.Fab")
			(hide yes)
			(effects
				(font
					(size 1 1)
					(thickness 0.15)
				)
				(justify mirror)
			)
		)
		(property "Val" "0R"
			(at 0 0 180)
			(unlocked yes)
			(layer "B.Fab")
			(hide yes)
			(effects
				(font
					(size 1 1)
					(thickness 0.15)
				)
				(justify mirror)
			)
		)
		(property "License" "Apache-2.0"
			(at 0 0 180)
			(unlocked yes)
			(layer "B.Fab")
			(hide yes)
			(effects
				(font
					(size 1 1)
					(thickness 0.15)
				)
				(justify mirror)
			)
		)
		(property "Author" "Antmicro"
			(at 0 0 180)
			(unlocked yes)
			(layer "B.Fab")
			(hide yes)
			(effects
				(font
					(size 1 1)
					(thickness 0.15)
				)
				(justify mirror)
			)
		)
		(property "Tolerance" "~"
			(at 0 0 180)
			(unlocked yes)
			(layer "B.Fab")
			(hide yes)
			(effects
				(font
					(size 1 1)
					(thickness 0.15)
				)
				(justify mirror)
			)
		)
		(property "Current" "1A"
			(at 0 0 180)
			(unlocked yes)
			(layer "B.Fab")
			(hide yes)
			(effects
				(font
					(size 1 1)
					(thickness 0.15)
				)
				(justify mirror)
			)
		)
		(sheetname "/Recovery USB/")
		(sheetfile "recovery_usb.kicad_sch")
		(attr smd exclude_from_pos_files exclude_from_bom dnp)
		(fp_poly
			(pts
				(xy -0.925 0.47) (xy -0.925 -0.47) (xy 0.925 -0.47) (xy 0.925 0.47)
			)
			(stroke
				(width 0.05)
				(type default)
			)
			(fill no)
			(layer "B.CrtYd")
		)
		(fp_poly
			(pts
				(xy -0.5 0.25) (xy -0.5 -0.25) (xy 0.5 -0.25) (xy 0.5 0.25)
			)
			(stroke
				(width 0.15)
				(type solid)
			)
			(fill no)
			(layer "B.Fab")
		)
		(fp_text user "License: Apache-2.0"
			(at -0.949999 -5.169 0)
			(layer "B.Fab")
			(effects
				(font
					(size 0.7 0.7)
					(thickness 0.15)
				)
				(justify right top mirror)
			)
		)
		(fp_text user "${REFERENCE}"
			(at -0.95 -3.168 0)
			(layer "B.Fab")
			(effects
				(font
					(size 0.7 0.7)
					(thickness 0.15)
				)
				(justify right top mirror)
			)
		)
		(fp_text user "Author: Antmicro"
			(at -0.95 -4.169 0)
			(layer "B.Fab")
			(effects
				(font
					(size 0.7 0.7)
					(thickness 0.15)
				)
				(justify right top mirror)
			)
		)
		(pad "1" smd roundrect
			(at -0.48 0)
			(size 0.59 0.64)
			(layers "B.Cu" "B.Mask" "B.Paste")
			(roundrect_rratio 0.25)
			(net 850 "/I2C_{SYS}.SDA")
			(pintype "passive")
		)
		(pad "2" smd roundrect
			(at 0.48 0)
			(size 0.59 0.64)
			(layers "B.Cu" "B.Mask" "B.Paste")
			(roundrect_rratio 0.25)
			(net 1024 "/Recovery USB/USBC2_I2C_SDA")
			(pintype "passive")
		)
	)
	(footprint "antmicro-footprints:C_0402_1005Metric"
		(layer "B.Cu")
		(at 121.93 70.67)
		(descr "Capacitor SMD 0402")
		(tags "capacitor SMD 0402")
		(property "Reference" "C13"
			(at -0.73 0.63 0)
			(layer "B.SilkS")
			(effects
				(font
					(size 0.7 0.7)
					(thickness 0.15)
				)
				(justify right top mirror)
			)
		)
		(property "Value" "C_10u_0402"
			(at -1.022927 -2.155213 0)
			(layer "B.Fab")
			(effects
				(font
					(size 0.7 0.7)
					(thickness 0.15)
				)
				(justify right top mirror)
			)
		)
		(property "Datasheet" "https://www.yageo.com/en/Chart/Download/pdf/CC0402MRX5R5BB106"
			(at 0 0 0)
			(layer "B.Fab")
			(hide yes)
			(effects
				(font
					(size 1.27 1.27)
					(thickness 0.15)
				)
				(justify mirror)
			)
		)
		(property "Description" "SMD Multilayer Ceramic Capacitor, 10 µF, 6.3 V, 0402 [1005 Metric], ± 20%, X5R, CC Series"
			(at 0 0 0)
			(layer "B.Fab")
			(hide yes)
			(effects
				(font
					(size 1.27 1.27)
					(thickness 0.15)
				)
				(justify mirror)
			)
		)
		(property "MPN" "CC0402MRX5R5BB106"
			(at 0 0 0)
			(unlocked yes)
			(layer "B.Fab")
			(hide yes)
			(effects
				(font
					(size 1 1)
					(thickness 0.15)
				)
				(justify mirror)
			)
		)
		(property "Manufacturer" "YAGEO"
			(at 0 0 0)
			(unlocked yes)
			(layer "B.Fab")
			(hide yes)
			(effects
				(font
					(size 1 1)
					(thickness 0.15)
				)
				(justify mirror)
			)
		)
		(property "License" "Apache-2.0"
			(at 0 0 0)
			(unlocked yes)
			(layer "B.Fab")
			(hide yes)
			(effects
				(font
					(size 1 1)
					(thickness 0.15)
				)
				(justify mirror)
			)
		)
		(property "Author" "Antmicro"
			(at 0 0 0)
			(unlocked yes)
			(layer "B.Fab")
			(hide yes)
			(effects
				(font
					(size 1 1)
					(thickness 0.15)
				)
				(justify mirror)
			)
		)
		(property "Val" "10u"
			(at 0 0 0)
			(unlocked yes)
			(layer "B.Fab")
			(hide yes)
			(effects
				(font
					(size 1 1)
					(thickness 0.15)
				)
				(justify mirror)
			)
		)
		(property "Voltage" ""
			(at 0 0 0)
			(unlocked yes)
			(layer "B.Fab")
			(hide yes)
			(effects
				(font
					(size 1 1)
					(thickness 0.15)
				)
				(justify mirror)
			)
		)
		(property "Dielectric" "template_dielectric"
			(at 0 0 0)
			(unlocked yes)
			(layer "B.Fab")
			(hide yes)
			(effects
				(font
					(size 1 1)
					(thickness 0.15)
				)
				(justify mirror)
			)
		)
		(sheetname "/SoM_Power/")
		(sheetfile "som_power.kicad_sch")
		(attr smd)
		(fp_rect
			(start -0.925 0.47)
			(end 0.925 -0.47)
			(stroke
				(width 0.05)
				(type default)
			)
			(fill no)
			(layer "B.CrtYd")
		)
		(fp_line
			(start -0.494 -0.248)
			(end -0.494 0.25)
			(stroke
				(width 0.15)
				(type solid)
			)
			(layer "B.Fab")
		)
		(fp_line
			(start -0.494 0.25)
			(end 0.504 0.25)
			(stroke
				(width 0.15)
				(type solid)
			)
			(layer "B.Fab")
		)
		(fp_line
			(start 0.504 -0.248)
			(end -0.494 -0.248)
			(stroke
				(width 0.15)
				(type solid)
			)
			(layer "B.Fab")
		)
		(fp_line
			(start 0.504 0.25)
			(end 0.504 -0.248)
			(stroke
				(width 0.15)
				(type solid)
			)
			(layer "B.Fab")
		)
		(fp_text user "${REFERENCE}"
			(at -0.939 -4.599 0)
			(layer "B.Fab")
			(effects
				(font
					(size 0.7 0.7)
					(thickness 0.15)
				)
				(justify right top mirror)
			)
		)
		(fp_text user "Author: Antmicro"
			(at -0.939 -3.399 0)
			(layer "B.Fab")
			(effects
				(font
					(size 0.7 0.7)
					(thickness 0.15)
				)
				(justify right top mirror)
			)
		)
		(fp_text user "License: Apache-2.0"
			(at -0.939 -5.799 0)
			(layer "B.Fab")
			(effects
				(font
					(size 0.7 0.7)
					(thickness 0.15)
				)
				(justify right top mirror)
			)
		)
		(pad "1" smd roundrect
			(at -0.48 0)
			(size 0.59 0.64)
			(layers "B.Cu" "B.Mask" "B.Paste")
			(roundrect_rratio 0.25)
			(net 1 "GND")
			(pintype "passive")
		)
		(pad "2" smd roundrect
			(at 0.48 0)
			(size 0.59 0.64)
			(layers "B.Cu" "B.Mask" "B.Paste")
			(roundrect_rratio 0.25)
			(net 213 "+5V_SOM")
			(pintype "passive")
		)
	)
	(footprint "antmicro-footprints:C_0402_1005Metric"
		(layer "B.Cu")
		(at 215.826 145.4 180)
		(descr "Capacitor SMD 0402")
		(tags "capacitor SMD 0402")
		(property "Reference" "C172"
			(at -1.29 -1.77 0)
			(layer "B.SilkS")
			(effects
				(font
					(size 0.7 0.7)
					(thickness 0.15)
				)
				(justify left bottom mirror)
			)
		)
		(property "Value" "C_100n_0402"
			(at -1.022927 -2.155213 0)
			(layer "B.Fab")
			(effects
				(font
					(size 0.7 0.7)
					(thickness 0.15)
				)
				(justify left bottom mirror)
			)
		)
		(property "Datasheet" "https://www.murata.com/products/productdetail?partno=GRM155R61H104KE14%23"
			(at 0 0 0)
			(layer "B.Fab")
			(hide yes)
			(effects
				(font
					(size 1.27 1.27)
					(thickness 0.15)
				)
				(justify mirror)
			)
		)
		(property "Description" "SMD Multilayer Ceramic Capacitor, 0.1 µF, 50 V, 0402 [1005 Metric], ± 10%, X5R, GRM Series"
			(at 0 0 0)
			(layer "B.Fab")
			(hide yes)
			(effects
				(font
					(size 1.27 1.27)
					(thickness 0.15)
				)
				(justify mirror)
			)
		)
		(property "MPN" "GRM155R61H104KE14D"
			(at 0 0 0)
			(unlocked yes)
			(layer "B.Fab")
			(hide yes)
			(effects
				(font
					(size 1 1)
					(thickness 0.15)
				)
				(justify mirror)
			)
		)
		(property "Manufacturer" "Murata"
			(at 0 0 0)
			(unlocked yes)
			(layer "B.Fab")
			(hide yes)
			(effects
				(font
					(size 1 1)
					(thickness 0.15)
				)
				(justify mirror)
			)
		)
		(property "License" "Apache-2.0"
			(at 0 0 0)
			(unlocked yes)
			(layer "B.Fab")
			(hide yes)
			(effects
				(font
					(size 1 1)
					(thickness 0.15)
				)
				(justify mirror)
			)
		)
		(property "Author" "Antmicro"
			(at 0 0 0)
			(unlocked yes)
			(layer "B.Fab")
			(hide yes)
			(effects
				(font
					(size 1 1)
					(thickness 0.15)
				)
				(justify mirror)
			)
		)
		(property "Val" "100n"
			(at 0 0 0)
			(unlocked yes)
			(layer "B.Fab")
			(hide yes)
			(effects
				(font
					(size 1 1)
					(thickness 0.15)
				)
				(justify mirror)
			)
		)
		(property "Voltage" "50V"
			(at 0 0 0)
			(unlocked yes)
			(layer "B.Fab")
			(hide yes)
			(effects
				(font
					(size 1 1)
					(thickness 0.15)
				)
				(justify mirror)
			)
		)
		(property "Dielectric" "X5R"
			(at 0 0 0)
			(unlocked yes)
			(layer "B.Fab")
			(hide yes)
			(effects
				(font
					(size 1 1)
					(thickness 0.15)
				)
				(justify mirror)
			)
		)
		(sheetname "/SFP/")
		(sheetfile "sfp.kicad_sch")
		(attr smd)
		(fp_poly
			(pts
				(xy -0.925 0.47) (xy -0.925 -0.47) (xy 0.925 -0.47) (xy 0.925 0.47)
			)
			(stroke
				(width 0.05)
				(type default)
			)
			(fill no)
			(layer "B.CrtYd")
		)
		(fp_line
			(start 0.504 0.25)
			(end 0.504 -0.248)
			(stroke
				(width 0.15)
				(type solid)
			)
			(layer "B.Fab")
		)
		(fp_line
			(start 0.504 -0.248)
			(end -0.494 -0.248)
			(stroke
				(width 0.15)
				(type solid)
			)
			(layer "B.Fab")
		)
		(fp_line
			(start -0.494 0.25)
			(end 0.504 0.25)
			(stroke
				(width 0.15)
				(type solid)
			)
			(layer "B.Fab")
		)
		(fp_line
			(start -0.494 -0.248)
			(end -0.494 0.25)
			(stroke
				(width 0.15)
				(type solid)
			)
			(layer "B.Fab")
		)
		(fp_text user "Author: Antmicro"
			(at -0.939 -3.399 0)
			(layer "B.Fab")
			(effects
				(font
					(size 0.7 0.7)
					(thickness 0.15)
				)
				(justify left bottom mirror)
			)
		)
		(fp_text user "License: Apache-2.0"
			(at -0.939 -5.799 0)
			(layer "B.Fab")
			(effects
				(font
					(size 0.7 0.7)
					(thickness 0.15)
				)
				(justify left bottom mirror)
			)
		)
		(fp_text user "${REFERENCE}"
			(at -0.939 -4.599 0)
			(layer "B.Fab")
			(effects
				(font
					(size 0.7 0.7)
					(thickness 0.15)
				)
				(justify left bottom mirror)
			)
		)
		(pad "1" smd roundrect
			(at -0.48 0 180)
			(size 0.59 0.64)
			(layers "B.Cu" "B.Mask" "B.Paste")
			(roundrect_rratio 0.25)
			(net 1 "GND")
			(pintype "passive")
		)
		(pad "2" smd roundrect
			(at 0.48 0 180)
			(size 0.59 0.64)
			(layers "B.Cu" "B.Mask" "B.Paste")
			(roundrect_rratio 0.25)
			(net 379 "/SFP/SH")
			(pintype "passive")
		)
	)
	(footprint "antmicro-footprints:C_0402_1005Metric"
		(layer "B.Cu")
		(at 178.37 88.85 180)
		(descr "Capacitor SMD 0402")
		(tags "capacitor SMD 0402")
		(property "Reference" "C263"
			(at 3.64 -0.43 0)
			(layer "B.SilkS")
			(effects
				(font
					(size 0.7 0.7)
					(thickness 0.15)
				)
				(justify left bottom mirror)
			)
		)
		(property "Value" "C_100n_0402"
			(at -1.022927 -2.155213 0)
			(layer "B.Fab")
			(effects
				(font
					(size 0.7 0.7)
					(thickness 0.15)
				)
				(justify left bottom mirror)
			)
		)
		(property "Datasheet" "https://www.murata.com/products/productdetail?partno=GRM155R61H104KE14%23"
			(at 0 0 0)
			(layer "B.Fab")
			(hide yes)
			(effects
				(font
					(size 1.27 1.27)
					(thickness 0.15)
				)
				(justify mirror)
			)
		)
		(property "Description" "SMD Multilayer Ceramic Capacitor, 0.1 µF, 50 V, 0402 [1005 Metric], ± 10%, X5R, GRM Series"
			(at 0 0 0)
			(layer "B.Fab")
			(hide yes)
			(effects
				(font
					(size 1.27 1.27)
					(thickness 0.15)
				)
				(justify mirror)
			)
		)
		(property "MPN" "GRM155R61H104KE14D"
			(at 0 0 0)
			(unlocked yes)
			(layer "B.Fab")
			(hide yes)
			(effects
				(font
					(size 1 1)
					(thickness 0.15)
				)
				(justify mirror)
			)
		)
		(property "Val" "100n"
			(at 0 0 0)
			(unlocked yes)
			(layer "B.Fab")
			(hide yes)
			(effects
				(font
					(size 1 1)
					(thickness 0.15)
				)
				(justify mirror)
			)
		)
		(property "Voltage" "50V"
			(at 0 0 0)
			(unlocked yes)
			(layer "B.Fab")
			(hide yes)
			(effects
				(font
					(size 1 1)
					(thickness 0.15)
				)
				(justify mirror)
			)
		)
		(property "Dielectric" "X5R"
			(at 0 0 0)
			(unlocked yes)
			(layer "B.Fab")
			(hide yes)
			(effects
				(font
					(size 1 1)
					(thickness 0.15)
				)
				(justify mirror)
			)
		)
		(property "Manufacturer" "Murata"
			(at 0 0 0)
			(unlocked yes)
			(layer "B.Fab")
			(hide yes)
			(effects
				(font
					(size 1 1)
					(thickness 0.15)
				)
				(justify mirror)
			)
		)
		(property "License" "Apache-2.0"
			(at 0 0 0)
			(unlocked yes)
			(layer "B.Fab")
			(hide yes)
			(effects
				(font
					(size 1 1)
					(thickness 0.15)
				)
				(justify mirror)
			)
		)
		(property "Author" "Antmicro"
			(at 0 0 0)
			(unlocked yes)
			(layer "B.Fab")
			(hide yes)
			(effects
				(font
					(size 1 1)
					(thickness 0.15)
				)
				(justify mirror)
			)
		)
		(sheetname "/Power/")
		(sheetfile "power.kicad_sch")
		(attr smd)
		(fp_rect
			(start -0.925 0.47)
			(end 0.925 -0.47)
			(stroke
				(width 0.05)
				(type default)
			)
			(fill no)
			(layer "B.CrtYd")
		)
		(fp_line
			(start 0.504 0.25)
			(end 0.504 -0.248)
			(stroke
				(width 0.15)
				(type solid)
			)
			(layer "B.Fab")
		)
		(fp_line
			(start 0.504 -0.248)
			(end -0.494 -0.248)
			(stroke
				(width 0.15)
				(type solid)
			)
			(layer "B.Fab")
		)
		(fp_line
			(start -0.494 0.25)
			(end 0.504 0.25)
			(stroke
				(width 0.15)
				(type solid)
			)
			(layer "B.Fab")
		)
		(fp_line
			(start -0.494 -0.248)
			(end -0.494 0.25)
			(stroke
				(width 0.15)
				(type solid)
			)
			(layer "B.Fab")
		)
		(fp_text user "Author: Antmicro"
			(at -0.939 -3.399 0)
			(layer "B.Fab")
			(effects
				(font
					(size 0.7 0.7)
					(thickness 0.15)
				)
				(justify left bottom mirror)
			)
		)
		(fp_text user "${REFERENCE}"
			(at -0.939 -4.599 0)
			(layer "B.Fab")
			(effects
				(font
					(size 0.7 0.7)
					(thickness 0.15)
				)
				(justify left bottom mirror)
			)
		)
		(fp_text user "License: Apache-2.0"
			(at -0.939 -5.799 0)
			(layer "B.Fab")
			(effects
				(font
					(size 0.7 0.7)
					(thickness 0.15)
				)
				(justify left bottom mirror)
			)
		)
		(pad "1" smd roundrect
			(at -0.48 0 180)
			(size 0.59 0.64)
			(layers "B.Cu" "B.Mask" "B.Paste")
			(roundrect_rratio 0.25)
			(net 1 "GND")
			(pintype "passive")
		)
		(pad "2" smd roundrect
			(at 0.48 0 180)
			(size 0.59 0.64)
			(layers "B.Cu" "B.Mask" "B.Paste")
			(roundrect_rratio 0.25)
			(net 904 "+20V")
			(pintype "passive")
		)
	)
	(footprint "antmicro-footprints:R_0402_1005Metric"
		(layer "B.Cu")
		(at 76 66.5 180)
		(descr "Resistor SMD 0402")
		(tags "resistor SMD 0402")
		(property "Reference" "R275"
			(at -1.6 -2.4 0)
			(layer "B.SilkS")
			(effects
				(font
					(size 0.7 0.7)
					(thickness 0.15)
				)
				(justify left bottom mirror)
			)
		)
		(property "Value" "R_10k_0402"
			(at -1.011843 -1.772046 0)
			(layer "B.Fab")
			(effects
				(font
					(size 0.7 0.7)
					(thickness 0.15)
				)
				(justify left bottom mirror)
			)
		)
		(property "Datasheet" "https://www.bourns.com/docs/product-datasheets/cr.pdf"
			(at 0 0 0)
			(layer "B.Fab")
			(hide yes)
			(effects
				(font
					(size 1.27 1.27)
					(thickness 0.15)
				)
				(justify mirror)
			)
		)
		(property "Description" "SMD Chip Resistor, 10 kohm, ± 1%, 62.5 mW, 0402 [1005 Metric], Thick Film, General Purpose"
			(at 0 0 0)
			(layer "B.Fab")
			(hide yes)
			(effects
				(font
					(size 1.27 1.27)
					(thickness 0.15)
				)
				(justify mirror)
			)
		)
		(property "MPN" "CR0402-FX-1002GLF"
			(at 0 0 0)
			(unlocked yes)
			(layer "B.Fab")
			(hide yes)
			(effects
				(font
					(size 1 1)
					(thickness 0.15)
				)
				(justify mirror)
			)
		)
		(property "Manufacturer" "Bourns"
			(at 0 0 0)
			(unlocked yes)
			(layer "B.Fab")
			(hide yes)
			(effects
				(font
					(size 1 1)
					(thickness 0.15)
				)
				(justify mirror)
			)
		)
		(property "License" "Apache-2.0"
			(at 0 0 0)
			(unlocked yes)
			(layer "B.Fab")
			(hide yes)
			(effects
				(font
					(size 1 1)
					(thickness 0.15)
				)
				(justify mirror)
			)
		)
		(property "Author" "Antmicro"
			(at 0 0 0)
			(unlocked yes)
			(layer "B.Fab")
			(hide yes)
			(effects
				(font
					(size 1 1)
					(thickness 0.15)
				)
				(justify mirror)
			)
		)
		(property "Val" "10k"
			(at 0 0 0)
			(unlocked yes)
			(layer "B.Fab")
			(hide yes)
			(effects
				(font
					(size 1 1)
					(thickness 0.15)
				)
				(justify mirror)
			)
		)
		(property "Tolerance" "1%"
			(at 0 0 0)
			(unlocked yes)
			(layer "B.Fab")
			(hide yes)
			(effects
				(font
					(size 1 1)
					(thickness 0.15)
				)
				(justify mirror)
			)
		)
		(sheetname "/Expansion connector/")
		(sheetfile "expansion_connector.kicad_sch")
		(attr smd exclude_from_pos_files exclude_from_bom dnp)
		(fp_poly
			(pts
				(xy -0.925 0.47) (xy 0.925 0.47) (xy 0.925 -0.47) (xy -0.925 -0.47)
			)
			(stroke
				(width 0.05)
				(type default)
			)
			(fill no)
			(layer "B.CrtYd")
		)
		(fp_poly
			(pts
				(xy -0.5 0.25) (xy 0.5 0.25) (xy 0.5 -0.25) (xy -0.5 -0.25)
			)
			(stroke
				(width 0.15)
				(type solid)
			)
			(fill no)
			(layer "B.Fab")
		)
		(fp_text user "License: Apache-2.0"
			(at -0.949999 -5.169 0)
			(layer "B.Fab")
			(effects
				(font
					(size 0.7 0.7)
					(thickness 0.15)
				)
				(justify left bottom mirror)
			)
		)
		(fp_text user "${REFERENCE}"
			(at -0.95 -3.168 0)
			(layer "B.Fab")
			(effects
				(font
					(size 0.7 0.7)
					(thickness 0.15)
				)
				(justify left bottom mirror)
			)
		)
		(fp_text user "Author: Antmicro"
			(at -0.95 -4.169 0)
			(layer "B.Fab")
			(effects
				(font
					(size 0.7 0.7)
					(thickness 0.15)
				)
				(justify left bottom mirror)
			)
		)
		(pad "1" smd roundrect
			(at -0.48 0 180)
			(size 0.59 0.64)
			(layers "B.Cu" "B.Mask" "B.Paste")
			(roundrect_rratio 0.25)
			(net 341 "/Expansion connector/FMC_PRESENT")
			(pintype "passive")
		)
		(pad "2" smd roundrect
			(at 0.48 0 180)
			(size 0.59 0.64)
			(layers "B.Cu" "B.Mask" "B.Paste")
			(roundrect_rratio 0.25)
			(net 295 "/Expansion connector/+V_{ADJ}")
			(pintype "passive")
		)
	)
	(footprint "antmicro-footprints:R_0402_1005Metric"
		(layer "B.Cu")
		(at 144.6 65.2 -90)
		(descr "Resistor SMD 0402")
		(tags "resistor SMD 0402")
		(property "Reference" "R243"
			(at 0.8 -0.4 90)
			(layer "B.SilkS")
			(effects
				(font
					(size 0.7 0.7)
					(thickness 0.15)
				)
				(justify left bottom mirror)
			)
		)
		(property "Value" "R_10k_0402"
			(at -1.011843 -1.772046 90)
			(layer "B.Fab")
			(effects
				(font
					(size 0.7 0.7)
					(thickness 0.15)
				)
				(justify left bottom mirror)
			)
		)
		(property "Datasheet" "https://www.bourns.com/docs/product-datasheets/cr.pdf"
			(at 0 0 90)
			(layer "B.Fab")
			(hide yes)
			(effects
				(font
					(size 1.27 1.27)
					(thickness 0.15)
				)
				(justify mirror)
			)
		)
		(property "Description" "SMD Chip Resistor, 10 kohm, ± 1%, 62.5 mW, 0402 [1005 Metric], Thick Film, General Purpose"
			(at 0 0 90)
			(layer "B.Fab")
			(hide yes)
			(effects
				(font
					(size 1.27 1.27)
					(thickness 0.15)
				)
				(justify mirror)
			)
		)
		(property "Manufacturer" "Bourns"
			(at 0 0 90)
			(unlocked yes)
			(layer "B.Fab")
			(hide yes)
			(effects
				(font
					(size 1 1)
					(thickness 0.15)
				)
				(justify mirror)
			)
		)
		(property "MPN" "CR0402-FX-1002GLF"
			(at 0 0 90)
			(unlocked yes)
			(layer "B.Fab")
			(hide yes)
			(effects
				(font
					(size 1 1)
					(thickness 0.15)
				)
				(justify mirror)
			)
		)
		(property "Val" "10k"
			(at 0 0 90)
			(unlocked yes)
			(layer "B.Fab")
			(hide yes)
			(effects
				(font
					(size 1 1)
					(thickness 0.15)
				)
				(justify mirror)
			)
		)
		(property "License" "Apache-2.0"
			(at 0 0 90)
			(unlocked yes)
			(layer "B.Fab")
			(hide yes)
			(effects
				(font
					(size 1 1)
					(thickness 0.15)
				)
				(justify mirror)
			)
		)
		(property "Author" "Antmicro"
			(at 0 0 90)
			(unlocked yes)
			(layer "B.Fab")
			(hide yes)
			(effects
				(font
					(size 1 1)
					(thickness 0.15)
				)
				(justify mirror)
			)
		)
		(property "Tolerance" "1%"
			(at 0 0 90)
			(unlocked yes)
			(layer "B.Fab")
			(hide yes)
			(effects
				(font
					(size 1 1)
					(thickness 0.15)
				)
				(justify mirror)
			)
		)
		(sheetname "/Peripherals/")
		(sheetfile "peripherals.kicad_sch")
		(attr smd)
		(fp_poly
			(pts
				(xy -0.925 0.47) (xy 0.925 0.47) (xy 0.925 -0.47) (xy -0.925 -0.47)
			)
			(stroke
				(width 0.05)
				(type default)
			)
			(fill no)
			(layer "B.CrtYd")
		)
		(fp_poly
			(pts
				(xy -0.5 0.25) (xy 0.5 0.25) (xy 0.5 -0.25) (xy -0.5 -0.25)
			)
			(stroke
				(width 0.15)
				(type solid)
			)
			(fill no)
			(layer "B.Fab")
		)
		(fp_text user "${REFERENCE}"
			(at -0.95 -3.168 90)
			(layer "B.Fab")
			(effects
				(font
					(size 0.7 0.7)
					(thickness 0.15)
				)
				(justify left bottom mirror)
			)
		)
		(fp_text user "Author: Antmicro"
			(at -0.95 -4.169 90)
			(layer "B.Fab")
			(effects
				(font
					(size 0.7 0.7)
					(thickness 0.15)
				)
				(justify left bottom mirror)
			)
		)
		(fp_text user "License: Apache-2.0"
			(at -0.949999 -5.169 90)
			(layer "B.Fab")
			(effects
				(font
					(size 0.7 0.7)
					(thickness 0.15)
				)
				(justify left bottom mirror)
			)
		)
		(pad "1" smd roundrect
			(at -0.48 0 270)
			(size 0.59 0.64)
			(layers "B.Cu" "B.Mask" "B.Paste")
			(roundrect_rratio 0.25)
			(net 90 "/Peripherals/I2C_CONN_PEN")
			(pintype "passive")
		)
		(pad "2" smd roundrect
			(at 0.48 0 270)
			(size 0.59 0.64)
			(layers "B.Cu" "B.Mask" "B.Paste")
			(roundrect_rratio 0.25)
			(net 2 "+3V3")
			(pintype "passive")
		)
	)
	(footprint "antmicro-footprints:R_0402_1005Metric"
		(layer "B.Cu")
		(at 96 62.99 90)
		(descr "Resistor SMD 0402")
		(tags "resistor SMD 0402")
		(property "Reference" "R47"
			(at -1.26 -2.5 90)
			(layer "B.SilkS")
			(effects
				(font
					(size 0.7 0.7)
					(thickness 0.15)
				)
				(justify right top mirror)
			)
		)
		(property "Value" "R_100k_0402"
			(at -1.011843 -1.772047 90)
			(layer "B.Fab")
			(effects
				(font
					(size 0.7 0.7)
					(thickness 0.15)
				)
				(justify right top mirror)
			)
		)
		(property "Datasheet" "https://www.bourns.com/docs/product-datasheets/cr.pdf"
			(at 0 0 90)
			(layer "B.Fab")
			(hide yes)
			(effects
				(font
					(size 1.27 1.27)
					(thickness 0.15)
				)
				(justify mirror)
			)
		)
		(property "Description" "SMD Chip Resistor, 100 kohm, ± 1%, 62.5 mW, 0402 [1005 Metric], Thick Film, General Purpose"
			(at 0 0 90)
			(layer "B.Fab")
			(hide yes)
			(effects
				(font
					(size 1.27 1.27)
					(thickness 0.15)
				)
				(justify mirror)
			)
		)
		(property "MPN" "CR0402-FX-1003GLF"
			(at 0 0 270)
			(unlocked yes)
			(layer "B.Fab")
			(hide yes)
			(effects
				(font
					(size 1 1)
					(thickness 0.15)
				)
				(justify mirror)
			)
		)
		(property "Manufacturer" "Bourns"
			(at 0 0 270)
			(unlocked yes)
			(layer "B.Fab")
			(hide yes)
			(effects
				(font
					(size 1 1)
					(thickness 0.15)
				)
				(justify mirror)
			)
		)
		(property "License" "Apache-2.0"
			(at 0 0 270)
			(unlocked yes)
			(layer "B.Fab")
			(hide yes)
			(effects
				(font
					(size 1 1)
					(thickness 0.15)
				)
				(justify mirror)
			)
		)
		(property "Author" "Antmicro"
			(at 0 0 270)
			(unlocked yes)
			(layer "B.Fab")
			(hide yes)
			(effects
				(font
					(size 1 1)
					(thickness 0.15)
				)
				(justify mirror)
			)
		)
		(property "Val" "100k"
			(at 0 0 270)
			(unlocked yes)
			(layer "B.Fab")
			(hide yes)
			(effects
				(font
					(size 1 1)
					(thickness 0.15)
				)
				(justify mirror)
			)
		)
		(property "Tolerance" "1%"
			(at 0 0 270)
			(unlocked yes)
			(layer "B.Fab")
			(hide yes)
			(effects
				(font
					(size 1 1)
					(thickness 0.15)
				)
				(justify mirror)
			)
		)
		(sheetname "/SoM_Power/")
		(sheetfile "som_power.kicad_sch")
		(attr smd)
		(fp_rect
			(start -0.925 0.47)
			(end 0.925 -0.47)
			(stroke
				(width 0.05)
				(type default)
			)
			(fill no)
			(layer "B.CrtYd")
		)
		(fp_rect
			(start -0.5 0.25)
			(end 0.5 -0.25)
			(stroke
				(width 0.15)
				(type solid)
			)
			(fill no)
			(layer "B.Fab")
		)
		(fp_text user "Author: Antmicro"
			(at -0.95 -4.169 90)
			(layer "B.Fab")
			(effects
				(font
					(size 0.7 0.7)
					(thickness 0.15)
				)
				(justify right top mirror)
			)
		)
		(fp_text user "${REFERENCE}"
			(at -0.95 -3.168 90)
			(layer "B.Fab")
			(effects
				(font
					(size 0.7 0.7)
					(thickness 0.15)
				)
				(justify right top mirror)
			)
		)
		(fp_text user "License: Apache-2.0"
			(at -0.95 -5.169 90)
			(layer "B.Fab")
			(effects
				(font
					(size 0.7 0.7)
					(thickness 0.15)
				)
				(justify right top mirror)
			)
		)
		(pad "1" smd roundrect
			(at -0.48 0 90)
			(size 0.59 0.64)
			(layers "B.Cu" "B.Mask" "B.Paste")
			(roundrect_rratio 0.25)
			(net 1298 "Net-(Q37-G)")
			(pintype "passive")
		)
		(pad "2" smd roundrect
			(at 0.48 0 90)
			(size 0.59 0.64)
			(layers "B.Cu" "B.Mask" "B.Paste")
			(roundrect_rratio 0.25)
			(net 4 "+3V3_AON")
			(pintype "passive")
		)
	)
	(footprint "antmicro-footprints:R_0402_1005Metric"
		(layer "B.Cu")
		(at 103.92 64.5 -90)
		(descr "Resistor SMD 0402")
		(tags "resistor SMD 0402")
		(property "Reference" "R3"
			(at -2.5 -0.48 90)
			(layer "B.SilkS")
			(effects
				(font
					(size 0.7 0.7)
					(thickness 0.15)
				)
				(justify left bottom mirror)
			)
		)
		(property "Value" "R_33R_0402"
			(at -1.011843 -1.772047 90)
			(layer "B.Fab")
			(effects
				(font
					(size 0.7 0.7)
					(thickness 0.15)
				)
				(justify left bottom mirror)
			)
		)
		(property "Datasheet" "https://www.bourns.com/docs/product-datasheets/cr.pdf"
			(at 0 0 90)
			(layer "B.Fab")
			(hide yes)
			(effects
				(font
					(size 1.27 1.27)
					(thickness 0.15)
				)
				(justify mirror)
			)
		)
		(property "Description" "SMD Chip Resistor, 33 ohm, ± 1%, 62.5 mW, 0402 [1005 Metric], Thick Film, General Purpose"
			(at 0 0 90)
			(layer "B.Fab")
			(hide yes)
			(effects
				(font
					(size 1.27 1.27)
					(thickness 0.15)
				)
				(justify mirror)
			)
		)
		(property "MPN" "CR0402-FX-33R0GLF"
			(at 0 0 90)
			(unlocked yes)
			(layer "B.Fab")
			(hide yes)
			(effects
				(font
					(size 1 1)
					(thickness 0.15)
				)
				(justify mirror)
			)
		)
		(property "Manufacturer" "Bourns"
			(at 0 0 90)
			(unlocked yes)
			(layer "B.Fab")
			(hide yes)
			(effects
				(font
					(size 1 1)
					(thickness 0.15)
				)
				(justify mirror)
			)
		)
		(property "License" "Apache-2.0"
			(at 0 0 90)
			(unlocked yes)
			(layer "B.Fab")
			(hide yes)
			(effects
				(font
					(size 1 1)
					(thickness 0.15)
				)
				(justify mirror)
			)
		)
		(property "Author" "Antmicro"
			(at 0 0 90)
			(unlocked yes)
			(layer "B.Fab")
			(hide yes)
			(effects
				(font
					(size 1 1)
					(thickness 0.15)
				)
				(justify mirror)
			)
		)
		(property "Val" "33R"
			(at 0 0 90)
			(unlocked yes)
			(layer "B.Fab")
			(hide yes)
			(effects
				(font
					(size 1 1)
					(thickness 0.15)
				)
				(justify mirror)
			)
		)
		(property "Tolerance" "1%"
			(at 0 0 90)
			(unlocked yes)
			(layer "B.Fab")
			(hide yes)
			(effects
				(font
					(size 1 1)
					(thickness 0.15)
				)
				(justify mirror)
			)
		)
		(sheetname "/SoM_IO2/")
		(sheetfile "som_io2.kicad_sch")
		(attr smd)
		(fp_rect
			(start -0.925 0.47)
			(end 0.925 -0.47)
			(stroke
				(width 0.05)
				(type default)
			)
			(fill no)
			(layer "B.CrtYd")
		)
		(fp_rect
			(start -0.5 0.25)
			(end 0.5 -0.25)
			(stroke
				(width 0.15)
				(type solid)
			)
			(fill no)
			(layer "B.Fab")
		)
		(fp_text user "Author: Antmicro"
			(at -0.95 -4.169 90)
			(layer "B.Fab")
			(effects
				(font
					(size 0.7 0.7)
					(thickness 0.15)
				)
				(justify left bottom mirror)
			)
		)
		(fp_text user "${REFERENCE}"
			(at -0.95 -3.168 90)
			(layer "B.Fab")
			(effects
				(font
					(size 0.7 0.7)
					(thickness 0.15)
				)
				(justify left bottom mirror)
			)
		)
		(fp_text user "License: Apache-2.0"
			(at -0.95 -5.169 90)
			(layer "B.Fab")
			(effects
				(font
					(size 0.7 0.7)
					(thickness 0.15)
				)
				(justify left bottom mirror)
			)
		)
		(pad "1" smd roundrect
			(at -0.48 0 270)
			(size 0.59 0.64)
			(layers "B.Cu" "B.Mask" "B.Paste")
			(roundrect_rratio 0.25)
			(net 895 "/SoM_IO2/SFI_CLK-")
			(pintype "passive")
		)
		(pad "2" smd roundrect
			(at 0.48 0 270)
			(size 0.59 0.64)
			(layers "B.Cu" "B.Mask" "B.Paste")
			(roundrect_rratio 0.25)
			(net 171 "/SoM_IO2/SFI_REFCLK-")
			(pintype "passive")
		)
	)
	(footprint "antmicro-footprints:Fiducial_1mm_Mask3mm"
		(layer "B.Cu")
		(at 63.11 150.58 180)
		(descr "Circular Fiducial, 1.5mm bare copper, 3mm soldermask opening")
		(tags "fiducial")
		(property "Reference" "FD7"
			(at -0.93 1.67 0)
			(layer "B.SilkS")
			(effects
				(font
					(size 0.7 0.7)
					(thickness 0.15)
				)
				(justify left bottom mirror)
			)
		)
		(property "Value" "Fiducial_1mm_Mask3mm"
			(at 0 -2.603 0)
			(layer "B.Fab")
			(effects
				(font
					(size 0.7 0.7)
					(thickness 0.15)
				)
				(justify left bottom mirror)
			)
		)
		(property "Description" "Fiducial mask"
			(at 0 0 0)
			(layer "B.Fab")
			(hide yes)
			(effects
				(font
					(size 1.27 1.27)
					(thickness 0.15)
				)
				(justify mirror)
			)
		)
		(property "Author" "Antmicro"
			(at 0 0 0)
			(unlocked yes)
			(layer "B.Fab")
			(hide yes)
			(effects
				(font
					(size 1 1)
					(thickness 0.15)
				)
				(justify mirror)
			)
		)
		(property "License" "Apache-2.0"
			(at 0 0 0)
			(unlocked yes)
			(layer "B.Fab")
			(hide yes)
			(effects
				(font
					(size 1 1)
					(thickness 0.15)
				)
				(justify mirror)
			)
		)
		(sheetname "/")
		(sheetfile "jetson-agx-thor-baseboard.kicad_sch")
		(attr exclude_from_pos_files exclude_from_bom)
		(fp_circle
			(center 0 0)
			(end 1.5 0)
			(stroke
				(width 0.05)
				(type solid)
			)
			(fill no)
			(layer "B.CrtYd")
		)
		(fp_circle
			(center 0 0)
			(end 1.5 0)
			(stroke
				(width 0.15)
				(type solid)
			)
			(fill no)
			(layer "B.Fab")
		)
		(fp_text user "License: Apache-2.0"
			(at -1.25 -7.003 0)
			(layer "B.Fab")
			(effects
				(font
					(size 0.7 0.7)
					(thickness 0.15)
				)
				(justify left bottom mirror)
			)
		)
		(fp_text user "Author: Antmicro"
			(at -1.25 -5.803 0)
			(layer "B.Fab")
			(effects
				(font
					(size 0.7 0.7)
					(thickness 0.15)
				)
				(justify left bottom mirror)
			)
		)
		(fp_text user "${REFERENCE}"
			(at -1.25 -4.603 0)
			(layer "B.Fab")
			(effects
				(font
					(size 0.7 0.7)
					(thickness 0.15)
				)
				(justify left bottom mirror)
			)
		)
		(pad "" smd circle
			(at 0 0 180)
			(size 1 1)
			(layers "B.Cu" "B.Mask")
			(solder_mask_margin 1)
			(clearance 1)
		)
	)
	(footprint "antmicro-footprints:C_0402_1005Metric"
		(layer "B.Cu")
		(at 161.5 64.49)
		(descr "Capacitor SMD 0402")
		(tags "capacitor SMD 0402")
		(property "Reference" "C237"
			(at -3.8 -0.29 0)
			(layer "B.SilkS")
			(effects
				(font
					(size 0.7 0.7)
					(thickness 0.15)
				)
				(justify right top mirror)
			)
		)
		(property "Value" "C_100n_0402"
			(at -1.022927 -2.155213 0)
			(layer "B.Fab")
			(effects
				(font
					(size 0.7 0.7)
					(thickness 0.15)
				)
				(justify right top mirror)
			)
		)
		(property "Datasheet" "https://www.murata.com/products/productdetail?partno=GRM155R61H104KE14%23"
			(at 0 0 0)
			(layer "B.Fab")
			(hide yes)
			(effects
				(font
					(size 1.27 1.27)
					(thickness 0.15)
				)
				(justify mirror)
			)
		)
		(property "Description" "SMD Multilayer Ceramic Capacitor, 0.1 µF, 50 V, 0402 [1005 Metric], ± 10%, X5R, GRM Series"
			(at 0 0 0)
			(layer "B.Fab")
			(hide yes)
			(effects
				(font
					(size 1.27 1.27)
					(thickness 0.15)
				)
				(justify mirror)
			)
		)
		(property "MPN" "GRM155R61H104KE14D"
			(at 0 0 180)
			(unlocked yes)
			(layer "B.Fab")
			(hide yes)
			(effects
				(font
					(size 1 1)
					(thickness 0.15)
				)
				(justify mirror)
			)
		)
		(property "Val" "100n"
			(at 0 0 180)
			(unlocked yes)
			(layer "B.Fab")
			(hide yes)
			(effects
				(font
					(size 1 1)
					(thickness 0.15)
				)
				(justify mirror)
			)
		)
		(property "Voltage" "50V"
			(at 0 0 180)
			(unlocked yes)
			(layer "B.Fab")
			(hide yes)
			(effects
				(font
					(size 1 1)
					(thickness 0.15)
				)
				(justify mirror)
			)
		)
		(property "Dielectric" "X5R"
			(at 0 0 180)
			(unlocked yes)
			(layer "B.Fab")
			(hide yes)
			(effects
				(font
					(size 1 1)
					(thickness 0.15)
				)
				(justify mirror)
			)
		)
		(property "Manufacturer" "Murata"
			(at 0 0 180)
			(unlocked yes)
			(layer "B.Fab")
			(hide yes)
			(effects
				(font
					(size 1 1)
					(thickness 0.15)
				)
				(justify mirror)
			)
		)
		(property "License" "Apache-2.0"
			(at 0 0 180)
			(unlocked yes)
			(layer "B.Fab")
			(hide yes)
			(effects
				(font
					(size 1 1)
					(thickness 0.15)
				)
				(justify mirror)
			)
		)
		(property "Author" "Antmicro"
			(at 0 0 180)
			(unlocked yes)
			(layer "B.Fab")
			(hide yes)
			(effects
				(font
					(size 1 1)
					(thickness 0.15)
				)
				(justify mirror)
			)
		)
		(sheetname "/SoM_IO2/")
		(sheetfile "som_io2.kicad_sch")
		(attr smd exclude_from_pos_files exclude_from_bom dnp)
		(fp_rect
			(start -0.925 0.47)
			(end 0.925 -0.47)
			(stroke
				(width 0.05)
				(type default)
			)
			(fill no)
			(layer "B.CrtYd")
		)
		(fp_line
			(start -0.494 -0.248)
			(end -0.494 0.25)
			(stroke
				(width 0.15)
				(type solid)
			)
			(layer "B.Fab")
		)
		(fp_line
			(start -0.494 0.25)
			(end 0.504 0.25)
			(stroke
				(width 0.15)
				(type solid)
			)
			(layer "B.Fab")
		)
		(fp_line
			(start 0.504 -0.248)
			(end -0.494 -0.248)
			(stroke
				(width 0.15)
				(type solid)
			)
			(layer "B.Fab")
		)
		(fp_line
			(start 0.504 0.25)
			(end 0.504 -0.248)
			(stroke
				(width 0.15)
				(type solid)
			)
			(layer "B.Fab")
		)
		(fp_text user "${REFERENCE}"
			(at -0.939 -4.599 0)
			(layer "B.Fab")
			(effects
				(font
					(size 0.7 0.7)
					(thickness 0.15)
				)
				(justify right top mirror)
			)
		)
		(fp_text user "Author: Antmicro"
			(at -0.939 -3.399 0)
			(layer "B.Fab")
			(effects
				(font
					(size 0.7 0.7)
					(thickness 0.15)
				)
				(justify right top mirror)
			)
		)
		(fp_text user "License: Apache-2.0"
			(at -0.939 -5.799 0)
			(layer "B.Fab")
			(effects
				(font
					(size 0.7 0.7)
					(thickness 0.15)
				)
				(justify right top mirror)
			)
		)
		(pad "1" smd roundrect
			(at -0.48 0)
			(size 0.59 0.64)
			(layers "B.Cu" "B.Mask" "B.Paste")
			(roundrect_rratio 0.25)
			(net 1 "GND")
			(pintype "passive")
		)
		(pad "2" smd roundrect
			(at 0.48 0)
			(size 0.59 0.64)
			(layers "B.Cu" "B.Mask" "B.Paste")
			(roundrect_rratio 0.25)
			(net 269 "/SoM_IO2/TC_VCC")
			(pintype "passive")
		)
	)
	(footprint "antmicro-footprints:TP_SMD_0.75mm"
		(layer "B.Cu")
		(at 92.6 69.3 -90)
		(property "Reference" "TP81"
			(at 0 0.6 90)
			(layer "B.SilkS")
			(effects
				(font
					(size 0.7 0.7)
					(thickness 0.15)
				)
				(justify left bottom mirror)
			)
		)
		(property "Value" "TP_0.75mm_SMD"
			(at 0 -1.2 90)
			(layer "B.Fab")
			(effects
				(font
					(size 0.7 0.7)
					(thickness 0.15)
				)
				(justify left bottom mirror)
			)
		)
		(property "Description" "SMT test point"
			(at 0 0 90)
			(layer "B.Fab")
			(hide yes)
			(effects
				(font
					(size 1.27 1.27)
					(thickness 0.15)
				)
				(justify mirror)
			)
		)
		(property "MPN" ""
			(at 0 0 90)
			(unlocked yes)
			(layer "B.Fab")
			(hide yes)
			(effects
				(font
					(size 1 1)
					(thickness 0.15)
				)
				(justify mirror)
			)
		)
		(property "Manufacturer" ""
			(at 0 0 90)
			(unlocked yes)
			(layer "B.Fab")
			(hide yes)
			(effects
				(font
					(size 1 1)
					(thickness 0.15)
				)
				(justify mirror)
			)
		)
		(property "Author" "Antmicro"
			(at 0 0 90)
			(unlocked yes)
			(layer "B.Fab")
			(hide yes)
			(effects
				(font
					(size 1 1)
					(thickness 0.15)
				)
				(justify mirror)
			)
		)
		(property "License" "Apache-2.0"
			(at 0 0 90)
			(unlocked yes)
			(layer "B.Fab")
			(hide yes)
			(effects
				(font
					(size 1 1)
					(thickness 0.15)
				)
				(justify mirror)
			)
		)
		(sheetname "/SoM_Power/")
		(sheetfile "som_power.kicad_sch")
		(attr exclude_from_pos_files exclude_from_bom)
		(fp_circle
			(center 0 0)
			(end 0.475 0)
			(stroke
				(width 0.05)
				(type default)
			)
			(fill no)
			(layer "B.CrtYd")
		)
		(fp_text user "Author: Antmicro"
			(at -0.4 -3.901 90)
			(layer "B.Fab")
			(effects
				(font
					(size 0.7 0.7)
					(thickness 0.15)
				)
				(justify left bottom mirror)
			)
		)
		(fp_text user "${REFERENCE}"
			(at -0.4 -2.7 90)
			(layer "B.Fab")
			(effects
				(font
					(size 0.7 0.7)
					(thickness 0.15)
				)
				(justify left bottom mirror)
			)
		)
		(fp_text user "License: Apache-2.0"
			(at -0.4 -5.101 90)
			(layer "B.Fab")
			(effects
				(font
					(size 0.7 0.7)
					(thickness 0.15)
				)
				(justify left bottom mirror)
			)
		)
		(pad "1" smd circle
			(at 0 0 270)
			(size 0.75 0.75)
			(layers "B.Cu" "B.Mask")
			(net 495 "/SoM_Power/~{FORCE_RECOVERY}")
			(pinfunction "1")
			(pintype "passive")
		)
	)
	(footprint "antmicro-footprints:R_0402_1005Metric"
		(layer "B.Cu")
		(at 224.046 77.865)
		(descr "Resistor SMD 0402")
		(tags "resistor SMD 0402")
		(property "Reference" "R147"
			(at -1.746 -2.265 0)
			(layer "B.SilkS")
			(effects
				(font
					(size 0.7 0.7)
					(thickness 0.15)
				)
				(justify right top mirror)
			)
		)
		(property "Value" "R_27R_0402"
			(at -1.011843 -1.772047 0)
			(layer "B.Fab")
			(effects
				(font
					(size 0.7 0.7)
					(thickness 0.15)
				)
				(justify right top mirror)
			)
		)
		(property "Datasheet" "https://www.bourns.com/docs/product-datasheets/cr.pdf"
			(at 0 0 0)
			(layer "B.Fab")
			(hide yes)
			(effects
				(font
					(size 1.27 1.27)
					(thickness 0.15)
				)
				(justify mirror)
			)
		)
		(property "Description" "SMD Chip Resistor, 27 ohm, ± 1%, 63 mW, 0402 [1005 Metric], Thick Film, General Purpose"
			(at 0 0 0)
			(layer "B.Fab")
			(hide yes)
			(effects
				(font
					(size 1.27 1.27)
					(thickness 0.15)
				)
				(justify mirror)
			)
		)
		(property "Manufacturer" "Bourns"
			(at 0 0 180)
			(unlocked yes)
			(layer "B.Fab")
			(hide yes)
			(effects
				(font
					(size 1 1)
					(thickness 0.15)
				)
				(justify mirror)
			)
		)
		(property "MPN" "CR0402-FX-27R0GLF"
			(at 0 0 180)
			(unlocked yes)
			(layer "B.Fab")
			(hide yes)
			(effects
				(font
					(size 1 1)
					(thickness 0.15)
				)
				(justify mirror)
			)
		)
		(property "Val" "27R"
			(at 0 0 180)
			(unlocked yes)
			(layer "B.Fab")
			(hide yes)
			(effects
				(font
					(size 1 1)
					(thickness 0.15)
				)
				(justify mirror)
			)
		)
		(property "License" "Apache-2.0"
			(at 0 0 180)
			(unlocked yes)
			(layer "B.Fab")
			(hide yes)
			(effects
				(font
					(size 1 1)
					(thickness 0.15)
				)
				(justify mirror)
			)
		)
		(property "Author" "Antmicro"
			(at 0 0 180)
			(unlocked yes)
			(layer "B.Fab")
			(hide yes)
			(effects
				(font
					(size 1 1)
					(thickness 0.15)
				)
				(justify mirror)
			)
		)
		(property "Tolerance" "1%"
			(at 0 0 180)
			(unlocked yes)
			(layer "B.Fab")
			(hide yes)
			(effects
				(font
					(size 1 1)
					(thickness 0.15)
				)
				(justify mirror)
			)
		)
		(sheetname "/USB Debug, PD/")
		(sheetfile "usb_debug_pd.kicad_sch")
		(attr smd)
		(fp_rect
			(start -0.925 0.47)
			(end 0.925 -0.47)
			(stroke
				(width 0.05)
				(type default)
			)
			(fill no)
			(layer "B.CrtYd")
		)
		(fp_rect
			(start -0.5 0.25)
			(end 0.5 -0.25)
			(stroke
				(width 0.15)
				(type solid)
			)
			(fill no)
			(layer "B.Fab")
		)
		(fp_text user "License: Apache-2.0"
			(at -0.95 -5.169 0)
			(layer "B.Fab")
			(effects
				(font
					(size 0.7 0.7)
					(thickness 0.15)
				)
				(justify right top mirror)
			)
		)
		(fp_text user "${REFERENCE}"
			(at -0.95 -3.168 0)
			(layer "B.Fab")
			(effects
				(font
					(size 0.7 0.7)
					(thickness 0.15)
				)
				(justify right top mirror)
			)
		)
		(fp_text user "Author: Antmicro"
			(at -0.95 -4.169 0)
			(layer "B.Fab")
			(effects
				(font
					(size 0.7 0.7)
					(thickness 0.15)
				)
				(justify right top mirror)
			)
		)
		(pad "1" smd roundrect
			(at -0.48 0)
			(size 0.59 0.64)
			(layers "B.Cu" "B.Mask" "B.Paste")
			(roundrect_rratio 0.25)
			(net 973 "/USB Debug, PD/USB_FTDI_P")
			(pintype "passive")
		)
		(pad "2" smd roundrect
			(at 0.48 0)
			(size 0.59 0.64)
			(layers "B.Cu" "B.Mask" "B.Paste")
			(roundrect_rratio 0.25)
			(net 489 "/USB Debug, PD/USBC0_D_P")
			(pintype "passive")
		)
	)
	(footprint "antmicro-footprints:Mech_M2_2242_H2.5mm"
		(layer "B.Cu")
		(at 159.46 129.51 90)
		(property "Reference" "A2"
			(at -0.001 12.11 90)
			(layer "B.SilkS")
			(hide yes)
			(effects
				(font
					(size 0.7 0.7)
					(thickness 0.15)
				)
				(justify left bottom mirror)
			)
		)
		(property "Value" "Mech_M2_2242_H2.5mm"
			(at -0.001 -6.857 90)
			(layer "B.Fab")
			(effects
				(font
					(size 0.7 0.7)
					(thickness 0.15)
				)
				(justify left bottom mirror)
			)
		)
		(property "Description" "Mechanical model for M2 2242 2.5mm module"
			(at 0 0 90)
			(layer "B.Fab")
			(hide yes)
			(effects
				(font
					(size 1.27 1.27)
					(thickness 0.15)
				)
				(justify mirror)
			)
		)
		(property "MPN" ""
			(at 0 0 270)
			(unlocked yes)
			(layer "B.Fab")
			(hide yes)
			(effects
				(font
					(size 1 1)
					(thickness 0.15)
				)
				(justify mirror)
			)
		)
		(property "Manufacturer" ""
			(at 0 0 270)
			(unlocked yes)
			(layer "B.Fab")
			(hide yes)
			(effects
				(font
					(size 1 1)
					(thickness 0.15)
				)
				(justify mirror)
			)
		)
		(property "Author" "Antmicro"
			(at 0 0 270)
			(unlocked yes)
			(layer "B.Fab")
			(hide yes)
			(effects
				(font
					(size 1 1)
					(thickness 0.15)
				)
				(justify mirror)
			)
		)
		(property "License" "Apache-2.0"
			(at 0 0 270)
			(unlocked yes)
			(layer "B.Fab")
			(hide yes)
			(effects
				(font
					(size 1 1)
					(thickness 0.15)
				)
				(justify mirror)
			)
		)
		(sheetname "/M.2/")
		(sheetfile "m2.kicad_sch")
		(attr through_hole exclude_from_pos_files exclude_from_bom allow_missing_courtyard
			dnp
		)
		(fp_text user "${REFERENCE}"
			(at -11 -66.248 90)
			(layer "B.Fab")
			(effects
				(font
					(size 0.7 0.7)
					(thickness 0.15)
				)
				(justify right top mirror)
			)
		)
		(fp_text user "License: Apache-2.0"
			(at -11 -68.65 90)
			(layer "B.Fab")
			(effects
				(font
					(size 0.7 0.7)
					(thickness 0.15)
				)
				(justify right top mirror)
			)
		)
		(fp_text user "Author: Antmicro"
			(at -11 -67.45 90)
			(layer "B.Fab")
			(effects
				(font
					(size 0.7 0.7)
					(thickness 0.15)
				)
				(justify right top mirror)
			)
		)
	)
	(footprint "antmicro-footprints:TP_SMD_0.75mm"
		(layer "B.Cu")
		(at 201.4 116.4 180)
		(property "Reference" "TP68"
			(at 0.4 0.6 90)
			(layer "B.SilkS")
			(effects
				(font
					(size 0.7 0.7)
					(thickness 0.15)
				)
				(justify right top mirror)
			)
		)
		(property "Value" "TP_0.75mm_SMD"
			(at 0 -1.2 180)
			(layer "B.Fab")
			(effects
				(font
					(size 0.7 0.7)
					(thickness 0.15)
				)
				(justify right top mirror)
			)
		)
		(property "Description" "SMT test point"
			(at 0 0 180)
			(layer "B.Fab")
			(hide yes)
			(effects
				(font
					(size 1.27 1.27)
					(thickness 0.15)
				)
				(justify mirror)
			)
		)
		(property "MPN" ""
			(at 0 0 0)
			(unlocked yes)
			(layer "B.Fab")
			(hide yes)
			(effects
				(font
					(size 1 1)
					(thickness 0.15)
				)
				(justify mirror)
			)
		)
		(property "Manufacturer" ""
			(at 0 0 0)
			(unlocked yes)
			(layer "B.Fab")
			(hide yes)
			(effects
				(font
					(size 1 1)
					(thickness 0.15)
				)
				(justify mirror)
			)
		)
		(property "Author" "Antmicro"
			(at 0 0 0)
			(unlocked yes)
			(layer "B.Fab")
			(hide yes)
			(effects
				(font
					(size 1 1)
					(thickness 0.15)
				)
				(justify mirror)
			)
		)
		(property "License" "Apache-2.0"
			(at 0 0 0)
			(unlocked yes)
			(layer "B.Fab")
			(hide yes)
			(effects
				(font
					(size 1 1)
					(thickness 0.15)
				)
				(justify mirror)
			)
		)
		(sheetname "/USB Hub/")
		(sheetfile "usb_hub.kicad_sch")
		(attr exclude_from_pos_files exclude_from_bom)
		(fp_circle
			(center 0 0)
			(end 0.475 0)
			(stroke
				(width 0.05)
				(type default)
			)
			(fill no)
			(layer "B.CrtYd")
		)
		(fp_text user "License: Apache-2.0"
			(at -0.4 -5.101 180)
			(layer "B.Fab")
			(effects
				(font
					(size 0.7 0.7)
					(thickness 0.15)
				)
				(justify right top mirror)
			)
		)
		(fp_text user "${REFERENCE}"
			(at -0.4 -2.7 180)
			(layer "B.Fab")
			(effects
				(font
					(size 0.7 0.7)
					(thickness 0.15)
				)
				(justify right top mirror)
			)
		)
		(fp_text user "Author: Antmicro"
			(at -0.4 -3.901 180)
			(layer "B.Fab")
			(effects
				(font
					(size 0.7 0.7)
					(thickness 0.15)
				)
				(justify right top mirror)
			)
		)
		(pad "1" smd circle
			(at 0 0 180)
			(size 0.75 0.75)
			(layers "B.Cu" "B.Mask")
			(net 1095 "/USB Hub/DP1_VCONN2")
			(pinfunction "1")
			(pintype "passive")
		)
	)
	(footprint "antmicro-footprints:TP_SMD_0.75mm"
		(layer "B.Cu")
		(at 137.7 82.65 90)
		(property "Reference" "TP33"
			(at -3.05 -1.2 90)
			(layer "B.SilkS")
			(effects
				(font
					(size 0.7 0.7)
					(thickness 0.15)
				)
				(justify right top mirror)
			)
		)
		(property "Value" "TP_0.75mm_SMD"
			(at 0 -1.2 90)
			(layer "B.Fab")
			(effects
				(font
					(size 0.7 0.7)
					(thickness 0.15)
				)
				(justify right top mirror)
			)
		)
		(property "Description" "SMT test point"
			(at 0 0 90)
			(layer "B.Fab")
			(hide yes)
			(effects
				(font
					(size 1.27 1.27)
					(thickness 0.15)
				)
				(justify mirror)
			)
		)
		(property "MPN" ""
			(at 0 0 270)
			(unlocked yes)
			(layer "B.Fab")
			(hide yes)
			(effects
				(font
					(size 1 1)
					(thickness 0.15)
				)
				(justify mirror)
			)
		)
		(property "Manufacturer" ""
			(at 0 0 270)
			(unlocked yes)
			(layer "B.Fab")
			(hide yes)
			(effects
				(font
					(size 1 1)
					(thickness 0.15)
				)
				(justify mirror)
			)
		)
		(property "Author" "Antmicro"
			(at 0 0 270)
			(unlocked yes)
			(layer "B.Fab")
			(hide yes)
			(effects
				(font
					(size 1 1)
					(thickness 0.15)
				)
				(justify mirror)
			)
		)
		(property "License" "Apache-2.0"
			(at 0 0 270)
			(unlocked yes)
			(layer "B.Fab")
			(hide yes)
			(effects
				(font
					(size 1 1)
					(thickness 0.15)
				)
				(justify mirror)
			)
		)
		(sheetname "/SoM_Power/")
		(sheetfile "som_power.kicad_sch")
		(attr exclude_from_pos_files exclude_from_bom)
		(fp_circle
			(center 0 0)
			(end 0.475 0)
			(stroke
				(width 0.05)
				(type default)
			)
			(fill no)
			(layer "B.CrtYd")
		)
		(fp_text user "${REFERENCE}"
			(at -0.4 -2.7 90)
			(layer "B.Fab")
			(effects
				(font
					(size 0.7 0.7)
					(thickness 0.15)
				)
				(justify right top mirror)
			)
		)
		(fp_text user "Author: Antmicro"
			(at -0.4 -3.901 90)
			(layer "B.Fab")
			(effects
				(font
					(size 0.7 0.7)
					(thickness 0.15)
				)
				(justify right top mirror)
			)
		)
		(fp_text user "License: Apache-2.0"
			(at -0.4 -5.101 90)
			(layer "B.Fab")
			(effects
				(font
					(size 0.7 0.7)
					(thickness 0.15)
				)
				(justify right top mirror)
			)
		)
		(pad "1" smd circle
			(at 0 0 90)
			(size 0.75 0.75)
			(layers "B.Cu" "B.Mask")
			(net 907 "Net-(J1A-GPIO39)")
			(pinfunction "1")
			(pintype "passive")
		)
	)
	(footprint "antmicro-footprints:R_0402_1005Metric"
		(layer "B.Cu")
		(at 124.6 105.8 180)
		(descr "Resistor SMD 0402")
		(tags "resistor SMD 0402")
		(property "Reference" "R209"
			(at -3.9 -0.4 0)
			(layer "B.SilkS")
			(effects
				(font
					(size 0.7 0.7)
					(thickness 0.15)
				)
				(justify left bottom mirror)
			)
		)
		(property "Value" "R_47k_0402"
			(at -1.011843 -1.772046 0)
			(layer "B.Fab")
			(effects
				(font
					(size 0.7 0.7)
					(thickness 0.15)
				)
				(justify left bottom mirror)
			)
		)
		(property "Datasheet" "https://www.bourns.com/docs/product-datasheets/cr.pdf"
			(at 0 0 0)
			(layer "B.Fab")
			(hide yes)
			(effects
				(font
					(size 1.27 1.27)
					(thickness 0.15)
				)
				(justify mirror)
			)
		)
		(property "Description" "SMD Chip Resistor, 47 kohm, ± 1%, 62.5 mW, 0402 [1005 Metric], Thick Film, General Purpose"
			(at 0 0 0)
			(layer "B.Fab")
			(hide yes)
			(effects
				(font
					(size 1.27 1.27)
					(thickness 0.15)
				)
				(justify mirror)
			)
		)
		(property "Manufacturer" "Bourns"
			(at 0 0 0)
			(unlocked yes)
			(layer "B.Fab")
			(hide yes)
			(effects
				(font
					(size 1 1)
					(thickness 0.15)
				)
				(justify mirror)
			)
		)
		(property "MPN" "CR0402-FX-4702GLF"
			(at 0 0 0)
			(unlocked yes)
			(layer "B.Fab")
			(hide yes)
			(effects
				(font
					(size 1 1)
					(thickness 0.15)
				)
				(justify mirror)
			)
		)
		(property "Val" "47k"
			(at 0 0 0)
			(unlocked yes)
			(layer "B.Fab")
			(hide yes)
			(effects
				(font
					(size 1 1)
					(thickness 0.15)
				)
				(justify mirror)
			)
		)
		(property "License" "Apache-2.0"
			(at 0 0 0)
			(unlocked yes)
			(layer "B.Fab")
			(hide yes)
			(effects
				(font
					(size 1 1)
					(thickness 0.15)
				)
				(justify mirror)
			)
		)
		(property "Author" "Antmicro"
			(at 0 0 0)
			(unlocked yes)
			(layer "B.Fab")
			(hide yes)
			(effects
				(font
					(size 1 1)
					(thickness 0.15)
				)
				(justify mirror)
			)
		)
		(property "Tolerance" "1%"
			(at 0 0 0)
			(unlocked yes)
			(layer "B.Fab")
			(hide yes)
			(effects
				(font
					(size 1 1)
					(thickness 0.15)
				)
				(justify mirror)
			)
		)
		(sheetname "/M.2/")
		(sheetfile "m2.kicad_sch")
		(attr smd exclude_from_pos_files exclude_from_bom dnp)
		(fp_poly
			(pts
				(xy -0.925 0.47) (xy 0.925 0.47) (xy 0.925 -0.47) (xy -0.925 -0.47)
			)
			(stroke
				(width 0.05)
				(type default)
			)
			(fill no)
			(layer "B.CrtYd")
		)
		(fp_poly
			(pts
				(xy -0.5 0.25) (xy 0.5 0.25) (xy 0.5 -0.25) (xy -0.5 -0.25)
			)
			(stroke
				(width 0.15)
				(type solid)
			)
			(fill no)
			(layer "B.Fab")
		)
		(fp_text user "License: Apache-2.0"
			(at -0.949999 -5.169 0)
			(layer "B.Fab")
			(effects
				(font
					(size 0.7 0.7)
					(thickness 0.15)
				)
				(justify left bottom mirror)
			)
		)
		(fp_text user "Author: Antmicro"
			(at -0.95 -4.169 0)
			(layer "B.Fab")
			(effects
				(font
					(size 0.7 0.7)
					(thickness 0.15)
				)
				(justify left bottom mirror)
			)
		)
		(fp_text user "${REFERENCE}"
			(at -0.95 -3.168 0)
			(layer "B.Fab")
			(effects
				(font
					(size 0.7 0.7)
					(thickness 0.15)
				)
				(justify left bottom mirror)
			)
		)
		(pad "1" smd roundrect
			(at -0.48 0 180)
			(size 0.59 0.64)
			(layers "B.Cu" "B.Mask" "B.Paste")
			(roundrect_rratio 0.25)
			(net 2 "+3V3")
			(pintype "passive")
		)
		(pad "2" smd roundrect
			(at 0.48 0 180)
			(size 0.59 0.64)
			(layers "B.Cu" "B.Mask" "B.Paste")
			(roundrect_rratio 0.25)
			(net 827 "/M.2/~{PERST_M}")
			(pintype "passive")
		)
	)
	(footprint "antmicro-footprints:C_0402_1005Metric"
		(layer "B.Cu")
		(at 178.37 93.1 180)
		(descr "Capacitor SMD 0402")
		(tags "capacitor SMD 0402")
		(property "Reference" "C38"
			(at -0.66 -1.48 0)
			(layer "B.SilkS")
			(effects
				(font
					(size 0.7 0.7)
					(thickness 0.15)
				)
				(justify left bottom mirror)
			)
		)
		(property "Value" "C_100n_0402"
			(at -1.022927 -2.155213 0)
			(layer "B.Fab")
			(effects
				(font
					(size 0.7 0.7)
					(thickness 0.15)
				)
				(justify left bottom mirror)
			)
		)
		(property "Datasheet" "https://www.murata.com/products/productdetail?partno=GRM155R61H104KE14%23"
			(at 0 0 0)
			(layer "B.Fab")
			(hide yes)
			(effects
				(font
					(size 1.27 1.27)
					(thickness 0.15)
				)
				(justify mirror)
			)
		)
		(property "Description" "SMD Multilayer Ceramic Capacitor, 0.1 µF, 50 V, 0402 [1005 Metric], ± 10%, X5R, GRM Series"
			(at 0 0 0)
			(layer "B.Fab")
			(hide yes)
			(effects
				(font
					(size 1.27 1.27)
					(thickness 0.15)
				)
				(justify mirror)
			)
		)
		(property "MPN" "GRM155R61H104KE14D"
			(at 0 0 0)
			(unlocked yes)
			(layer "B.Fab")
			(hide yes)
			(effects
				(font
					(size 1 1)
					(thickness 0.15)
				)
				(justify mirror)
			)
		)
		(property "Manufacturer" "Murata"
			(at 0 0 0)
			(unlocked yes)
			(layer "B.Fab")
			(hide yes)
			(effects
				(font
					(size 1 1)
					(thickness 0.15)
				)
				(justify mirror)
			)
		)
		(property "License" "Apache-2.0"
			(at 0 0 0)
			(unlocked yes)
			(layer "B.Fab")
			(hide yes)
			(effects
				(font
					(size 1 1)
					(thickness 0.15)
				)
				(justify mirror)
			)
		)
		(property "Author" "Antmicro"
			(at 0 0 0)
			(unlocked yes)
			(layer "B.Fab")
			(hide yes)
			(effects
				(font
					(size 1 1)
					(thickness 0.15)
				)
				(justify mirror)
			)
		)
		(property "Val" "100n"
			(at 0 0 0)
			(unlocked yes)
			(layer "B.Fab")
			(hide yes)
			(effects
				(font
					(size 1 1)
					(thickness 0.15)
				)
				(justify mirror)
			)
		)
		(property "Voltage" "50V"
			(at 0 0 0)
			(unlocked yes)
			(layer "B.Fab")
			(hide yes)
			(effects
				(font
					(size 1 1)
					(thickness 0.15)
				)
				(justify mirror)
			)
		)
		(property "Dielectric" "X5R"
			(at 0 0 0)
			(unlocked yes)
			(layer "B.Fab")
			(hide yes)
			(effects
				(font
					(size 1 1)
					(thickness 0.15)
				)
				(justify mirror)
			)
		)
		(property "Public" "False"
			(at 0 0 0)
			(unlocked yes)
			(layer "B.Fab")
			(hide yes)
			(effects
				(font
					(size 1 1)
					(thickness 0.15)
				)
				(justify mirror)
			)
		)
		(sheetname "/Power/")
		(sheetfile "power.kicad_sch")
		(attr smd exclude_from_pos_files exclude_from_bom dnp)
		(fp_rect
			(start -0.925 0.47)
			(end 0.925 -0.47)
			(stroke
				(width 0.05)
				(type default)
			)
			(fill no)
			(layer "B.CrtYd")
		)
		(fp_line
			(start 0.504 0.25)
			(end 0.504 -0.248)
			(stroke
				(width 0.15)
				(type solid)
			)
			(layer "B.Fab")
		)
		(fp_line
			(start 0.504 -0.248)
			(end -0.494 -0.248)
			(stroke
				(width 0.15)
				(type solid)
			)
			(layer "B.Fab")
		)
		(fp_line
			(start -0.494 0.25)
			(end 0.504 0.25)
			(stroke
				(width 0.15)
				(type solid)
			)
			(layer "B.Fab")
		)
		(fp_line
			(start -0.494 -0.248)
			(end -0.494 0.25)
			(stroke
				(width 0.15)
				(type solid)
			)
			(layer "B.Fab")
		)
		(fp_text user "License: Apache-2.0"
			(at -0.939 -5.799 0)
			(layer "B.Fab")
			(effects
				(font
					(size 0.7 0.7)
					(thickness 0.15)
				)
				(justify left bottom mirror)
			)
		)
		(fp_text user "Author: Antmicro"
			(at -0.939 -3.399 0)
			(layer "B.Fab")
			(effects
				(font
					(size 0.7 0.7)
					(thickness 0.15)
				)
				(justify left bottom mirror)
			)
		)
		(fp_text user "${REFERENCE}"
			(at -0.939 -4.599 0)
			(layer "B.Fab")
			(effects
				(font
					(size 0.7 0.7)
					(thickness 0.15)
				)
				(justify left bottom mirror)
			)
		)
		(pad "1" smd roundrect
			(at -0.48 0 180)
			(size 0.59 0.64)
			(layers "B.Cu" "B.Mask" "B.Paste")
			(roundrect_rratio 0.25)
			(net 1 "GND")
			(pintype "passive")
		)
		(pad "2" smd roundrect
			(at 0.48 0 180)
			(size 0.59 0.64)
			(layers "B.Cu" "B.Mask" "B.Paste")
			(roundrect_rratio 0.25)
			(net 522 "/Power/USBPD1_HV")
			(pintype "passive")
		)
	)
	(footprint "antmicro-footprints:R_0402_1005Metric"
		(layer "B.Cu")
		(at 215.93 95.1 90)
		(descr "Resistor SMD 0402")
		(tags "resistor SMD 0402")
		(property "Reference" "R227"
			(at -3.8 -0.35 90)
			(layer "B.SilkS")
			(effects
				(font
					(size 0.7 0.7)
					(thickness 0.15)
				)
				(justify right top mirror)
			)
		)
		(property "Value" "R_0R_0402"
			(at -1.011843 -1.772047 90)
			(layer "B.Fab")
			(effects
				(font
					(size 0.7 0.7)
					(thickness 0.15)
				)
				(justify right top mirror)
			)
		)
		(property "Datasheet" "https://industrial.panasonic.com/cdbs/www-data/pdf/RDA0000/AOA0000C301.pdf"
			(at 0 0 90)
			(layer "B.Fab")
			(hide yes)
			(effects
				(font
					(size 1.27 1.27)
					(thickness 0.15)
				)
				(justify mirror)
			)
		)
		(property "Description" "SMD Chip Resistor, Jumper, 0 ohm, 100 mW, 0402 [1005 Metric], Thick Film, General Purpose"
			(at 0 0 90)
			(layer "B.Fab")
			(hide yes)
			(effects
				(font
					(size 1.27 1.27)
					(thickness 0.15)
				)
				(justify mirror)
			)
		)
		(property "Manufacturer" "Panasonic"
			(at 0 0 270)
			(unlocked yes)
			(layer "B.Fab")
			(hide yes)
			(effects
				(font
					(size 1 1)
					(thickness 0.15)
				)
				(justify mirror)
			)
		)
		(property "MPN" "ERJ2GE0R00X"
			(at 0 0 270)
			(unlocked yes)
			(layer "B.Fab")
			(hide yes)
			(effects
				(font
					(size 1 1)
					(thickness 0.15)
				)
				(justify mirror)
			)
		)
		(property "Val" "0R"
			(at 0 0 270)
			(unlocked yes)
			(layer "B.Fab")
			(hide yes)
			(effects
				(font
					(size 1 1)
					(thickness 0.15)
				)
				(justify mirror)
			)
		)
		(property "License" "Apache-2.0"
			(at 0 0 270)
			(unlocked yes)
			(layer "B.Fab")
			(hide yes)
			(effects
				(font
					(size 1 1)
					(thickness 0.15)
				)
				(justify mirror)
			)
		)
		(property "Author" "Antmicro"
			(at 0 0 270)
			(unlocked yes)
			(layer "B.Fab")
			(hide yes)
			(effects
				(font
					(size 1 1)
					(thickness 0.15)
				)
				(justify mirror)
			)
		)
		(property "Tolerance" "~"
			(at 0 0 270)
			(unlocked yes)
			(layer "B.Fab")
			(hide yes)
			(effects
				(font
					(size 1 1)
					(thickness 0.15)
				)
				(justify mirror)
			)
		)
		(property "Current" "1A"
			(at 0 0 270)
			(unlocked yes)
			(layer "B.Fab")
			(hide yes)
			(effects
				(font
					(size 1 1)
					(thickness 0.15)
				)
				(justify mirror)
			)
		)
		(sheetname "/USB DP Alt mode/")
		(sheetfile "usb_dp.kicad_sch")
		(attr smd)
		(fp_rect
			(start -0.925 0.47)
			(end 0.925 -0.47)
			(stroke
				(width 0.05)
				(type default)
			)
			(fill no)
			(layer "B.CrtYd")
		)
		(fp_rect
			(start -0.5 0.25)
			(end 0.5 -0.25)
			(stroke
				(width 0.15)
				(type solid)
			)
			(fill no)
			(layer "B.Fab")
		)
		(fp_text user "Author: Antmicro"
			(at -0.95 -4.169 90)
			(layer "B.Fab")
			(effects
				(font
					(size 0.7 0.7)
					(thickness 0.15)
				)
				(justify right top mirror)
			)
		)
		(fp_text user "${REFERENCE}"
			(at -0.95 -3.168 90)
			(layer "B.Fab")
			(effects
				(font
					(size 0.7 0.7)
					(thickness 0.15)
				)
				(justify right top mirror)
			)
		)
		(fp_text user "License: Apache-2.0"
			(at -0.95 -5.169 90)
			(layer "B.Fab")
			(effects
				(font
					(size 0.7 0.7)
					(thickness 0.15)
				)
				(justify right top mirror)
			)
		)
		(pad "1" smd roundrect
			(at -0.48 0 90)
			(size 0.59 0.64)
			(layers "B.Cu" "B.Mask" "B.Paste")
			(roundrect_rratio 0.25)
			(net 948 "/USB DP Alt mode/USBC_HPD")
			(pintype "passive")
		)
		(pad "2" smd roundrect
			(at 0.48 0 90)
			(size 0.59 0.64)
			(layers "B.Cu" "B.Mask" "B.Paste")
			(roundrect_rratio 0.25)
			(net 957 "/USB DP Alt mode/HPDIN")
			(pintype "passive")
		)
	)
	(footprint "antmicro-footprints:R_0402_1005Metric"
		(layer "B.Cu")
		(at 198.6 70.6 -90)
		(descr "Resistor SMD 0402")
		(tags "resistor SMD 0402")
		(property "Reference" "R103"
			(at -1.2 -3.5 90)
			(layer "B.SilkS")
			(effects
				(font
					(size 0.7 0.7)
					(thickness 0.15)
				)
				(justify left bottom mirror)
			)
		)
		(property "Value" "R_4k7_0402"
			(at -1.011843 -1.772046 90)
			(layer "B.Fab")
			(effects
				(font
					(size 0.7 0.7)
					(thickness 0.15)
				)
				(justify left bottom mirror)
			)
		)
		(property "Datasheet" "https://www.bourns.com/docs/product-datasheets/cr.pdf"
			(at 0 0 90)
			(layer "B.Fab")
			(hide yes)
			(effects
				(font
					(size 1.27 1.27)
					(thickness 0.15)
				)
				(justify mirror)
			)
		)
		(property "Description" "SMD Chip Resistor, 4.7 kohm, ± 1%, 62.5 mW, 0402 [1005 Metric], Thick Film, General Purpose"
			(at 0 0 90)
			(layer "B.Fab")
			(hide yes)
			(effects
				(font
					(size 1.27 1.27)
					(thickness 0.15)
				)
				(justify mirror)
			)
		)
		(property "Manufacturer" "Bourns"
			(at 0 0 90)
			(unlocked yes)
			(layer "B.Fab")
			(hide yes)
			(effects
				(font
					(size 1 1)
					(thickness 0.15)
				)
				(justify mirror)
			)
		)
		(property "MPN" "CR0402-FX-4701GLF"
			(at 0 0 90)
			(unlocked yes)
			(layer "B.Fab")
			(hide yes)
			(effects
				(font
					(size 1 1)
					(thickness 0.15)
				)
				(justify mirror)
			)
		)
		(property "Val" "4k7"
			(at 0 0 90)
			(unlocked yes)
			(layer "B.Fab")
			(hide yes)
			(effects
				(font
					(size 1 1)
					(thickness 0.15)
				)
				(justify mirror)
			)
		)
		(property "License" "Apache-2.0"
			(at 0 0 90)
			(unlocked yes)
			(layer "B.Fab")
			(hide yes)
			(effects
				(font
					(size 1 1)
					(thickness 0.15)
				)
				(justify mirror)
			)
		)
		(property "Author" "Antmicro"
			(at 0 0 90)
			(unlocked yes)
			(layer "B.Fab")
			(hide yes)
			(effects
				(font
					(size 1 1)
					(thickness 0.15)
				)
				(justify mirror)
			)
		)
		(property "Tolerance" "1%"
			(at 0 0 90)
			(unlocked yes)
			(layer "B.Fab")
			(hide yes)
			(effects
				(font
					(size 1 1)
					(thickness 0.15)
				)
				(justify mirror)
			)
		)
		(sheetname "/USB Debug, PD/")
		(sheetfile "usb_debug_pd.kicad_sch")
		(attr smd exclude_from_pos_files exclude_from_bom dnp)
		(fp_poly
			(pts
				(xy -0.925 0.47) (xy 0.925 0.47) (xy 0.925 -0.47) (xy -0.925 -0.47)
			)
			(stroke
				(width 0.05)
				(type default)
			)
			(fill no)
			(layer "B.CrtYd")
		)
		(fp_poly
			(pts
				(xy -0.5 0.25) (xy 0.5 0.25) (xy 0.5 -0.25) (xy -0.5 -0.25)
			)
			(stroke
				(width 0.15)
				(type solid)
			)
			(fill no)
			(layer "B.Fab")
		)
		(fp_text user "${REFERENCE}"
			(at -0.95 -3.168 90)
			(layer "B.Fab")
			(effects
				(font
					(size 0.7 0.7)
					(thickness 0.15)
				)
				(justify left bottom mirror)
			)
		)
		(fp_text user "Author: Antmicro"
			(at -0.95 -4.169 90)
			(layer "B.Fab")
			(effects
				(font
					(size 0.7 0.7)
					(thickness 0.15)
				)
				(justify left bottom mirror)
			)
		)
		(fp_text user "License: Apache-2.0"
			(at -0.949999 -5.169 90)
			(layer "B.Fab")
			(effects
				(font
					(size 0.7 0.7)
					(thickness 0.15)
				)
				(justify left bottom mirror)
			)
		)
		(pad "1" smd roundrect
			(at -0.48 0 270)
			(size 0.59 0.64)
			(layers "B.Cu" "B.Mask" "B.Paste")
			(roundrect_rratio 0.25)
			(net 2 "+3V3")
			(pintype "passive")
		)
		(pad "2" smd roundrect
			(at 0.48 0 270)
			(size 0.59 0.64)
			(layers "B.Cu" "B.Mask" "B.Paste")
			(roundrect_rratio 0.25)
			(net 945 "/USB Debug, PD/DEBUG_SCL")
			(pintype "passive")
		)
	)
	(footprint "antmicro-footprints:R_0402_1005Metric"
		(layer "B.Cu")
		(at 227.4 95.4 -90)
		(descr "Resistor SMD 0402")
		(tags "resistor SMD 0402")
		(property "Reference" "R127"
			(at -1.225998 0.8 90)
			(layer "B.SilkS")
			(effects
				(font
					(size 0.7 0.7)
					(thickness 0.15)
				)
				(justify left bottom mirror)
			)
		)
		(property "Value" "R_10k_0402"
			(at -1.011843 -1.772046 90)
			(layer "B.Fab")
			(effects
				(font
					(size 0.7 0.7)
					(thickness 0.15)
				)
				(justify left bottom mirror)
			)
		)
		(property "Datasheet" "https://www.bourns.com/docs/product-datasheets/cr.pdf"
			(at 0 0 90)
			(layer "B.Fab")
			(hide yes)
			(effects
				(font
					(size 1.27 1.27)
					(thickness 0.15)
				)
				(justify mirror)
			)
		)
		(property "Description" "SMD Chip Resistor, 10 kohm, ± 1%, 62.5 mW, 0402 [1005 Metric], Thick Film, General Purpose"
			(at 0 0 90)
			(layer "B.Fab")
			(hide yes)
			(effects
				(font
					(size 1.27 1.27)
					(thickness 0.15)
				)
				(justify mirror)
			)
		)
		(property "Manufacturer" "Bourns"
			(at 0 0 90)
			(unlocked yes)
			(layer "B.Fab")
			(hide yes)
			(effects
				(font
					(size 1 1)
					(thickness 0.15)
				)
				(justify mirror)
			)
		)
		(property "MPN" "CR0402-FX-1002GLF"
			(at 0 0 90)
			(unlocked yes)
			(layer "B.Fab")
			(hide yes)
			(effects
				(font
					(size 1 1)
					(thickness 0.15)
				)
				(justify mirror)
			)
		)
		(property "Val" "10k"
			(at 0 0 90)
			(unlocked yes)
			(layer "B.Fab")
			(hide yes)
			(effects
				(font
					(size 1 1)
					(thickness 0.15)
				)
				(justify mirror)
			)
		)
		(property "License" "Apache-2.0"
			(at 0 0 90)
			(unlocked yes)
			(layer "B.Fab")
			(hide yes)
			(effects
				(font
					(size 1 1)
					(thickness 0.15)
				)
				(justify mirror)
			)
		)
		(property "Author" "Antmicro"
			(at 0 0 90)
			(unlocked yes)
			(layer "B.Fab")
			(hide yes)
			(effects
				(font
					(size 1 1)
					(thickness 0.15)
				)
				(justify mirror)
			)
		)
		(property "Tolerance" "1%"
			(at 0 0 90)
			(unlocked yes)
			(layer "B.Fab")
			(hide yes)
			(effects
				(font
					(size 1 1)
					(thickness 0.15)
				)
				(justify mirror)
			)
		)
		(sheetname "/USB DP Alt mode/")
		(sheetfile "usb_dp.kicad_sch")
		(attr smd)
		(fp_poly
			(pts
				(xy -0.925 0.47) (xy -0.925 -0.47) (xy 0.925 -0.47) (xy 0.925 0.47)
			)
			(stroke
				(width 0.05)
				(type default)
			)
			(fill no)
			(layer "B.CrtYd")
		)
		(fp_poly
			(pts
				(xy -0.5 0.25) (xy -0.5 -0.25) (xy 0.5 -0.25) (xy 0.5 0.25)
			)
			(stroke
				(width 0.15)
				(type solid)
			)
			(fill no)
			(layer "B.Fab")
		)
		(fp_text user "License: Apache-2.0"
			(at -0.949999 -5.169 90)
			(layer "B.Fab")
			(effects
				(font
					(size 0.7 0.7)
					(thickness 0.15)
				)
				(justify left bottom mirror)
			)
		)
		(fp_text user "Author: Antmicro"
			(at -0.95 -4.169 90)
			(layer "B.Fab")
			(effects
				(font
					(size 0.7 0.7)
					(thickness 0.15)
				)
				(justify left bottom mirror)
			)
		)
		(fp_text user "${REFERENCE}"
			(at -0.95 -3.168 90)
			(layer "B.Fab")
			(effects
				(font
					(size 0.7 0.7)
					(thickness 0.15)
				)
				(justify left bottom mirror)
			)
		)
		(pad "1" smd roundrect
			(at -0.48 0 270)
			(size 0.59 0.64)
			(layers "B.Cu" "B.Mask" "B.Paste")
			(roundrect_rratio 0.25)
			(net 962 "/SoM_IO/USBC1_FLG")
			(pintype "passive")
		)
		(pad "2" smd roundrect
			(at 0.48 0 270)
			(size 0.59 0.64)
			(layers "B.Cu" "B.Mask" "B.Paste")
			(roundrect_rratio 0.25)
			(net 2 "+3V3")
			(pintype "passive")
		)
	)
	(footprint "antmicro-footprints:C_0402_1005Metric"
		(layer "B.Cu")
		(at 205.9 79.2 180)
		(descr "Capacitor SMD 0402")
		(tags "capacitor SMD 0402")
		(property "Reference" "C118"
			(at -1.090532 -1.4 0)
			(layer "B.SilkS")
			(effects
				(font
					(size 0.7 0.7)
					(thickness 0.15)
				)
				(justify left bottom mirror)
			)
		)
		(property "Value" "C_10u_0402"
			(at -1.022927 -2.155213 0)
			(layer "B.Fab")
			(effects
				(font
					(size 0.7 0.7)
					(thickness 0.15)
				)
				(justify left bottom mirror)
			)
		)
		(property "Datasheet" "https://www.yageo.com/en/Chart/Download/pdf/CC0402MRX5R5BB106"
			(at 0 0 0)
			(layer "B.Fab")
			(hide yes)
			(effects
				(font
					(size 1.27 1.27)
					(thickness 0.15)
				)
				(justify mirror)
			)
		)
		(property "Description" "SMD Multilayer Ceramic Capacitor, 10 µF, 6.3 V, 0402 [1005 Metric], ± 20%, X5R, CC Series"
			(at 0 0 0)
			(layer "B.Fab")
			(hide yes)
			(effects
				(font
					(size 1.27 1.27)
					(thickness 0.15)
				)
				(justify mirror)
			)
		)
		(property "MPN" "CC0402MRX5R5BB106"
			(at 0 0 0)
			(unlocked yes)
			(layer "B.Fab")
			(hide yes)
			(effects
				(font
					(size 1 1)
					(thickness 0.15)
				)
				(justify mirror)
			)
		)
		(property "Manufacturer" "YAGEO"
			(at 0 0 0)
			(unlocked yes)
			(layer "B.Fab")
			(hide yes)
			(effects
				(font
					(size 1 1)
					(thickness 0.15)
				)
				(justify mirror)
			)
		)
		(property "License" "Apache-2.0"
			(at 0 0 0)
			(unlocked yes)
			(layer "B.Fab")
			(hide yes)
			(effects
				(font
					(size 1 1)
					(thickness 0.15)
				)
				(justify mirror)
			)
		)
		(property "Author" "Antmicro"
			(at 0 0 0)
			(unlocked yes)
			(layer "B.Fab")
			(hide yes)
			(effects
				(font
					(size 1 1)
					(thickness 0.15)
				)
				(justify mirror)
			)
		)
		(property "Val" "10u"
			(at 0 0 0)
			(unlocked yes)
			(layer "B.Fab")
			(hide yes)
			(effects
				(font
					(size 1 1)
					(thickness 0.15)
				)
				(justify mirror)
			)
		)
		(property "Voltage" ""
			(at 0 0 0)
			(unlocked yes)
			(layer "B.Fab")
			(hide yes)
			(effects
				(font
					(size 1 1)
					(thickness 0.15)
				)
				(justify mirror)
			)
		)
		(property "Dielectric" ""
			(at 0 0 0)
			(unlocked yes)
			(layer "B.Fab")
			(hide yes)
			(effects
				(font
					(size 1 1)
					(thickness 0.15)
				)
				(justify mirror)
			)
		)
		(sheetname "/USB Debug, PD/")
		(sheetfile "usb_debug_pd.kicad_sch")
		(attr smd)
		(fp_rect
			(start -0.925 0.47)
			(end 0.925 -0.47)
			(stroke
				(width 0.05)
				(type default)
			)
			(fill no)
			(layer "B.CrtYd")
		)
		(fp_line
			(start 0.504 0.25)
			(end 0.504 -0.248)
			(stroke
				(width 0.15)
				(type solid)
			)
			(layer "B.Fab")
		)
		(fp_line
			(start 0.504 -0.248)
			(end -0.494 -0.248)
			(stroke
				(width 0.15)
				(type solid)
			)
			(layer "B.Fab")
		)
		(fp_line
			(start -0.494 0.25)
			(end 0.504 0.25)
			(stroke
				(width 0.15)
				(type solid)
			)
			(layer "B.Fab")
		)
		(fp_line
			(start -0.494 -0.248)
			(end -0.494 0.25)
			(stroke
				(width 0.15)
				(type solid)
			)
			(layer "B.Fab")
		)
		(fp_text user "Author: Antmicro"
			(at -0.939 -3.399 0)
			(layer "B.Fab")
			(effects
				(font
					(size 0.7 0.7)
					(thickness 0.15)
				)
				(justify left bottom mirror)
			)
		)
		(fp_text user "${REFERENCE}"
			(at -0.939 -4.599 0)
			(layer "B.Fab")
			(effects
				(font
					(size 0.7 0.7)
					(thickness 0.15)
				)
				(justify left bottom mirror)
			)
		)
		(fp_text user "License: Apache-2.0"
			(at -0.939 -5.799 0)
			(layer "B.Fab")
			(effects
				(font
					(size 0.7 0.7)
					(thickness 0.15)
				)
				(justify left bottom mirror)
			)
		)
		(pad "1" smd roundrect
			(at -0.48 0 180)
			(size 0.59 0.64)
			(layers "B.Cu" "B.Mask" "B.Paste")
			(roundrect_rratio 0.25)
			(net 1 "GND")
			(pintype "passive")
		)
		(pad "2" smd roundrect
			(at 0.48 0 180)
			(size 0.59 0.64)
			(layers "B.Cu" "B.Mask" "B.Paste")
			(roundrect_rratio 0.25)
			(net 2 "+3V3")
			(pintype "passive")
		)
	)
	(footprint "antmicro-footprints:TP_SMD_0.75mm"
		(layer "B.Cu")
		(at 195.8 123.8 180)
		(property "Reference" "TP40"
			(at 3.4 0.4 180)
			(layer "B.SilkS")
			(effects
				(font
					(size 0.7 0.7)
					(thickness 0.15)
				)
				(justify right top mirror)
			)
		)
		(property "Value" "TP_0.75mm_SMD"
			(at 0 -1.2 180)
			(layer "B.Fab")
			(effects
				(font
					(size 0.7 0.7)
					(thickness 0.15)
				)
				(justify right top mirror)
			)
		)
		(property "Description" "SMT test point"
			(at 0 0 180)
			(layer "B.Fab")
			(hide yes)
			(effects
				(font
					(size 1.27 1.27)
					(thickness 0.15)
				)
				(justify mirror)
			)
		)
		(property "MPN" ""
			(at 0 0 0)
			(unlocked yes)
			(layer "B.Fab")
			(hide yes)
			(effects
				(font
					(size 1 1)
					(thickness 0.15)
				)
				(justify mirror)
			)
		)
		(property "Manufacturer" ""
			(at 0 0 0)
			(unlocked yes)
			(layer "B.Fab")
			(hide yes)
			(effects
				(font
					(size 1 1)
					(thickness 0.15)
				)
				(justify mirror)
			)
		)
		(property "Author" "Antmicro"
			(at 0 0 0)
			(unlocked yes)
			(layer "B.Fab")
			(hide yes)
			(effects
				(font
					(size 1 1)
					(thickness 0.15)
				)
				(justify mirror)
			)
		)
		(property "License" "Apache-2.0"
			(at 0 0 0)
			(unlocked yes)
			(layer "B.Fab")
			(hide yes)
			(effects
				(font
					(size 1 1)
					(thickness 0.15)
				)
				(justify mirror)
			)
		)
		(sheetname "/USB Hub/")
		(sheetfile "usb_hub.kicad_sch")
		(attr exclude_from_pos_files exclude_from_bom)
		(fp_circle
			(center 0 0)
			(end 0.475 0)
			(stroke
				(width 0.05)
				(type default)
			)
			(fill no)
			(layer "B.CrtYd")
		)
		(fp_text user "License: Apache-2.0"
			(at -0.4 -5.101 180)
			(layer "B.Fab")
			(effects
				(font
					(size 0.7 0.7)
					(thickness 0.15)
				)
				(justify right top mirror)
			)
		)
		(fp_text user "Author: Antmicro"
			(at -0.4 -3.901 180)
			(layer "B.Fab")
			(effects
				(font
					(size 0.7 0.7)
					(thickness 0.15)
				)
				(justify right top mirror)
			)
		)
		(fp_text user "${REFERENCE}"
			(at -0.4 -2.7 180)
			(layer "B.Fab")
			(effects
				(font
					(size 0.7 0.7)
					(thickness 0.15)
				)
				(justify right top mirror)
			)
		)
		(pad "1" smd circle
			(at 0 0 180)
			(size 0.75 0.75)
			(layers "B.Cu" "B.Mask")
			(net 912 "/USB Hub/PRT_CTL4")
			(pinfunction "1")
			(pintype "passive")
		)
	)
	(footprint "antmicro-footprints:SOT-523"
		(layer "B.Cu")
		(at 132.2 150.6 -90)
		(property "Reference" "Q1"
			(at -0.5 -5.19 90)
			(layer "B.SilkS")
			(effects
				(font
					(size 0.7 0.7)
					(thickness 0.15)
				)
				(justify left bottom mirror)
			)
		)
		(property "Value" "DMG1012T-7"
			(at 0.1 -1.824 90)
			(layer "B.Fab")
			(effects
				(font
					(size 0.7 0.7)
					(thickness 0.15)
				)
				(justify left bottom mirror)
			)
		)
		(property "Datasheet" "https://www.diodes.com/assets/Datasheets/ds31783.pdf"
			(at 0 0 90)
			(layer "B.Fab")
			(hide yes)
			(effects
				(font
					(size 1.27 1.27)
					(thickness 0.15)
				)
				(justify mirror)
			)
		)
		(property "Description" "Power MOSFET, N Channel, 20 V, 630 mA, 0.3 ohm, SOT-523, Surface Mount"
			(at 0 0 90)
			(layer "B.Fab")
			(hide yes)
			(effects
				(font
					(size 1.27 1.27)
					(thickness 0.15)
				)
				(justify mirror)
			)
		)
		(property "MPN" "DMG1012T-7"
			(at 0 0 90)
			(unlocked yes)
			(layer "B.Fab")
			(hide yes)
			(effects
				(font
					(size 1 1)
					(thickness 0.15)
				)
				(justify mirror)
			)
		)
		(property "Manufacturer" "Diodes Incorporated"
			(at 0 0 90)
			(unlocked yes)
			(layer "B.Fab")
			(hide yes)
			(effects
				(font
					(size 1 1)
					(thickness 0.15)
				)
				(justify mirror)
			)
		)
		(property "Author" "Antmicro"
			(at 0 0 90)
			(unlocked yes)
			(layer "B.Fab")
			(hide yes)
			(effects
				(font
					(size 1 1)
					(thickness 0.15)
				)
				(justify mirror)
			)
		)
		(property "License" "Apache-2.0"
			(at 0 0 90)
			(unlocked yes)
			(layer "B.Fab")
			(hide yes)
			(effects
				(font
					(size 1 1)
					(thickness 0.15)
				)
				(justify mirror)
			)
		)
		(sheetname "/Peripherals/")
		(sheetfile "peripherals.kicad_sch")
		(attr smd)
		(fp_line
			(start -0.725 0.551)
			(end -0.277 0.551)
			(stroke
				(width 0.15)
				(type solid)
			)
			(layer "B.SilkS")
		)
		(fp_line
			(start -0.277 0.551)
			(end -0.277 0.75)
			(stroke
				(width 0.15)
				(type solid)
			)
			(layer "B.SilkS")
		)
		(fp_line
			(start -0.927 0.351)
			(end -0.725 0.551)
			(stroke
				(width 0.15)
				(type solid)
			)
			(layer "B.SilkS")
		)
		(fp_line
			(start -0.927 0.051)
			(end -0.927 0.351)
			(stroke
				(width 0.15)
				(type solid)
			)
			(layer "B.SilkS")
		)
		(fp_circle
			(center -0.9652 -0.9652)
			(end -0.9152 -0.9652)
			(stroke
				(width 0.15)
				(type solid)
			)
			(fill yes)
			(layer "B.SilkS")
		)
		(fp_line
			(start -1.12 1.16)
			(end 1.1 1.16)
			(stroke
				(width 0.05)
				(type solid)
			)
			(layer "B.CrtYd")
		)
		(fp_line
			(start -1.12 1.16)
			(end -1.12 -1.15)
			(stroke
				(width 0.05)
				(type solid)
			)
			(layer "B.CrtYd")
		)
		(fp_line
			(start 1.1 1.16)
			(end 1.1 -1.15)
			(stroke
				(width 0.05)
				(type solid)
			)
			(layer "B.CrtYd")
		)
		(fp_line
			(start -1.12 -1.15)
			(end 1.1 -1.15)
			(stroke
				(width 0.05)
				(type solid)
			)
			(layer "B.CrtYd")
		)
		(fp_line
			(start -0.652 0.425)
			(end -0.802 0.276)
			(stroke
				(width 0.15)
				(type solid)
			)
			(layer "B.Fab")
		)
		(fp_line
			(start 0.8 0.425)
			(end -0.652 0.425)
			(stroke
				(width 0.15)
				(type solid)
			)
			(layer "B.Fab")
		)
		(fp_line
			(start 0.8 0.425)
			(end 0.8 -0.424)
			(stroke
				(width 0.15)
				(type solid)
			)
			(layer "B.Fab")
		)
		(fp_line
			(start -0.802 0.276)
			(end -0.802 -0.424)
			(stroke
				(width 0.15)
				(type solid)
			)
			(layer "B.Fab")
		)
		(fp_line
			(start 0.8 -0.424)
			(end -0.802 -0.424)
			(stroke
				(width 0.15)
				(type solid)
			)
			(layer "B.Fab")
		)
		(fp_circle
			(center -0.9652 -0.9652)
			(end -0.9144 -0.9652)
			(stroke
				(width 0.15)
				(type solid)
			)
			(fill no)
			(layer "B.Fab")
		)
		(fp_text user "${REFERENCE}"
			(at -1.12 -3.824 90)
			(layer "B.Fab")
			(effects
				(font
					(size 0.7 0.7)
					(thickness 0.15)
				)
				(justify left bottom mirror)
			)
		)
		(fp_text user "Author: Antmicro"
			(at -1.12 -6.224 90)
			(layer "B.Fab")
			(effects
				(font
					(size 0.7 0.7)
					(thickness 0.15)
				)
				(justify left bottom mirror)
			)
		)
		(fp_text user "License: Apache-2.0"
			(at -1.12 -5.024 90)
			(layer "B.Fab")
			(effects
				(font
					(size 0.7 0.7)
					(thickness 0.15)
				)
				(justify left bottom mirror)
			)
		)
		(pad "1" smd rect
			(at -0.5 -0.65 270)
			(size 0.4 0.51)
			(layers "B.Cu" "B.Mask" "B.Paste")
			(net 1100 "/Peripherals/TPM_RST")
			(pinfunction "G")
			(pintype "input")
		)
		(pad "2" smd rect
			(at 0.498 -0.65 270)
			(size 0.4 0.51)
			(layers "B.Cu" "B.Mask" "B.Paste")
			(net 1 "GND")
			(pinfunction "S")
			(pintype "passive")
		)
		(pad "3" smd rect
			(at 0 0.652 270)
			(size 0.4 0.51)
			(layers "B.Cu" "B.Mask" "B.Paste")
			(net 1089 "Net-(Q1-D)")
			(pinfunction "D")
			(pintype "passive")
		)
	)
	(footprint "antmicro-footprints:SOD-523"
		(layer "B.Cu")
		(at 230.069 116.6 180)
		(property "Reference" "D45"
			(at 0.999 -0.4 0)
			(layer "B.SilkS")
			(effects
				(font
					(size 0.7 0.7)
					(thickness 0.15)
				)
				(justify left bottom mirror)
			)
		)
		(property "Value" "PESD5Z5.0F"
			(at 0 -1.499 0)
			(layer "B.Fab")
			(effects
				(font
					(size 0.7 0.7)
					(thickness 0.15)
				)
				(justify left bottom mirror)
			)
		)
		(property "Datasheet" "https://assets.nexperia.com/documents/data-sheet/PESD5Z5_0.pdf"
			(at 0 0 0)
			(layer "B.Fab")
			(hide yes)
			(effects
				(font
					(size 1.27 1.27)
					(thickness 0.15)
				)
				(justify mirror)
			)
		)
		(property "Description" "Unidirectional TVS, 30 kV,  SOD-523, 5 V, 89 pF"
			(at 0 0 0)
			(layer "B.Fab")
			(hide yes)
			(effects
				(font
					(size 1.27 1.27)
					(thickness 0.15)
				)
				(justify mirror)
			)
		)
		(property "Manufacturer" "Nexperia"
			(at 0 0 180)
			(unlocked yes)
			(layer "B.Fab")
			(hide yes)
			(effects
				(font
					(size 1 1)
					(thickness 0.15)
				)
				(justify mirror)
			)
		)
		(property "MPN" "PESD5Z5.0F"
			(at 0 0 180)
			(unlocked yes)
			(layer "B.Fab")
			(hide yes)
			(effects
				(font
					(size 1 1)
					(thickness 0.15)
				)
				(justify mirror)
			)
		)
		(property "Author" "Antmicro"
			(at 0 0 180)
			(unlocked yes)
			(layer "B.Fab")
			(hide yes)
			(effects
				(font
					(size 1 1)
					(thickness 0.15)
				)
				(justify mirror)
			)
		)
		(property "License" "Apache-2.0"
			(at 0 0 180)
			(unlocked yes)
			(layer "B.Fab")
			(hide yes)
			(effects
				(font
					(size 1 1)
					(thickness 0.15)
				)
				(justify mirror)
			)
		)
		(sheetname "/USB Hub/")
		(sheetfile "usb_hub.kicad_sch")
		(attr smd)
		(fp_line
			(start -0.35 0.5)
			(end -0.35 -0.5)
			(stroke
				(width 0.15)
				(type solid)
			)
			(layer "B.SilkS")
		)
		(fp_rect
			(start -1 0.6)
			(end 1 -0.6)
			(stroke
				(width 0.05)
				(type solid)
			)
			(fill no)
			(layer "B.CrtYd")
		)
		(fp_line
			(start 0.65 0.425)
			(end 0.65 -0.423)
			(stroke
				(width 0.15)
				(type solid)
			)
			(layer "B.Fab")
		)
		(fp_line
			(start -0.35 0.4)
			(end -0.35 -0.4)
			(stroke
				(width 0.15)
				(type solid)
			)
			(layer "B.Fab")
		)
		(fp_line
			(start -0.652 0.425)
			(end 0.65 0.425)
			(stroke
				(width 0.15)
				(type solid)
			)
			(layer "B.Fab")
		)
		(fp_line
			(start -0.652 -0.423)
			(end 0.65 -0.423)
			(stroke
				(width 0.15)
				(type solid)
			)
			(layer "B.Fab")
		)
		(fp_line
			(start -0.652 -0.423)
			(end -0.652 0.425)
			(stroke
				(width 0.15)
				(type solid)
			)
			(layer "B.Fab")
		)
		(fp_text user "License: Apache-2.0"
			(at -1.276 -5.9 0)
			(layer "B.Fab")
			(effects
				(font
					(size 0.7 0.7)
					(thickness 0.15)
				)
				(justify left bottom mirror)
			)
		)
		(fp_text user "${REFERENCE}"
			(at -1.276 -3.499 0)
			(layer "B.Fab")
			(effects
				(font
					(size 0.7 0.7)
					(thickness 0.15)
				)
				(justify left bottom mirror)
			)
		)
		(fp_text user "Author: Antmicro"
			(at -1.276 -4.7 0)
			(layer "B.Fab")
			(effects
				(font
					(size 0.7 0.7)
					(thickness 0.15)
				)
				(justify left bottom mirror)
			)
		)
		(pad "1" smd roundrect
			(at -0.701 0 180)
			(size 0.5 0.6)
			(layers "B.Cu" "B.Mask" "B.Paste")
			(roundrect_rratio 0.25)
			(net 71 "/USB Hub/USBC3_VBUS")
			(pinfunction "C")
			(pintype "passive")
		)
		(pad "2" smd roundrect
			(at 0.699 0 180)
			(size 0.5 0.6)
			(layers "B.Cu" "B.Mask" "B.Paste")
			(roundrect_rratio 0.25)
			(net 1 "GND")
			(pinfunction "A")
			(pintype "passive")
		)
	)
	(footprint "antmicro-footprints:Spacer_Drill3.7mm_H8mm_9774080151R"
		(locked yes)
		(layer "B.Cu")
		(at 80.430532 143.71 -90)
		(descr "Spacer M=3 h=8mm fi=5.1mm")
		(property "Reference" "H1"
			(at 0 3.2 90)
			(layer "B.SilkS")
			(effects
				(font
					(size 0.7 0.7)
					(thickness 0.15)
				)
				(justify left bottom mirror)
			)
		)
		(property "Value" "Spacer_Drill3.7mm_H8mm_9774080151R"
			(at 0 -4 90)
			(layer "B.Fab")
			(effects
				(font
					(size 0.7 0.7)
					(thickness 0.15)
				)
				(justify left bottom mirror)
			)
		)
		(property "Datasheet" "https://www.we-online.com/components/products/datasheet/9774080151R.pdf"
			(at 0 0 90)
			(layer "B.Fab")
			(hide yes)
			(effects
				(font
					(size 1.27 1.27)
					(thickness 0.15)
				)
				(justify mirror)
			)
		)
		(property "Description" "Spacer, SMT, Non Stop, Steel, Swage Round, 5.1 mm x 8 mm, M2.5 Thread, WA-SMSI Series"
			(at 0 0 90)
			(layer "B.Fab")
			(hide yes)
			(effects
				(font
					(size 1.27 1.27)
					(thickness 0.15)
				)
				(justify mirror)
			)
		)
		(property "Manufacturer" "Würth Elektronik"
			(at 0 0 270)
			(unlocked yes)
			(layer "B.Fab")
			(hide yes)
			(effects
				(font
					(size 1 1)
					(thickness 0.15)
				)
				(justify mirror)
			)
		)
		(property "MPN" "9774080151R"
			(at 0 0 270)
			(unlocked yes)
			(layer "B.Fab")
			(hide yes)
			(effects
				(font
					(size 1 1)
					(thickness 0.15)
				)
				(justify mirror)
			)
		)
		(property "Author" "Antmicro"
			(at 0 0 270)
			(unlocked yes)
			(layer "B.Fab")
			(hide yes)
			(effects
				(font
					(size 1 1)
					(thickness 0.15)
				)
				(justify mirror)
			)
		)
		(property "License" "Apache-2.0"
			(at 0 0 270)
			(unlocked yes)
			(layer "B.Fab")
			(hide yes)
			(effects
				(font
					(size 1 1)
					(thickness 0.15)
				)
				(justify mirror)
			)
		)
		(sheetname "/")
		(sheetfile "jetson-agx-thor-baseboard.kicad_sch")
		(solder_paste_margin_ratio -1)
		(attr smd)
		(fp_circle
			(center 0 0)
			(end 3.05 0)
			(stroke
				(width 0.05)
				(type solid)
			)
			(fill no)
			(layer "B.CrtYd")
		)
		(fp_circle
			(center 0 0)
			(end 2.6 0)
			(stroke
				(width 0.15)
				(type solid)
			)
			(fill no)
			(layer "B.Fab")
		)
		(fp_text user "License: Apache-2.0"
			(at -9.6 -8.9 90)
			(layer "B.Fab")
			(effects
				(font
					(size 0.7 0.7)
					(thickness 0.15)
				)
				(justify left bottom mirror)
			)
		)
		(fp_text user "${REFERENCE}"
			(at -9.6 -6.5 90)
			(layer "B.Fab")
			(effects
				(font
					(size 0.7 0.7)
					(thickness 0.15)
				)
				(justify left bottom mirror)
			)
		)
		(fp_text user "Author: Antmicro"
			(at -9.6 -7.7 90)
			(layer "B.Fab")
			(effects
				(font
					(size 0.7 0.7)
					(thickness 0.15)
				)
				(justify left bottom mirror)
			)
		)
		(pad "" smd custom
			(at -1.7 -1.7 180)
			(size 0.62 0.62)
			(layers "B.Paste")
			(thermal_bridge_angle 90)
			(options
				(clearance outline)
				(anchor circle)
			)
			(primitives
				(gr_arc
					(start 1.266786 0.24747)
					(mid 0.285453 -0.29439)
					(end -0.250195 -1.279127)
					(width 0.2)
				)
				(gr_arc
					(start 1.259603 0.339191)
					(mid 0.218448 -0.232561)
					(end -0.34334 -1.279127)
					(width 0.2)
				)
				(gr_arc
					(start 1.255279 0.431435)
					(mid 0.152481 -0.169693)
					(end -0.436309 -1.279127)
					(width 0.2)
				)
				(gr_arc
					(start 1.253811 0.524161)
					(mid 0.087542 -0.105784)
					(end -0.529126 -1.279127)
					(width 0.2)
				)
				(gr_arc
					(start 1.275473 0.621136)
					(mid 0.0309 -0.033527)
					(end -0.621807 -1.279127)
					(width 0.2)
				)
				(gr_arc
					(start 1.263664 0.711602)
					(mid -0.037759 0.026651)
					(end -0.71437 -1.279127)
					(width 0.2)
				)
				(gr_arc
					(start 1.253435 0.802342)
					(mid -0.105837 0.087395)
					(end -0.806826 -1.279127)
					(width 0.2)
				)
				(gr_arc
					(start 1.267475 0.897258)
					(mid -0.165236 0.156885)
					(end -0.899187 -1.279127)
					(width 0.2)
				)
				(gr_arc
					(start 1.270645 0.990112)
					(mid -0.228522 0.222449)
					(end -0.991463 -1.279127)
					(width 0.2)
				)
				(gr_arc
					(start 1.266278 1.081674)
					(mid -0.294507 0.285313)
					(end -1.083663 -1.279127)
					(width 0.2)
				)
				(gr_line
					(start 1.279127 0.250195)
					(end 1.279127 1.083663)
					(width 0.2)
				)
				(gr_line
					(start -0.250195 -1.279127)
					(end -1.083663 -1.279127)
					(width 0.2)
				)
			)
		)
		(pad "" smd custom
			(at -1.7 1.7 270)
			(size 0.62 0.62)
			(layers "B.Paste")
			(thermal_bridge_angle 90)
			(options
				(clearance outline)
				(anchor circle)
			)
			(primitives
				(gr_arc
					(start 1.266786 0.24747)
					(mid 0.285453 -0.29439)
					(end -0.250195 -1.279127)
					(width 0.2)
				)
				(gr_arc
					(start 1.259603 0.339191)
					(mid 0.218448 -0.232561)
					(end -0.34334 -1.279127)
					(width 0.2)
				)
				(gr_arc
					(start 1.255279 0.431435)
					(mid 0.152481 -0.169693)
					(end -0.436309 -1.279127)
					(width 0.2)
				)
				(gr_arc
					(start 1.253811 0.524161)
					(mid 0.087542 -0.105784)
					(end -0.529126 -1.279127)
					(width 0.2)
				)
				(gr_arc
					(start 1.275473 0.621136)
					(mid 0.0309 -0.033527)
					(end -0.621807 -1.279127)
					(width 0.2)
				)
				(gr_arc
					(start 1.263664 0.711602)
					(mid -0.037759 0.026651)
					(end -0.71437 -1.279127)
					(width 0.2)
				)
				(gr_arc
					(start 1.253435 0.802342)
					(mid -0.105837 0.087395)
					(end -0.806826 -1.279127)
					(width 0.2)
				)
				(gr_arc
					(start 1.267475 0.897258)
					(mid -0.165236 0.156885)
					(end -0.899187 -1.279127)
					(width 0.2)
				)
				(gr_arc
					(start 1.270645 0.990112)
					(mid -0.228522 0.222449)
					(end -0.991463 -1.279127)
					(width 0.2)
				)
				(gr_arc
					(start 1.266278 1.081674)
					(mid -0.294507 0.285313)
					(end -1.083663 -1.279127)
					(width 0.2)
				)
				(gr_line
					(start 1.279127 0.250195)
					(end 1.279127 1.083663)
					(width 0.2)
				)
				(gr_line
					(start -0.250195 -1.279127)
					(end -1.083663 -1.279127)
					(width 0.2)
				)
			)
		)
		(pad "" smd custom
			(at 1.7 -1.7 90)
			(size 0.62 0.62)
			(layers "B.Paste")
			(thermal_bridge_angle 90)
			(options
				(clearance outline)
				(anchor circle)
			)
			(primitives
				(gr_arc
					(start 1.266786 0.24747)
					(mid 0.285453 -0.29439)
					(end -0.250195 -1.279127)
					(width 0.2)
				)
				(gr_arc
					(start 1.259603 0.339191)
					(mid 0.218448 -0.232561)
					(end -0.34334 -1.279127)
					(width 0.2)
				)
				(gr_arc
					(start 1.255279 0.431435)
					(mid 0.152481 -0.169693)
					(end -0.436309 -1.279127)
					(width 0.2)
				)
				(gr_arc
					(start 1.253811 0.524161)
					(mid 0.087542 -0.105784)
					(end -0.529126 -1.279127)
					(width 0.2)
				)
				(gr_arc
					(start 1.275473 0.621136)
					(mid 0.0309 -0.033527)
					(end -0.621807 -1.279127)
					(width 0.2)
				)
				(gr_arc
					(start 1.263664 0.711602)
					(mid -0.037759 0.026651)
					(end -0.71437 -1.279127)
					(width 0.2)
				)
				(gr_arc
					(start 1.253435 0.802342)
					(mid -0.105837 0.087395)
					(end -0.806826 -1.279127)
					(width 0.2)
				)
				(gr_arc
					(start 1.267475 0.897258)
					(mid -0.165236 0.156885)
					(end -0.899187 -1.279127)
					(width 0.2)
				)
				(gr_arc
					(start 1.270645 0.990112)
					(mid -0.228522 0.222449)
					(end -0.991463 -1.279127)
					(width 0.2)
				)
				(gr_arc
					(start 1.266278 1.081674)
					(mid -0.294507 0.285313)
					(end -1.083663 -1.279127)
					(width 0.2)
				)
				(gr_line
					(start 1.279127 0.250195)
					(end 1.279127 1.083663)
					(width 0.2)
				)
				(gr_line
					(start -0.250195 -1.279127)
					(end -1.083663 -1.279127)
					(width 0.2)
				)
			)
		)
		(pad "" smd custom
			(at 1.7 1.7)
			(size 0.62 0.62)
			(layers "B.Paste")
			(thermal_bridge_angle 90)
			(options
				(clearance outline)
				(anchor circle)
			)
			(primitives
				(gr_arc
					(start 1.266786 0.24747)
					(mid 0.285453 -0.29439)
					(end -0.250195 -1.279127)
					(width 0.2)
				)
				(gr_arc
					(start 1.259603 0.339191)
					(mid 0.218448 -0.232561)
					(end -0.34334 -1.279127)
					(width 0.2)
				)
				(gr_arc
					(start 1.255279 0.431435)
					(mid 0.152481 -0.169693)
					(end -0.436309 -1.279127)
					(width 0.2)
				)
				(gr_arc
					(start 1.253811 0.524161)
					(mid 0.087542 -0.105784)
					(end -0.529126 -1.279127)
					(width 0.2)
				)
				(gr_arc
					(start 1.275473 0.621136)
					(mid 0.0309 -0.033527)
					(end -0.621807 -1.279127)
					(width 0.2)
				)
				(gr_arc
					(start 1.263664 0.711602)
					(mid -0.037759 0.026651)
					(end -0.71437 -1.279127)
					(width 0.2)
				)
				(gr_arc
					(start 1.253435 0.802342)
					(mid -0.105837 0.087395)
					(end -0.806826 -1.279127)
					(width 0.2)
				)
				(gr_arc
					(start 1.267475 0.897258)
					(mid -0.165236 0.156885)
					(end -0.899187 -1.279127)
					(width 0.2)
				)
				(gr_arc
					(start 1.270645 0.990112)
					(mid -0.228522 0.222449)
					(end -0.991463 -1.279127)
					(width 0.2)
				)
				(gr_arc
					(start 1.266278 1.081674)
					(mid -0.294507 0.285313)
					(end -1.083663 -1.279127)
					(width 0.2)
				)
				(gr_line
					(start 1.279127 0.250195)
					(end 1.279127 1.083663)
					(width 0.2)
				)
				(gr_line
					(start -0.250195 -1.279127)
					(end -1.083663 -1.279127)
					(width 0.2)
				)
			)
		)
		(pad "1" thru_hole circle
			(at 0 0 270)
			(size 6 6)
			(drill 3.7)
			(layers "*.Cu" "*.Mask")
			(remove_unused_layers no)
			(net 1 "GND")
			(pintype "passive")
		)
	)
	(footprint "antmicro-footprints:TSOT23-6"
		(layer "B.Cu")
		(at 232.4 134)
		(property "Reference" "U20"
			(at -0.24 -2.58 0)
			(layer "B.SilkS")
			(effects
				(font
					(size 0.7 0.7)
					(thickness 0.15)
				)
				(justify right top mirror)
			)
		)
		(property "Value" "AP22615A_TSOT26"
			(at 0 -2.600001 0)
			(layer "B.Fab")
			(effects
				(font
					(size 0.7 0.7)
					(thickness 0.15)
				)
				(justify right top mirror)
			)
		)
		(property "Datasheet" "https://www.mouser.com/datasheet/2/115/DIOD_S_A0008958405_1-2543193.pdf"
			(at 0 0 0)
			(layer "B.Fab")
			(hide yes)
			(effects
				(font
					(size 1.27 1.27)
					(thickness 0.15)
				)
				(justify mirror)
			)
		)
		(property "Description" "Power Load Distribution Switch, High Side, Active High, 1 Output, 5.5 V, 3.6 A, 0.04 ohm, TSOT-26-6"
			(at 0 0 0)
			(layer "B.Fab")
			(hide yes)
			(effects
				(font
					(size 1.27 1.27)
					(thickness 0.15)
				)
				(justify mirror)
			)
		)
		(property "MPN" "AP22615AWU-7"
			(at 0 0 180)
			(unlocked yes)
			(layer "B.Fab")
			(hide yes)
			(effects
				(font
					(size 1 1)
					(thickness 0.15)
				)
				(justify mirror)
			)
		)
		(property "Manufacturer" "Diodes Incorporated"
			(at 0 0 180)
			(unlocked yes)
			(layer "B.Fab")
			(hide yes)
			(effects
				(font
					(size 1 1)
					(thickness 0.15)
				)
				(justify mirror)
			)
		)
		(property "Author" "Antmicro"
			(at 0 0 180)
			(unlocked yes)
			(layer "B.Fab")
			(hide yes)
			(effects
				(font
					(size 1 1)
					(thickness 0.15)
				)
				(justify mirror)
			)
		)
		(property "License" "Apache-2.0"
			(at 0 0 180)
			(unlocked yes)
			(layer "B.Fab")
			(hide yes)
			(effects
				(font
					(size 1 1)
					(thickness 0.15)
				)
				(justify mirror)
			)
		)
		(sheetname "/USB Hub/")
		(sheetfile "usb_hub.kicad_sch")
		(attr smd)
		(fp_line
			(start -1 -1.55)
			(end -1 -1.4)
			(stroke
				(width 0.15)
				(type solid)
			)
			(layer "B.SilkS")
		)
		(fp_line
			(start -1 1.5)
			(end -1 1.375)
			(stroke
				(width 0.15)
				(type solid)
			)
			(layer "B.SilkS")
		)
		(fp_line
			(start 1 -1.55)
			(end -1 -1.55)
			(stroke
				(width 0.15)
				(type solid)
			)
			(layer "B.SilkS")
		)
		(fp_line
			(start 1 -1.55)
			(end 1 -1.4)
			(stroke
				(width 0.15)
				(type solid)
			)
			(layer "B.SilkS")
		)
		(fp_line
			(start 1 1.497)
			(end -1 1.5)
			(stroke
				(width 0.15)
				(type solid)
			)
			(layer "B.SilkS")
		)
		(fp_line
			(start 1 1.497)
			(end 1 1.375)
			(stroke
				(width 0.15)
				(type solid)
			)
			(layer "B.SilkS")
		)
		(fp_circle
			(center -1.44 1.5)
			(end -1.39 1.5)
			(stroke
				(width 0.15)
				(type solid)
			)
			(fill yes)
			(layer "B.SilkS")
		)
		(fp_poly
			(pts
				(xy 1.930001 1.7) (xy 1.930001 -1.7) (xy -1.930001 -1.7) (xy -1.930001 1.7)
			)
			(stroke
				(width 0.05)
				(type solid)
			)
			(fill no)
			(layer "B.CrtYd")
		)
		(fp_line
			(start -0.45 1.520999)
			(end -0.876001 1.096)
			(stroke
				(width 0.15)
				(type solid)
			)
			(layer "B.Fab")
		)
		(fp_poly
			(pts
				(xy 0.875 -1.528) (xy 0.875 1.525) (xy -0.875 1.525) (xy -0.875 -1.528)
			)
			(stroke
				(width 0.15)
				(type solid)
			)
			(fill no)
			(layer "B.Fab")
		)
		(fp_text user "Author: Antmicro"
			(at -1.93 -5 0)
			(layer "B.Fab")
			(effects
				(font
					(size 0.7 0.7)
					(thickness 0.15)
				)
				(justify right top mirror)
			)
		)
		(fp_text user "License: Apache-2.0"
			(at -1.93 -6.199 0)
			(layer "B.Fab")
			(effects
				(font
					(size 0.7 0.7)
					(thickness 0.15)
				)
				(justify right top mirror)
			)
		)
		(fp_text user "${REFERENCE}"
			(at -1.93 -3.8 0)
			(layer "B.Fab")
			(effects
				(font
					(size 0.7 0.7)
					(thickness 0.15)
				)
				(justify right top mirror)
			)
		)
		(pad "1" smd rect
			(at -1.301 0.947 90)
			(size 0.7 1.2)
			(layers "B.Cu" "B.Mask" "B.Paste")
			(net 115 "/USB Hub/USBC4_VBUS")
			(pinfunction "OUT")
			(pintype "power_out")
		)
		(pad "2" smd rect
			(at -1.300999 -0.004 90)
			(size 0.7 1.2)
			(layers "B.Cu" "B.Mask" "B.Paste")
			(net 1 "GND")
			(pinfunction "GND")
			(pintype "power_in")
		)
		(pad "3" smd rect
			(at -1.301 -0.954 90)
			(size 0.7 1.2)
			(layers "B.Cu" "B.Mask" "B.Paste")
			(net 914 "/USB Hub/PRT_CTL1")
			(pinfunction "FLG")
			(pintype "output")
		)
		(pad "4" smd rect
			(at 1.299 -0.954 90)
			(size 0.7 1.2)
			(layers "B.Cu" "B.Mask" "B.Paste")
			(net 914 "/USB Hub/PRT_CTL1")
			(pinfunction "EN")
			(pintype "input")
		)
		(pad "5" smd rect
			(at 1.299 -0.004 90)
			(size 0.7 1.2)
			(layers "B.Cu" "B.Mask" "B.Paste")
			(net 1015 "/USB Hub/USBC4_ISET")
			(pinfunction "ISET")
			(pintype "passive")
		)
		(pad "6" smd rect
			(at 1.299 0.947 90)
			(size 0.7 1.2)
			(layers "B.Cu" "B.Mask" "B.Paste")
			(net 5 "+5V")
			(pinfunction "IN")
			(pintype "power_in")
		)
	)
	(footprint "antmicro-footprints:LED_0603_1608Metric_G"
		(layer "B.Cu")
		(at 61.5 83.92)
		(descr "LED SMD 0603 Green")
		(tags "LED SMD 0603 Green")
		(property "Reference" "D28"
			(at -1 -2.92 0)
			(layer "B.SilkS")
			(effects
				(font
					(size 0.7 0.7)
					(thickness 0.15)
				)
				(justify right top mirror)
			)
		)
		(property "Value" "LED_G_0603_LTST-C190GKT"
			(at -0.001 -1.599 0)
			(layer "B.Fab")
			(effects
				(font
					(size 0.7 0.7)
					(thickness 0.15)
				)
				(justify right top mirror)
			)
		)
		(property "Datasheet" "https://media.digikey.com/pdf/Data%20Sheets/Lite-On%20PDFs/LTST-C190GKT.pdf"
			(at 0 0 0)
			(layer "B.Fab")
			(hide yes)
			(effects
				(font
					(size 1.27 1.27)
					(thickness 0.15)
				)
				(justify mirror)
			)
		)
		(property "Description" "LED, Green, SMD, 0603, 20 mA, 2.1 V, 569 nm"
			(at 0 0 0)
			(layer "B.Fab")
			(hide yes)
			(effects
				(font
					(size 1.27 1.27)
					(thickness 0.15)
				)
				(justify mirror)
			)
		)
		(property "MPN" "LTST-C190GKT"
			(at 0 0 180)
			(unlocked yes)
			(layer "B.Fab")
			(hide yes)
			(effects
				(font
					(size 1 1)
					(thickness 0.15)
				)
				(justify mirror)
			)
		)
		(property "Manufacturer" "Lite-On"
			(at 0 0 180)
			(unlocked yes)
			(layer "B.Fab")
			(hide yes)
			(effects
				(font
					(size 1 1)
					(thickness 0.15)
				)
				(justify mirror)
			)
		)
		(property "Author" "Antmicro"
			(at 0 0 180)
			(unlocked yes)
			(layer "B.Fab")
			(hide yes)
			(effects
				(font
					(size 1 1)
					(thickness 0.15)
				)
				(justify mirror)
			)
		)
		(property "License" "Apache-2.0"
			(at 0 0 180)
			(unlocked yes)
			(layer "B.Fab")
			(hide yes)
			(effects
				(font
					(size 1 1)
					(thickness 0.15)
				)
				(justify mirror)
			)
		)
		(property "Color" "Green"
			(at 0 0 180)
			(unlocked yes)
			(layer "B.Fab")
			(hide yes)
			(effects
				(font
					(size 1 1)
					(thickness 0.15)
				)
				(justify mirror)
			)
		)
		(sheetname "/CSI/")
		(sheetfile "csi.kicad_sch")
		(attr smd)
		(fp_line
			(start -1.18 0.319)
			(end -1.18 -0.321)
			(stroke
				(width 0.15)
				(type solid)
			)
			(layer "B.SilkS")
		)
		(fp_line
			(start -0.094672 -0.201008)
			(end -0.094672 0.198992)
			(stroke
				(width 0.1)
				(type solid)
			)
			(layer "B.SilkS")
		)
		(fp_line
			(start -0.094672 -0.001008)
			(end -0.24 -0.001008)
			(stroke
				(width 0.1)
				(type solid)
			)
			(layer "B.SilkS")
		)
		(fp_line
			(start -0.094672 -0.001008)
			(end 0.105328 0.198992)
			(stroke
				(width 0.1)
				(type solid)
			)
			(layer "B.SilkS")
		)
		(fp_line
			(start 0.105328 -0.201008)
			(end -0.094672 -0.001008)
			(stroke
				(width 0.1)
				(type solid)
			)
			(layer "B.SilkS")
		)
		(fp_line
			(start 0.105328 -0.201008)
			(end 0.105328 0.198992)
			(stroke
				(width 0.1)
				(type solid)
			)
			(layer "B.SilkS")
		)
		(fp_line
			(start 0.105328 -0.001008)
			(end 0.24 -0.001)
			(stroke
				(width 0.1)
				(type solid)
			)
			(layer "B.SilkS")
		)
		(fp_line
			(start 0.22 -0.35)
			(end -0.22 -0.35)
			(stroke
				(width 0.15)
				(type solid)
			)
			(layer "B.SilkS")
		)
		(fp_line
			(start 0.22 0.35)
			(end -0.22 0.35)
			(stroke
				(width 0.15)
				(type solid)
			)
			(layer "B.SilkS")
		)
		(fp_rect
			(start 1.25 -0.65)
			(end -1.25 0.65)
			(stroke
				(width 0.05)
				(type solid)
			)
			(fill no)
			(layer "B.CrtYd")
		)
		(fp_line
			(start -0.199 -0.2)
			(end -0.199 -0.1)
			(stroke
				(width 0.15)
				(type solid)
			)
			(layer "B.Fab")
		)
		(fp_line
			(start -0.199 0)
			(end -0.597 0)
			(stroke
				(width 0.15)
				(type solid)
			)
			(layer "B.Fab")
		)
		(fp_line
			(start -0.199 0.202)
			(end -0.199 -0.1)
			(stroke
				(width 0.15)
				(type solid)
			)
			(layer "B.Fab")
		)
		(fp_line
			(start -0.101 0)
			(end 0.201 -0.2)
			(stroke
				(width 0.15)
				(type solid)
			)
			(layer "B.Fab")
		)
		(fp_line
			(start 0.201 -0.2)
			(end 0.201 0)
			(stroke
				(width 0.15)
				(type solid)
			)
			(layer "B.Fab")
		)
		(fp_line
			(start 0.201 0)
			(end 0.201 0.202)
			(stroke
				(width 0.15)
				(type solid)
			)
			(layer "B.Fab")
		)
		(fp_line
			(start 0.201 0.202)
			(end -0.101 0)
			(stroke
				(width 0.15)
				(type solid)
			)
			(layer "B.Fab")
		)
		(fp_line
			(start 0.599 0)
			(end 0.201 0)
			(stroke
				(width 0.15)
				(type solid)
			)
			(layer "B.Fab")
		)
		(fp_rect
			(start 0.848 -0.4)
			(end -0.85 0.402)
			(stroke
				(width 0.15)
				(type solid)
			)
			(fill no)
			(layer "B.Fab")
		)
		(fp_text user "${REFERENCE}"
			(at -1.4224 -5.999 0)
			(layer "B.Fab")
			(effects
				(font
					(size 0.7 0.7)
					(thickness 0.15)
				)
				(justify right top mirror)
			)
		)
		(fp_text user "Author: Antmicro"
			(at -1.4224 -4.799 0)
			(layer "B.Fab")
			(effects
				(font
					(size 0.7 0.7)
					(thickness 0.15)
				)
				(justify right top mirror)
			)
		)
		(fp_text user "License: Apache-2.0"
			(at -1.4224 -3.599 0)
			(layer "B.Fab")
			(effects
				(font
					(size 0.7 0.7)
					(thickness 0.15)
				)
				(justify right top mirror)
			)
		)
		(pad "1" smd roundrect
			(at -0.7 0 180)
			(size 0.8 1)
			(layers "B.Cu" "B.Mask" "B.Paste")
			(roundrect_rratio 0.2)
			(net 1 "GND")
			(pinfunction "C")
			(pintype "passive")
		)
		(pad "2" smd roundrect
			(at 0.7 0 180)
			(size 0.8 1)
			(layers "B.Cu" "B.Mask" "B.Paste")
			(roundrect_rratio 0.2)
			(net 541 "Net-(D28-A)")
			(pinfunction "A")
			(pintype "passive")
		)
	)
	(footprint "antmicro-footprints:R_0402_1005Metric"
		(layer "B.Cu")
		(at 224.04 78.88)
		(descr "Resistor SMD 0402")
		(tags "resistor SMD 0402")
		(property "Reference" "R148"
			(at -1.74 -2.34 0)
			(layer "B.SilkS")
			(effects
				(font
					(size 0.7 0.7)
					(thickness 0.15)
				)
				(justify right top mirror)
			)
		)
		(property "Value" "R_27R_0402"
			(at -1.011843 -1.772047 0)
			(layer "B.Fab")
			(effects
				(font
					(size 0.7 0.7)
					(thickness 0.15)
				)
				(justify right top mirror)
			)
		)
		(property "Datasheet" "https://www.bourns.com/docs/product-datasheets/cr.pdf"
			(at 0 0 0)
			(layer "B.Fab")
			(hide yes)
			(effects
				(font
					(size 1.27 1.27)
					(thickness 0.15)
				)
				(justify mirror)
			)
		)
		(property "Description" "SMD Chip Resistor, 27 ohm, ± 1%, 63 mW, 0402 [1005 Metric], Thick Film, General Purpose"
			(at 0 0 0)
			(layer "B.Fab")
			(hide yes)
			(effects
				(font
					(size 1.27 1.27)
					(thickness 0.15)
				)
				(justify mirror)
			)
		)
		(property "Manufacturer" "Bourns"
			(at 0 0 180)
			(unlocked yes)
			(layer "B.Fab")
			(hide yes)
			(effects
				(font
					(size 1 1)
					(thickness 0.15)
				)
				(justify mirror)
			)
		)
		(property "MPN" "CR0402-FX-27R0GLF"
			(at 0 0 180)
			(unlocked yes)
			(layer "B.Fab")
			(hide yes)
			(effects
				(font
					(size 1 1)
					(thickness 0.15)
				)
				(justify mirror)
			)
		)
		(property "Val" "27R"
			(at 0 0 180)
			(unlocked yes)
			(layer "B.Fab")
			(hide yes)
			(effects
				(font
					(size 1 1)
					(thickness 0.15)
				)
				(justify mirror)
			)
		)
		(property "License" "Apache-2.0"
			(at 0 0 180)
			(unlocked yes)
			(layer "B.Fab")
			(hide yes)
			(effects
				(font
					(size 1 1)
					(thickness 0.15)
				)
				(justify mirror)
			)
		)
		(property "Author" "Antmicro"
			(at 0 0 180)
			(unlocked yes)
			(layer "B.Fab")
			(hide yes)
			(effects
				(font
					(size 1 1)
					(thickness 0.15)
				)
				(justify mirror)
			)
		)
		(property "Tolerance" "1%"
			(at 0 0 180)
			(unlocked yes)
			(layer "B.Fab")
			(hide yes)
			(effects
				(font
					(size 1 1)
					(thickness 0.15)
				)
				(justify mirror)
			)
		)
		(sheetname "/USB Debug, PD/")
		(sheetfile "usb_debug_pd.kicad_sch")
		(attr smd)
		(fp_rect
			(start -0.925 0.47)
			(end 0.925 -0.47)
			(stroke
				(width 0.05)
				(type default)
			)
			(fill no)
			(layer "B.CrtYd")
		)
		(fp_rect
			(start -0.5 0.25)
			(end 0.5 -0.25)
			(stroke
				(width 0.15)
				(type solid)
			)
			(fill no)
			(layer "B.Fab")
		)
		(fp_text user "${REFERENCE}"
			(at -0.95 -3.168 0)
			(layer "B.Fab")
			(effects
				(font
					(size 0.7 0.7)
					(thickness 0.15)
				)
				(justify right top mirror)
			)
		)
		(fp_text user "Author: Antmicro"
			(at -0.95 -4.169 0)
			(layer "B.Fab")
			(effects
				(font
					(size 0.7 0.7)
					(thickness 0.15)
				)
				(justify right top mirror)
			)
		)
		(fp_text user "License: Apache-2.0"
			(at -0.95 -5.169 0)
			(layer "B.Fab")
			(effects
				(font
					(size 0.7 0.7)
					(thickness 0.15)
				)
				(justify right top mirror)
			)
		)
		(pad "1" smd roundrect
			(at -0.48 0)
			(size 0.59 0.64)
			(layers "B.Cu" "B.Mask" "B.Paste")
			(roundrect_rratio 0.25)
			(net 974 "/USB Debug, PD/USB_FTDI_N")
			(pintype "passive")
		)
		(pad "2" smd roundrect
			(at 0.48 0)
			(size 0.59 0.64)
			(layers "B.Cu" "B.Mask" "B.Paste")
			(roundrect_rratio 0.25)
			(net 488 "/USB Debug, PD/USBC0_D_N")
			(pintype "passive")
		)
	)
	(footprint "antmicro-footprints:TSOT23-6"
		(layer "B.Cu")
		(at 232.4 95.1)
		(property "Reference" "U35"
			(at -0.971 1.9 0)
			(layer "B.SilkS")
			(effects
				(font
					(size 0.7 0.7)
					(thickness 0.15)
				)
				(justify right top mirror)
			)
		)
		(property "Value" "AP22615A_TSOT26"
			(at 0 -2.600001 0)
			(layer "B.Fab")
			(effects
				(font
					(size 0.7 0.7)
					(thickness 0.15)
				)
				(justify right top mirror)
			)
		)
		(property "Datasheet" "https://www.mouser.com/datasheet/2/115/DIOD_S_A0008958405_1-2543193.pdf"
			(at 0 0 0)
			(layer "B.Fab")
			(hide yes)
			(effects
				(font
					(size 1.27 1.27)
					(thickness 0.15)
				)
				(justify mirror)
			)
		)
		(property "Description" "Power Load Distribution Switch, High Side, Active High, 1 Output, 5.5 V, 3.6 A, 0.04 ohm, TSOT-26-6"
			(at 0 0 0)
			(layer "B.Fab")
			(hide yes)
			(effects
				(font
					(size 1.27 1.27)
					(thickness 0.15)
				)
				(justify mirror)
			)
		)
		(property "MPN" "AP22615AWU-7"
			(at 0 0 180)
			(unlocked yes)
			(layer "B.Fab")
			(hide yes)
			(effects
				(font
					(size 1 1)
					(thickness 0.15)
				)
				(justify mirror)
			)
		)
		(property "Manufacturer" "Diodes Incorporated"
			(at 0 0 180)
			(unlocked yes)
			(layer "B.Fab")
			(hide yes)
			(effects
				(font
					(size 1 1)
					(thickness 0.15)
				)
				(justify mirror)
			)
		)
		(property "Author" "Antmicro"
			(at 0 0 180)
			(unlocked yes)
			(layer "B.Fab")
			(hide yes)
			(effects
				(font
					(size 1 1)
					(thickness 0.15)
				)
				(justify mirror)
			)
		)
		(property "License" "Apache-2.0"
			(at 0 0 180)
			(unlocked yes)
			(layer "B.Fab")
			(hide yes)
			(effects
				(font
					(size 1 1)
					(thickness 0.15)
				)
				(justify mirror)
			)
		)
		(sheetname "/USB DP Alt mode/")
		(sheetfile "usb_dp.kicad_sch")
		(attr smd)
		(fp_line
			(start -1 -1.55)
			(end -1 -1.4)
			(stroke
				(width 0.15)
				(type solid)
			)
			(layer "B.SilkS")
		)
		(fp_line
			(start -1 1.5)
			(end -1 1.375)
			(stroke
				(width 0.15)
				(type solid)
			)
			(layer "B.SilkS")
		)
		(fp_line
			(start 1 -1.55)
			(end -1 -1.55)
			(stroke
				(width 0.15)
				(type solid)
			)
			(layer "B.SilkS")
		)
		(fp_line
			(start 1 -1.55)
			(end 1 -1.4)
			(stroke
				(width 0.15)
				(type solid)
			)
			(layer "B.SilkS")
		)
		(fp_line
			(start 1 1.497)
			(end -1 1.5)
			(stroke
				(width 0.15)
				(type solid)
			)
			(layer "B.SilkS")
		)
		(fp_line
			(start 1 1.497)
			(end 1 1.375)
			(stroke
				(width 0.15)
				(type solid)
			)
			(layer "B.SilkS")
		)
		(fp_circle
			(center -1.44 1.5)
			(end -1.39 1.5)
			(stroke
				(width 0.15)
				(type solid)
			)
			(fill yes)
			(layer "B.SilkS")
		)
		(fp_poly
			(pts
				(xy 1.930001 1.7) (xy 1.930001 -1.7) (xy -1.930001 -1.7) (xy -1.930001 1.7)
			)
			(stroke
				(width 0.05)
				(type solid)
			)
			(fill no)
			(layer "B.CrtYd")
		)
		(fp_line
			(start -0.45 1.520999)
			(end -0.876001 1.096)
			(stroke
				(width 0.15)
				(type solid)
			)
			(layer "B.Fab")
		)
		(fp_poly
			(pts
				(xy 0.875 -1.528) (xy 0.875 1.525) (xy -0.875 1.525) (xy -0.875 -1.528)
			)
			(stroke
				(width 0.15)
				(type solid)
			)
			(fill no)
			(layer "B.Fab")
		)
		(fp_text user "${REFERENCE}"
			(at -1.93 -3.8 0)
			(layer "B.Fab")
			(effects
				(font
					(size 0.7 0.7)
					(thickness 0.15)
				)
				(justify right top mirror)
			)
		)
		(fp_text user "Author: Antmicro"
			(at -1.93 -5 0)
			(layer "B.Fab")
			(effects
				(font
					(size 0.7 0.7)
					(thickness 0.15)
				)
				(justify right top mirror)
			)
		)
		(fp_text user "License: Apache-2.0"
			(at -1.93 -6.199 0)
			(layer "B.Fab")
			(effects
				(font
					(size 0.7 0.7)
					(thickness 0.15)
				)
				(justify right top mirror)
			)
		)
		(pad "1" smd rect
			(at -1.301 0.947 90)
			(size 0.7 1.2)
			(layers "B.Cu" "B.Mask" "B.Paste")
			(net 376 "/USB DP Alt mode/USBC1_VBUS")
			(pinfunction "OUT")
			(pintype "power_out")
		)
		(pad "2" smd rect
			(at -1.300999 -0.004 90)
			(size 0.7 1.2)
			(layers "B.Cu" "B.Mask" "B.Paste")
			(net 1 "GND")
			(pinfunction "GND")
			(pintype "power_in")
		)
		(pad "3" smd rect
			(at -1.301 -0.954 90)
			(size 0.7 1.2)
			(layers "B.Cu" "B.Mask" "B.Paste")
			(net 962 "/SoM_IO/USBC1_FLG")
			(pinfunction "FLG")
			(pintype "output")
		)
		(pad "4" smd rect
			(at 1.299 -0.954 90)
			(size 0.7 1.2)
			(layers "B.Cu" "B.Mask" "B.Paste")
			(net 971 "Net-(U35-EN)")
			(pinfunction "EN")
			(pintype "input")
		)
		(pad "5" smd rect
			(at 1.299 -0.004 90)
			(size 0.7 1.2)
			(layers "B.Cu" "B.Mask" "B.Paste")
			(net 972 "Net-(U35-ISET)")
			(pinfunction "ISET")
			(pintype "passive")
		)
		(pad "6" smd rect
			(at 1.299 0.947 90)
			(size 0.7 1.2)
			(layers "B.Cu" "B.Mask" "B.Paste")
			(net 5 "+5V")
			(pinfunction "IN")
			(pintype "power_in")
		)
	)
	(footprint "antmicro-footprints:R_0402_1005Metric"
		(layer "B.Cu")
		(at 222.4 82.3 90)
		(descr "Resistor SMD 0402")
		(tags "resistor SMD 0402")
		(property "Reference" "R145"
			(at -3.73 -0.42 90)
			(layer "B.SilkS")
			(effects
				(font
					(size 0.7 0.7)
					(thickness 0.15)
				)
				(justify right top mirror)
			)
		)
		(property "Value" "R_10k_0402"
			(at -1.011843 -1.772047 90)
			(layer "B.Fab")
			(effects
				(font
					(size 0.7 0.7)
					(thickness 0.15)
				)
				(justify right top mirror)
			)
		)
		(property "Datasheet" "https://www.bourns.com/docs/product-datasheets/cr.pdf"
			(at 0 0 90)
			(layer "B.Fab")
			(hide yes)
			(effects
				(font
					(size 1.27 1.27)
					(thickness 0.15)
				)
				(justify mirror)
			)
		)
		(property "Description" "SMD Chip Resistor, 10 kohm, ± 1%, 62.5 mW, 0402 [1005 Metric], Thick Film, General Purpose"
			(at 0 0 90)
			(layer "B.Fab")
			(hide yes)
			(effects
				(font
					(size 1.27 1.27)
					(thickness 0.15)
				)
				(justify mirror)
			)
		)
		(property "Manufacturer" "Bourns"
			(at 0 0 270)
			(unlocked yes)
			(layer "B.Fab")
			(hide yes)
			(effects
				(font
					(size 1 1)
					(thickness 0.15)
				)
				(justify mirror)
			)
		)
		(property "MPN" "CR0402-FX-1002GLF"
			(at 0 0 270)
			(unlocked yes)
			(layer "B.Fab")
			(hide yes)
			(effects
				(font
					(size 1 1)
					(thickness 0.15)
				)
				(justify mirror)
			)
		)
		(property "Val" "10k"
			(at 0 0 270)
			(unlocked yes)
			(layer "B.Fab")
			(hide yes)
			(effects
				(font
					(size 1 1)
					(thickness 0.15)
				)
				(justify mirror)
			)
		)
		(property "License" "Apache-2.0"
			(at 0 0 270)
			(unlocked yes)
			(layer "B.Fab")
			(hide yes)
			(effects
				(font
					(size 1 1)
					(thickness 0.15)
				)
				(justify mirror)
			)
		)
		(property "Author" "Antmicro"
			(at 0 0 270)
			(unlocked yes)
			(layer "B.Fab")
			(hide yes)
			(effects
				(font
					(size 1 1)
					(thickness 0.15)
				)
				(justify mirror)
			)
		)
		(property "Tolerance" "1%"
			(at 0 0 270)
			(unlocked yes)
			(layer "B.Fab")
			(hide yes)
			(effects
				(font
					(size 1 1)
					(thickness 0.15)
				)
				(justify mirror)
			)
		)
		(sheetname "/USB Debug, PD/")
		(sheetfile "usb_debug_pd.kicad_sch")
		(attr smd)
		(fp_rect
			(start -0.925 0.47)
			(end 0.925 -0.47)
			(stroke
				(width 0.05)
				(type default)
			)
			(fill no)
			(layer "B.CrtYd")
		)
		(fp_rect
			(start -0.5 0.25)
			(end 0.5 -0.25)
			(stroke
				(width 0.15)
				(type solid)
			)
			(fill no)
			(layer "B.Fab")
		)
		(fp_text user "${REFERENCE}"
			(at -0.95 -3.168 90)
			(layer "B.Fab")
			(effects
				(font
					(size 0.7 0.7)
					(thickness 0.15)
				)
				(justify right top mirror)
			)
		)
		(fp_text user "Author: Antmicro"
			(at -0.95 -4.169 90)
			(layer "B.Fab")
			(effects
				(font
					(size 0.7 0.7)
					(thickness 0.15)
				)
				(justify right top mirror)
			)
		)
		(fp_text user "License: Apache-2.0"
			(at -0.95 -5.169 90)
			(layer "B.Fab")
			(effects
				(font
					(size 0.7 0.7)
					(thickness 0.15)
				)
				(justify right top mirror)
			)
		)
		(pad "1" smd roundrect
			(at -0.48 0 90)
			(size 0.59 0.64)
			(layers "B.Cu" "B.Mask" "B.Paste")
			(roundrect_rratio 0.25)
			(net 334 "/USB Debug, PD/FTDI_3V3")
			(pintype "passive")
		)
		(pad "2" smd roundrect
			(at 0.48 0 90)
			(size 0.59 0.64)
			(layers "B.Cu" "B.Mask" "B.Paste")
			(roundrect_rratio 0.25)
			(net 339 "Net-(U34-~{RESET})")
			(pintype "passive")
		)
	)
	(footprint "antmicro-footprints:SOD-523"
		(layer "B.Cu")
		(at 148.7 147 90)
		(property "Reference" "D1"
			(at -0.9 0.8 90)
			(layer "B.SilkS")
			(effects
				(font
					(size 0.7 0.7)
					(thickness 0.15)
				)
				(justify right top mirror)
			)
		)
		(property "Value" "RB521S30T1G"
			(at 0 -1.499 90)
			(layer "B.Fab")
			(effects
				(font
					(size 0.7 0.7)
					(thickness 0.15)
				)
				(justify right top mirror)
			)
		)
		(property "Datasheet" "https://www.onsemi.com/pdf/datasheet/rb521s30t1-d.pdf"
			(at 0 0 90)
			(layer "B.Fab")
			(hide yes)
			(effects
				(font
					(size 1.27 1.27)
					(thickness 0.15)
				)
				(justify mirror)
			)
		)
		(property "Description" "Small Signal Schottky Diode, Single, 30 V, 200 mA, 500 mV, 1 A, 125 °C"
			(at 0 0 90)
			(layer "B.Fab")
			(hide yes)
			(effects
				(font
					(size 1.27 1.27)
					(thickness 0.15)
				)
				(justify mirror)
			)
		)
		(property "MPN" "RB521S30T1G"
			(at 0 0 270)
			(unlocked yes)
			(layer "B.Fab")
			(hide yes)
			(effects
				(font
					(size 1 1)
					(thickness 0.15)
				)
				(justify mirror)
			)
		)
		(property "Manufacturer" "ON Semiconductor"
			(at 0 0 270)
			(unlocked yes)
			(layer "B.Fab")
			(hide yes)
			(effects
				(font
					(size 1 1)
					(thickness 0.15)
				)
				(justify mirror)
			)
		)
		(property "Author" "Antmicro"
			(at 0 0 270)
			(unlocked yes)
			(layer "B.Fab")
			(hide yes)
			(effects
				(font
					(size 1 1)
					(thickness 0.15)
				)
				(justify mirror)
			)
		)
		(property "License" "Apache-2.0"
			(at 0 0 270)
			(unlocked yes)
			(layer "B.Fab")
			(hide yes)
			(effects
				(font
					(size 1 1)
					(thickness 0.15)
				)
				(justify mirror)
			)
		)
		(sheetname "/SoM_Power/")
		(sheetfile "som_power.kicad_sch")
		(attr smd)
		(fp_line
			(start -0.35 0.5)
			(end -0.35 -0.5)
			(stroke
				(width 0.15)
				(type solid)
			)
			(layer "B.SilkS")
		)
		(fp_rect
			(start -1 0.6)
			(end 1 -0.6)
			(stroke
				(width 0.05)
				(type solid)
			)
			(fill no)
			(layer "B.CrtYd")
		)
		(fp_line
			(start -0.652 -0.423)
			(end 0.65 -0.423)
			(stroke
				(width 0.15)
				(type solid)
			)
			(layer "B.Fab")
		)
		(fp_line
			(start -0.652 -0.423)
			(end -0.652 0.425)
			(stroke
				(width 0.15)
				(type solid)
			)
			(layer "B.Fab")
		)
		(fp_line
			(start -0.35 0.4)
			(end -0.35 -0.4)
			(stroke
				(width 0.15)
				(type solid)
			)
			(layer "B.Fab")
		)
		(fp_line
			(start 0.65 0.425)
			(end 0.65 -0.423)
			(stroke
				(width 0.15)
				(type solid)
			)
			(layer "B.Fab")
		)
		(fp_line
			(start -0.652 0.425)
			(end 0.65 0.425)
			(stroke
				(width 0.15)
				(type solid)
			)
			(layer "B.Fab")
		)
		(fp_text user "Author: Antmicro"
			(at -1.276 -4.7 90)
			(layer "B.Fab")
			(effects
				(font
					(size 0.7 0.7)
					(thickness 0.15)
				)
				(justify right top mirror)
			)
		)
		(fp_text user "${REFERENCE}"
			(at -1.276 -3.499 90)
			(layer "B.Fab")
			(effects
				(font
					(size 0.7 0.7)
					(thickness 0.15)
				)
				(justify right top mirror)
			)
		)
		(fp_text user "License: Apache-2.0"
			(at -1.276 -5.9 90)
			(layer "B.Fab")
			(effects
				(font
					(size 0.7 0.7)
					(thickness 0.15)
				)
				(justify right top mirror)
			)
		)
		(pad "1" smd roundrect
			(at -0.701 0 90)
			(size 0.5 0.6)
			(layers "B.Cu" "B.Mask" "B.Paste")
			(roundrect_rratio 0.25)
			(net 32 "Net-(D1-C)")
			(pinfunction "C")
			(pintype "passive")
		)
		(pad "2" smd roundrect
			(at 0.699 0 90)
			(size 0.5 0.6)
			(layers "B.Cu" "B.Mask" "B.Paste")
			(roundrect_rratio 0.25)
			(net 4 "+3V3_AON")
			(pinfunction "A")
			(pintype "passive")
		)
	)
	(footprint "antmicro-footprints:C_0402_1005Metric"
		(layer "B.Cu")
		(at 110.25 104.5)
		(descr "Capacitor SMD 0402")
		(tags "capacitor SMD 0402")
		(property "Reference" "C186"
			(at -0.95 -0.4 0)
			(layer "B.SilkS")
			(effects
				(font
					(size 0.7 0.7)
					(thickness 0.15)
				)
				(justify left top mirror)
			)
		)
		(property "Value" "C_220n_0402"
			(at -1.022927 -2.155213 0)
			(layer "B.Fab")
			(effects
				(font
					(size 0.7 0.7)
					(thickness 0.15)
				)
				(justify right top mirror)
			)
		)
		(property "Datasheet" "https://www.yageo.com/en/Chart/Download/pdf/CC0402KRX5R6BB224"
			(at 0 0 0)
			(layer "B.Fab")
			(hide yes)
			(effects
				(font
					(size 1.27 1.27)
					(thickness 0.15)
				)
				(justify mirror)
			)
		)
		(property "Description" "SMD Multilayer Ceramic Capacitor, 0.22 µF, 10 V, 0402 [1005 Metric], ± 10%, X5R, CC Series"
			(at 0 0 0)
			(layer "B.Fab")
			(hide yes)
			(effects
				(font
					(size 1.27 1.27)
					(thickness 0.15)
				)
				(justify mirror)
			)
		)
		(property "MPN" "CC0402KRX5R6BB224"
			(at 0 0 0)
			(unlocked yes)
			(layer "B.Fab")
			(hide yes)
			(effects
				(font
					(size 1 1)
					(thickness 0.15)
				)
				(justify mirror)
			)
		)
		(property "Val" "220n"
			(at 0 0 0)
			(unlocked yes)
			(layer "B.Fab")
			(hide yes)
			(effects
				(font
					(size 1 1)
					(thickness 0.15)
				)
				(justify mirror)
			)
		)
		(property "Voltage" "25V"
			(at 0 0 0)
			(unlocked yes)
			(layer "B.Fab")
			(hide yes)
			(effects
				(font
					(size 1 1)
					(thickness 0.15)
				)
				(justify mirror)
			)
		)
		(property "Dielectric" "X7R"
			(at 0 0 0)
			(unlocked yes)
			(layer "B.Fab")
			(hide yes)
			(effects
				(font
					(size 1 1)
					(thickness 0.15)
				)
				(justify mirror)
			)
		)
		(property "Manufacturer" "YAGEO"
			(at 0 0 0)
			(unlocked yes)
			(layer "B.Fab")
			(hide yes)
			(effects
				(font
					(size 1 1)
					(thickness 0.15)
				)
				(justify mirror)
			)
		)
		(property "License" "Apache-2.0"
			(at 0 0 0)
			(unlocked yes)
			(layer "B.Fab")
			(hide yes)
			(effects
				(font
					(size 1 1)
					(thickness 0.15)
				)
				(justify mirror)
			)
		)
		(property "Author" "Antmicro"
			(at 0 0 0)
			(unlocked yes)
			(layer "B.Fab")
			(hide yes)
			(effects
				(font
					(size 1 1)
					(thickness 0.15)
				)
				(justify mirror)
			)
		)
		(property "Public" "False"
			(at 0 0 0)
			(unlocked yes)
			(layer "B.Fab")
			(hide yes)
			(effects
				(font
					(size 1 1)
					(thickness 0.15)
				)
				(justify mirror)
			)
		)
		(sheetname "/M.2/")
		(sheetfile "m2.kicad_sch")
		(attr smd)
		(fp_poly
			(pts
				(xy -0.925 0.47) (xy -0.925 -0.47) (xy 0.925 -0.47) (xy 0.925 0.47)
			)
			(stroke
				(width 0.05)
				(type default)
			)
			(fill no)
			(layer "B.CrtYd")
		)
		(fp_line
			(start -0.494 -0.248)
			(end -0.494 0.25)
			(stroke
				(width 0.15)
				(type solid)
			)
			(layer "B.Fab")
		)
		(fp_line
			(start -0.494 0.25)
			(end 0.504 0.25)
			(stroke
				(width 0.15)
				(type solid)
			)
			(layer "B.Fab")
		)
		(fp_line
			(start 0.504 -0.248)
			(end -0.494 -0.248)
			(stroke
				(width 0.15)
				(type solid)
			)
			(layer "B.Fab")
		)
		(fp_line
			(start 0.504 0.25)
			(end 0.504 -0.248)
			(stroke
				(width 0.15)
				(type solid)
			)
			(layer "B.Fab")
		)
		(fp_text user "License: Apache-2.0"
			(at -0.939 -5.799 0)
			(layer "B.Fab")
			(effects
				(font
					(size 0.7 0.7)
					(thickness 0.15)
				)
				(justify right top mirror)
			)
		)
		(fp_text user "${REFERENCE}"
			(at -0.939 -4.599 0)
			(layer "B.Fab")
			(effects
				(font
					(size 0.7 0.7)
					(thickness 0.15)
				)
				(justify right top mirror)
			)
		)
		(fp_text user "Author: Antmicro"
			(at -0.939 -3.399 0)
			(layer "B.Fab")
			(effects
				(font
					(size 0.7 0.7)
					(thickness 0.15)
				)
				(justify right top mirror)
			)
		)
		(pad "1" smd roundrect
			(at -0.48 0)
			(size 0.59 0.64)
			(layers "B.Cu" "B.Mask" "B.Paste")
			(roundrect_rratio 0.25)
			(net 418 "/M.2/PCIe_{C5x4}.TX1-")
			(pintype "passive")
		)
		(pad "2" smd roundrect
			(at 0.48 0)
			(size 0.59 0.64)
			(layers "B.Cu" "B.Mask" "B.Paste")
			(roundrect_rratio 0.25)
			(net 417 "/M.2/M2_M_PET1_N")
			(pintype "passive")
		)
	)
	(footprint "antmicro-footprints:R_0402_1005Metric"
		(layer "B.Cu")
		(at 124.6 134.95)
		(descr "Resistor SMD 0402")
		(tags "resistor SMD 0402")
		(property "Reference" "R264"
			(at -1.2 -5.55 0)
			(layer "B.SilkS")
			(effects
				(font
					(size 0.7 0.7)
					(thickness 0.15)
				)
				(justify right top mirror)
			)
		)
		(property "Value" "R_0R_0402"
			(at -1.011843 -1.772046 0)
			(layer "B.Fab")
			(effects
				(font
					(size 0.7 0.7)
					(thickness 0.15)
				)
				(justify right top mirror)
			)
		)
		(property "Datasheet" "https://industrial.panasonic.com/cdbs/www-data/pdf/RDA0000/AOA0000C301.pdf"
			(at 0 0 0)
			(layer "B.Fab")
			(hide yes)
			(effects
				(font
					(size 1.27 1.27)
					(thickness 0.15)
				)
				(justify mirror)
			)
		)
		(property "Description" "SMD Chip Resistor, Jumper, 0 ohm, 100 mW, 0402 [1005 Metric], Thick Film, General Purpose"
			(at 0 0 0)
			(layer "B.Fab")
			(hide yes)
			(effects
				(font
					(size 1.27 1.27)
					(thickness 0.15)
				)
				(justify mirror)
			)
		)
		(property "MPN" "ERJ2GE0R00X"
			(at 0 0 180)
			(unlocked yes)
			(layer "B.Fab")
			(hide yes)
			(effects
				(font
					(size 1 1)
					(thickness 0.15)
				)
				(justify mirror)
			)
		)
		(property "Manufacturer" "Panasonic"
			(at 0 0 180)
			(unlocked yes)
			(layer "B.Fab")
			(hide yes)
			(effects
				(font
					(size 1 1)
					(thickness 0.15)
				)
				(justify mirror)
			)
		)
		(property "License" "Apache-2.0"
			(at 0 0 180)
			(unlocked yes)
			(layer "B.Fab")
			(hide yes)
			(effects
				(font
					(size 1 1)
					(thickness 0.15)
				)
				(justify mirror)
			)
		)
		(property "Val" "0R"
			(at 0 0 180)
			(unlocked yes)
			(layer "B.Fab")
			(hide yes)
			(effects
				(font
					(size 1 1)
					(thickness 0.15)
				)
				(justify mirror)
			)
		)
		(property "Tolerance" "~"
			(at 0 0 180)
			(unlocked yes)
			(layer "B.Fab")
			(hide yes)
			(effects
				(font
					(size 1 1)
					(thickness 0.15)
				)
				(justify mirror)
			)
		)
		(property "Current" "1A"
			(at 0 0 180)
			(unlocked yes)
			(layer "B.Fab")
			(hide yes)
			(effects
				(font
					(size 1 1)
					(thickness 0.15)
				)
				(justify mirror)
			)
		)
		(property "Author" "Antmicro"
			(at 0 0 180)
			(unlocked yes)
			(layer "B.Fab")
			(hide yes)
			(effects
				(font
					(size 1 1)
					(thickness 0.15)
				)
				(justify mirror)
			)
		)
		(property "Public" "False"
			(at 0 0 180)
			(unlocked yes)
			(layer "B.Fab")
			(hide yes)
			(effects
				(font
					(size 1 1)
					(thickness 0.15)
				)
				(justify mirror)
			)
		)
		(sheetname "/M.2/")
		(sheetfile "m2.kicad_sch")
		(attr smd)
		(fp_poly
			(pts
				(xy -0.925 0.47) (xy 0.925 0.47) (xy 0.925 -0.47) (xy -0.925 -0.47)
			)
			(stroke
				(width 0.05)
				(type default)
			)
			(fill no)
			(layer "B.CrtYd")
		)
		(fp_poly
			(pts
				(xy -0.5 0.25) (xy 0.5 0.25) (xy 0.5 -0.25) (xy -0.5 -0.25)
			)
			(stroke
				(width 0.15)
				(type solid)
			)
			(fill no)
			(layer "B.Fab")
		)
		(fp_text user "License: Apache-2.0"
			(at -0.949999 -5.169 0)
			(layer "B.Fab")
			(effects
				(font
					(size 0.7 0.7)
					(thickness 0.15)
				)
				(justify right top mirror)
			)
		)
		(fp_text user "Author: Antmicro"
			(at -0.95 -4.169 0)
			(layer "B.Fab")
			(effects
				(font
					(size 0.7 0.7)
					(thickness 0.15)
				)
				(justify right top mirror)
			)
		)
		(fp_text user "${REFERENCE}"
			(at -0.95 -3.168 0)
			(layer "B.Fab")
			(effects
				(font
					(size 0.7 0.7)
					(thickness 0.15)
				)
				(justify right top mirror)
			)
		)
		(pad "1" smd roundrect
			(at -0.48 0)
			(size 0.59 0.64)
			(layers "B.Cu" "B.Mask" "B.Paste")
			(roundrect_rratio 0.25)
			(net 244 "/M.2/M2_E_W_DIS_1")
			(pintype "passive")
		)
		(pad "2" smd roundrect
			(at 0.48 0)
			(size 0.59 0.64)
			(layers "B.Cu" "B.Mask" "B.Paste")
			(roundrect_rratio 0.25)
			(net 1113 "/M.2/M2_E.W_DIS_1")
			(pintype "passive")
		)
	)
	(footprint "antmicro-footprints:Vishay_PowerPAK_1212-8_Single"
		(layer "B.Cu")
		(at 183.08 84.307 90)
		(descr "PowerPAK 1212-8 Single")
		(tags "Vishay PowerPAK 1212-8 Single")
		(property "Reference" "Q24"
			(at -0.093 1.92 90)
			(layer "B.SilkS")
			(effects
				(font
					(size 0.7 0.7)
					(thickness 0.15)
				)
				(justify right top mirror)
			)
		)
		(property "Value" "SISS05DN-T1-GE3"
			(at 0 -2.7 90)
			(layer "B.Fab")
			(effects
				(font
					(size 0.7 0.7)
					(thickness 0.15)
				)
				(justify right top mirror)
			)
		)
		(property "Datasheet" "https://www.vishay.com/docs/77029/siss05dn.pdf"
			(at 0 0 90)
			(layer "B.Fab")
			(hide yes)
			(effects
				(font
					(size 1.27 1.27)
					(thickness 0.15)
				)
				(justify mirror)
			)
		)
		(property "Description" "Power MOSFET, P Channel, 30 V, 108 A, 0.0035 ohm, PowerPAK 1212, Surface Mount"
			(at 0 0 90)
			(layer "B.Fab")
			(hide yes)
			(effects
				(font
					(size 1.27 1.27)
					(thickness 0.15)
				)
				(justify mirror)
			)
		)
		(property "MPN" "SISS05DN-T1-GE3"
			(at 0 0 270)
			(unlocked yes)
			(layer "B.Fab")
			(hide yes)
			(effects
				(font
					(size 1 1)
					(thickness 0.15)
				)
				(justify mirror)
			)
		)
		(property "Manufacturer" "Vishay"
			(at 0 0 270)
			(unlocked yes)
			(layer "B.Fab")
			(hide yes)
			(effects
				(font
					(size 1 1)
					(thickness 0.15)
				)
				(justify mirror)
			)
		)
		(property "Author" "Antmicro"
			(at 0 0 270)
			(unlocked yes)
			(layer "B.Fab")
			(hide yes)
			(effects
				(font
					(size 1 1)
					(thickness 0.15)
				)
				(justify mirror)
			)
		)
		(property "License" "Apache-2.0"
			(at 0 0 270)
			(unlocked yes)
			(layer "B.Fab")
			(hide yes)
			(effects
				(font
					(size 1 1)
					(thickness 0.15)
				)
				(justify mirror)
			)
		)
		(sheetname "/Power/")
		(sheetfile "power.kicad_sch")
		(attr smd)
		(fp_line
			(start -1.635 -1.634)
			(end 1.634 -1.634)
			(stroke
				(width 0.15)
				(type solid)
			)
			(layer "B.SilkS")
		)
		(fp_line
			(start 1.634 -1.3)
			(end 1.634 -1.634)
			(stroke
				(width 0.15)
				(type solid)
			)
			(layer "B.SilkS")
		)
		(fp_line
			(start -1.635 -1.3)
			(end -1.635 -1.634)
			(stroke
				(width 0.15)
				(type solid)
			)
			(layer "B.SilkS")
		)
		(fp_line
			(start 1.648 1.651)
			(end 1.648 1.317)
			(stroke
				(width 0.15)
				(type solid)
			)
			(layer "B.SilkS")
		)
		(fp_line
			(start -1.651 1.651)
			(end -1.651 1.317)
			(stroke
				(width 0.15)
				(type solid)
			)
			(layer "B.SilkS")
		)
		(fp_line
			(start -1.651 1.651)
			(end 1.648 1.651)
			(stroke
				(width 0.15)
				(type solid)
			)
			(layer "B.SilkS")
		)
		(fp_circle
			(center -1.9 1.4)
			(end -1.85 1.4)
			(stroke
				(width 0.15)
				(type solid)
			)
			(fill yes)
			(layer "B.SilkS")
		)
		(fp_rect
			(start -2 1.8)
			(end 2 -1.798)
			(stroke
				(width 0.05)
				(type solid)
			)
			(fill no)
			(layer "B.CrtYd")
		)
		(fp_line
			(start -1.6425 1.4175)
			(end -1.4175 1.6425)
			(stroke
				(width 0.15)
				(type solid)
			)
			(layer "B.Fab")
		)
		(fp_rect
			(start -1.651 1.651)
			(end 1.648 -1.648)
			(stroke
				(width 0.15)
				(type solid)
			)
			(fill no)
			(layer "B.Fab")
		)
		(fp_text user "License: Apache-2.0"
			(at -8 -7.1 90)
			(layer "B.Fab")
			(effects
				(font
					(size 0.7 0.7)
					(thickness 0.15)
				)
				(justify right top mirror)
			)
		)
		(fp_text user "Author: Antmicro"
			(at -8 -5.9 90)
			(layer "B.Fab")
			(effects
				(font
					(size 0.7 0.7)
					(thickness 0.15)
				)
				(justify right top mirror)
			)
		)
		(fp_text user "${REFERENCE}"
			(at -8 -4.7 90)
			(layer "B.Fab")
			(effects
				(font
					(size 0.7 0.7)
					(thickness 0.15)
				)
				(justify right top mirror)
			)
		)
		(pad "1" smd rect
			(at -1.436 0.99 90)
			(size 0.99 0.405)
			(layers "B.Cu" "B.Mask" "B.Paste")
			(net 522 "/Power/USBPD1_HV")
			(pinfunction "S")
			(pintype "passive")
		)
		(pad "2" smd rect
			(at -1.436 0.332 90)
			(size 0.99 0.405)
			(layers "B.Cu" "B.Mask" "B.Paste")
			(net 522 "/Power/USBPD1_HV")
			(pinfunction "S")
			(pintype "passive")
		)
		(pad "3" smd rect
			(at -1.436 -0.33 90)
			(size 0.99 0.405)
			(layers "B.Cu" "B.Mask" "B.Paste")
			(net 522 "/Power/USBPD1_HV")
			(pinfunction "S")
			(pintype "passive")
		)
		(pad "4" smd rect
			(at -1.436 -0.988 90)
			(size 0.99 0.405)
			(layers "B.Cu" "B.Mask" "B.Paste")
			(net 1202 "Net-(Q24-G)")
			(pinfunction "G")
			(pintype "input")
		)
		(pad "5" smd custom
			(at 0.557 0 90)
			(size 1.725 2.235)
			(layers "B.Cu" "B.Mask" "B.Paste")
			(net 904 "+20V")
			(pinfunction "D")
			(pintype "passive")
			(zone_connect 2)
			(options
				(clearance outline)
				(anchor rect)
			)
			(primitives
				(gr_poly
					(pts
						(xy 0.8625 -0.1275) (xy 0.8625 0.1275) (xy 1.3725 0.1275) (xy 1.3725 0.5325) (xy 0.8625 0.5325)
						(xy 0.8625 0.7875) (xy 1.3725 0.7875) (xy 1.3725 1.195) (xy 0.6125 1.195) (xy 0.6125 -1.195) (xy 1.3725 -1.195)
						(xy 1.3725 -0.7875) (xy 0.8625 -0.7875) (xy 0.8625 -0.5325) (xy 1.3725 -0.5325) (xy 1.3725 -0.1275)
					)
					(width 0)
					(fill yes)
				)
			)
		)
	)
	(footprint "antmicro-footprints:R_0402_1005Metric"
		(layer "B.Cu")
		(at 213.8 80.2 180)
		(descr "Resistor SMD 0402")
		(tags "resistor SMD 0402")
		(property "Reference" "R113"
			(at 0.2 -2.4 0)
			(layer "B.SilkS")
			(effects
				(font
					(size 0.7 0.7)
					(thickness 0.15)
				)
				(justify left bottom mirror)
			)
		)
		(property "Value" "R_1k_0402"
			(at -1.011843 -1.772046 0)
			(layer "B.Fab")
			(effects
				(font
					(size 0.7 0.7)
					(thickness 0.15)
				)
				(justify left bottom mirror)
			)
		)
		(property "Datasheet" "https://www.bourns.com/docs/product-datasheets/cr.pdf"
			(at 0 0 0)
			(layer "B.Fab")
			(hide yes)
			(effects
				(font
					(size 1.27 1.27)
					(thickness 0.15)
				)
				(justify mirror)
			)
		)
		(property "Description" "SMD Chip Resistor, 1 kohm, ± 1%, 63 mW, 0402 [1005 Metric], Thick Film, General Purpose"
			(at 0 0 0)
			(layer "B.Fab")
			(hide yes)
			(effects
				(font
					(size 1.27 1.27)
					(thickness 0.15)
				)
				(justify mirror)
			)
		)
		(property "MPN" "CR0402-FX-1001GLF"
			(at 0 0 0)
			(unlocked yes)
			(layer "B.Fab")
			(hide yes)
			(effects
				(font
					(size 1 1)
					(thickness 0.15)
				)
				(justify mirror)
			)
		)
		(property "Manufacturer" "Bourns"
			(at 0 0 0)
			(unlocked yes)
			(layer "B.Fab")
			(hide yes)
			(effects
				(font
					(size 1 1)
					(thickness 0.15)
				)
				(justify mirror)
			)
		)
		(property "License" "Apache-2.0"
			(at 0 0 0)
			(unlocked yes)
			(layer "B.Fab")
			(hide yes)
			(effects
				(font
					(size 1 1)
					(thickness 0.15)
				)
				(justify mirror)
			)
		)
		(property "Author" "Antmicro"
			(at 0 0 0)
			(unlocked yes)
			(layer "B.Fab")
			(hide yes)
			(effects
				(font
					(size 1 1)
					(thickness 0.15)
				)
				(justify mirror)
			)
		)
		(property "Val" "1k"
			(at 0 0 0)
			(unlocked yes)
			(layer "B.Fab")
			(hide yes)
			(effects
				(font
					(size 1 1)
					(thickness 0.15)
				)
				(justify mirror)
			)
		)
		(property "Tolerance" "1%"
			(at 0 0 0)
			(unlocked yes)
			(layer "B.Fab")
			(hide yes)
			(effects
				(font
					(size 1 1)
					(thickness 0.15)
				)
				(justify mirror)
			)
		)
		(sheetname "/USB Debug, PD/")
		(sheetfile "usb_debug_pd.kicad_sch")
		(attr smd)
		(fp_poly
			(pts
				(xy -0.925 0.47) (xy -0.925 -0.47) (xy 0.925 -0.47) (xy 0.925 0.47)
			)
			(stroke
				(width 0.05)
				(type default)
			)
			(fill no)
			(layer "B.CrtYd")
		)
		(fp_poly
			(pts
				(xy -0.5 0.25) (xy -0.5 -0.25) (xy 0.5 -0.25) (xy 0.5 0.25)
			)
			(stroke
				(width 0.15)
				(type solid)
			)
			(fill no)
			(layer "B.Fab")
		)
		(fp_text user "License: Apache-2.0"
			(at -0.949999 -5.169 0)
			(layer "B.Fab")
			(effects
				(font
					(size 0.7 0.7)
					(thickness 0.15)
				)
				(justify left bottom mirror)
			)
		)
		(fp_text user "Author: Antmicro"
			(at -0.95 -4.169 0)
			(layer "B.Fab")
			(effects
				(font
					(size 0.7 0.7)
					(thickness 0.15)
				)
				(justify left bottom mirror)
			)
		)
		(fp_text user "${REFERENCE}"
			(at -0.95 -3.168 0)
			(layer "B.Fab")
			(effects
				(font
					(size 0.7 0.7)
					(thickness 0.15)
				)
				(justify left bottom mirror)
			)
		)
		(pad "1" smd roundrect
			(at -0.48 0 180)
			(size 0.59 0.64)
			(layers "B.Cu" "B.Mask" "B.Paste")
			(roundrect_rratio 0.25)
			(net 955 "/USB Debug, PD/FTDI_CBUS3{slash}SCL")
			(pintype "passive")
		)
		(pad "2" smd roundrect
			(at 0.48 0 180)
			(size 0.59 0.64)
			(layers "B.Cu" "B.Mask" "B.Paste")
			(roundrect_rratio 0.25)
			(net 334 "/USB Debug, PD/FTDI_3V3")
			(pintype "passive")
		)
	)
	(footprint "antmicro-footprints:R_0402_1005Metric"
		(layer "B.Cu")
		(at 193.7 87.8 90)
		(descr "Resistor SMD 0402")
		(tags "resistor SMD 0402")
		(property "Reference" "R384"
			(at -3.7 -0.4 270)
			(layer "B.SilkS")
			(effects
				(font
					(size 0.7 0.7)
					(thickness 0.15)
				)
				(justify right top mirror)
			)
		)
		(property "Value" "R_0R_0402"
			(at -1.011843 -1.772047 90)
			(layer "B.Fab")
			(effects
				(font
					(size 0.7 0.7)
					(thickness 0.15)
				)
				(justify right top mirror)
			)
		)
		(property "Datasheet" "https://industrial.panasonic.com/cdbs/www-data/pdf/RDA0000/AOA0000C301.pdf"
			(at 0 0 90)
			(layer "B.Fab")
			(hide yes)
			(effects
				(font
					(size 1.27 1.27)
					(thickness 0.15)
				)
				(justify mirror)
			)
		)
		(property "Description" "SMD Chip Resistor, Jumper, 0 ohm, 100 mW, 0402 [1005 Metric], Thick Film, General Purpose"
			(at 0 0 90)
			(layer "B.Fab")
			(hide yes)
			(effects
				(font
					(size 1.27 1.27)
					(thickness 0.15)
				)
				(justify mirror)
			)
		)
		(property "MPN" "ERJ2GE0R00X"
			(at 0 0 270)
			(unlocked yes)
			(layer "B.Fab")
			(hide yes)
			(effects
				(font
					(size 1 1)
					(thickness 0.15)
				)
				(justify mirror)
			)
		)
		(property "Manufacturer" "Panasonic"
			(at 0 0 270)
			(unlocked yes)
			(layer "B.Fab")
			(hide yes)
			(effects
				(font
					(size 1 1)
					(thickness 0.15)
				)
				(justify mirror)
			)
		)
		(property "License" "Apache-2.0"
			(at 0 0 270)
			(unlocked yes)
			(layer "B.Fab")
			(hide yes)
			(effects
				(font
					(size 1 1)
					(thickness 0.15)
				)
				(justify mirror)
			)
		)
		(property "Author" "Antmicro"
			(at 0 0 270)
			(unlocked yes)
			(layer "B.Fab")
			(hide yes)
			(effects
				(font
					(size 1 1)
					(thickness 0.15)
				)
				(justify mirror)
			)
		)
		(property "Val" "0R"
			(at 0 0 270)
			(unlocked yes)
			(layer "B.Fab")
			(hide yes)
			(effects
				(font
					(size 1 1)
					(thickness 0.15)
				)
				(justify mirror)
			)
		)
		(property "Tolerance" "~"
			(at 0 0 270)
			(unlocked yes)
			(layer "B.Fab")
			(hide yes)
			(effects
				(font
					(size 1 1)
					(thickness 0.15)
				)
				(justify mirror)
			)
		)
		(property "Current" "1A"
			(at 0 0 270)
			(unlocked yes)
			(layer "B.Fab")
			(hide yes)
			(effects
				(font
					(size 1 1)
					(thickness 0.15)
				)
				(justify mirror)
			)
		)
		(sheetname "/USB Debug, PD/")
		(sheetfile "usb_debug_pd.kicad_sch")
		(attr smd)
		(fp_rect
			(start -0.925 0.47)
			(end 0.925 -0.47)
			(stroke
				(width 0.05)
				(type default)
			)
			(fill no)
			(layer "B.CrtYd")
		)
		(fp_rect
			(start -0.5 0.25)
			(end 0.5 -0.25)
			(stroke
				(width 0.15)
				(type solid)
			)
			(fill no)
			(layer "B.Fab")
		)
		(fp_text user "${REFERENCE}"
			(at -0.95 -3.168 90)
			(layer "B.Fab")
			(effects
				(font
					(size 0.7 0.7)
					(thickness 0.15)
				)
				(justify right top mirror)
			)
		)
		(fp_text user "Author: Antmicro"
			(at -0.95 -4.169 90)
			(layer "B.Fab")
			(effects
				(font
					(size 0.7 0.7)
					(thickness 0.15)
				)
				(justify right top mirror)
			)
		)
		(fp_text user "License: Apache-2.0"
			(at -0.95 -5.169 90)
			(layer "B.Fab")
			(effects
				(font
					(size 0.7 0.7)
					(thickness 0.15)
				)
				(justify right top mirror)
			)
		)
		(pad "1" smd roundrect
			(at -0.48 0 90)
			(size 0.59 0.64)
			(layers "B.Cu" "B.Mask" "B.Paste")
			(roundrect_rratio 0.25)
			(net 810 "/USB Debug, PD/MISO")
			(pintype "passive")
		)
		(pad "2" smd roundrect
			(at 0.48 0 90)
			(size 0.59 0.64)
			(layers "B.Cu" "B.Mask" "B.Paste")
			(roundrect_rratio 0.25)
			(net 936 "/USB Debug, PD/PDC_MISO")
			(pintype "passive")
		)
	)
	(footprint "antmicro-footprints:TSOT23-6"
		(layer "B.Cu")
		(at 210.5 66 180)
		(property "Reference" "U46"
			(at -2.109001 -1.8 90)
			(layer "B.SilkS")
			(effects
				(font
					(size 0.7 0.7)
					(thickness 0.15)
				)
				(justify right top mirror)
			)
		)
		(property "Value" "AP22615A_TSOT26"
			(at 0 -2.600001 0)
			(layer "B.Fab")
			(effects
				(font
					(size 0.7 0.7)
					(thickness 0.15)
				)
				(justify left bottom mirror)
			)
		)
		(property "Datasheet" "https://www.mouser.com/datasheet/2/115/DIOD_S_A0008958405_1-2543193.pdf"
			(at 0 0 0)
			(layer "B.Fab")
			(hide yes)
			(effects
				(font
					(size 1.27 1.27)
					(thickness 0.15)
				)
				(justify mirror)
			)
		)
		(property "Description" "Power Load Distribution Switch, High Side, Active High, 1 Output, 5.5 V, 3.6 A, 0.04 ohm, TSOT-26-6"
			(at 0 0 0)
			(layer "B.Fab")
			(hide yes)
			(effects
				(font
					(size 1.27 1.27)
					(thickness 0.15)
				)
				(justify mirror)
			)
		)
		(property "MPN" "AP22615AWU-7"
			(at 0 0 0)
			(unlocked yes)
			(layer "B.Fab")
			(hide yes)
			(effects
				(font
					(size 1 1)
					(thickness 0.15)
				)
				(justify mirror)
			)
		)
		(property "Manufacturer" "Diodes Incorporated"
			(at 0 0 0)
			(unlocked yes)
			(layer "B.Fab")
			(hide yes)
			(effects
				(font
					(size 1 1)
					(thickness 0.15)
				)
				(justify mirror)
			)
		)
		(property "Author" "Antmicro"
			(at 0 0 0)
			(unlocked yes)
			(layer "B.Fab")
			(hide yes)
			(effects
				(font
					(size 1 1)
					(thickness 0.15)
				)
				(justify mirror)
			)
		)
		(property "License" "Apache-2.0"
			(at 0 0 0)
			(unlocked yes)
			(layer "B.Fab")
			(hide yes)
			(effects
				(font
					(size 1 1)
					(thickness 0.15)
				)
				(justify mirror)
			)
		)
		(sheetname "/CSI/")
		(sheetfile "csi.kicad_sch")
		(attr smd)
		(fp_line
			(start 1 1.497)
			(end 1 1.375)
			(stroke
				(width 0.15)
				(type solid)
			)
			(layer "B.SilkS")
		)
		(fp_line
			(start 1 1.497)
			(end -1 1.5)
			(stroke
				(width 0.15)
				(type solid)
			)
			(layer "B.SilkS")
		)
		(fp_line
			(start 1 -1.55)
			(end 1 -1.4)
			(stroke
				(width 0.15)
				(type solid)
			)
			(layer "B.SilkS")
		)
		(fp_line
			(start 1 -1.55)
			(end -1 -1.55)
			(stroke
				(width 0.15)
				(type solid)
			)
			(layer "B.SilkS")
		)
		(fp_line
			(start -1 1.5)
			(end -1 1.375)
			(stroke
				(width 0.15)
				(type solid)
			)
			(layer "B.SilkS")
		)
		(fp_line
			(start -1 -1.55)
			(end -1 -1.4)
			(stroke
				(width 0.15)
				(type solid)
			)
			(layer "B.SilkS")
		)
		(fp_circle
			(center -1.44 1.5)
			(end -1.39 1.5)
			(stroke
				(width 0.15)
				(type solid)
			)
			(fill yes)
			(layer "B.SilkS")
		)
		(fp_poly
			(pts
				(xy 1.930001 1.7) (xy 1.930001 -1.7) (xy -1.930001 -1.7) (xy -1.930001 1.7)
			)
			(stroke
				(width 0.05)
				(type solid)
			)
			(fill no)
			(layer "B.CrtYd")
		)
		(fp_line
			(start -0.45 1.520999)
			(end -0.876001 1.096)
			(stroke
				(width 0.15)
				(type solid)
			)
			(layer "B.Fab")
		)
		(fp_poly
			(pts
				(xy 0.875 -1.528) (xy 0.875 1.525) (xy -0.875 1.525) (xy -0.875 -1.528)
			)
			(stroke
				(width 0.15)
				(type solid)
			)
			(fill no)
			(layer "B.Fab")
		)
		(fp_text user "License: Apache-2.0"
			(at -1.93 -6.199 0)
			(layer "B.Fab")
			(effects
				(font
					(size 0.7 0.7)
					(thickness 0.15)
				)
				(justify left bottom mirror)
			)
		)
		(fp_text user "${REFERENCE}"
			(at -1.93 -3.8 0)
			(layer "B.Fab")
			(effects
				(font
					(size 0.7 0.7)
					(thickness 0.15)
				)
				(justify left bottom mirror)
			)
		)
		(fp_text user "Author: Antmicro"
			(at -1.93 -5 0)
			(layer "B.Fab")
			(effects
				(font
					(size 0.7 0.7)
					(thickness 0.15)
				)
				(justify left bottom mirror)
			)
		)
		(pad "1" smd rect
			(at -1.301 0.947 270)
			(size 0.7 1.2)
			(layers "B.Cu" "B.Mask" "B.Paste")
			(net 9 "/CSI/CSIB_5V")
			(pinfunction "OUT")
			(pintype "power_out")
		)
		(pad "2" smd rect
			(at -1.300999 -0.004 270)
			(size 0.7 1.2)
			(layers "B.Cu" "B.Mask" "B.Paste")
			(net 1 "GND")
			(pinfunction "GND")
			(pintype "power_in")
		)
		(pad "3" smd rect
			(at -1.301 -0.954 270)
			(size 0.7 1.2)
			(layers "B.Cu" "B.Mask" "B.Paste")
			(net 117 "/CSI/CAM_CTRL.CSIB_FLG")
			(pinfunction "FLG")
			(pintype "output")
		)
		(pad "4" smd rect
			(at 1.299 -0.954 270)
			(size 0.7 1.2)
			(layers "B.Cu" "B.Mask" "B.Paste")
			(net 123 "/CSI/CAM_CTRL.CSIB_PEN")
			(pinfunction "EN")
			(pintype "input")
		)
		(pad "5" smd rect
			(at 1.299 -0.004 270)
			(size 0.7 1.2)
			(layers "B.Cu" "B.Mask" "B.Paste")
			(net 997 "/CSI/CSIB_5V_ISET")
			(pinfunction "ISET")
			(pintype "passive")
		)
		(pad "6" smd rect
			(at 1.299 0.947 270)
			(size 0.7 1.2)
			(layers "B.Cu" "B.Mask" "B.Paste")
			(net 5 "+5V")
			(pinfunction "IN")
			(pintype "power_in")
		)
	)
	(footprint "antmicro-footprints:TP_SMD_0.75mm"
		(layer "B.Cu")
		(at 124.5 101.5)
		(property "Reference" "TP38"
			(at 0.61 -0.52 0)
			(layer "B.SilkS")
			(effects
				(font
					(size 0.7 0.7)
					(thickness 0.15)
				)
				(justify right top mirror)
			)
		)
		(property "Value" "TP_0.75mm_SMD"
			(at 0 -1.2 0)
			(layer "B.Fab")
			(effects
				(font
					(size 0.7 0.7)
					(thickness 0.15)
				)
				(justify right top mirror)
			)
		)
		(property "Description" "SMT test point"
			(at 0 0 0)
			(layer "B.Fab")
			(hide yes)
			(effects
				(font
					(size 1.27 1.27)
					(thickness 0.15)
				)
				(justify mirror)
			)
		)
		(property "MPN" ""
			(at 0 0 180)
			(unlocked yes)
			(layer "B.Fab")
			(hide yes)
			(effects
				(font
					(size 1 1)
					(thickness 0.15)
				)
				(justify mirror)
			)
		)
		(property "Manufacturer" ""
			(at 0 0 180)
			(unlocked yes)
			(layer "B.Fab")
			(hide yes)
			(effects
				(font
					(size 1 1)
					(thickness 0.15)
				)
				(justify mirror)
			)
		)
		(property "Author" "Antmicro"
			(at 0 0 180)
			(unlocked yes)
			(layer "B.Fab")
			(hide yes)
			(effects
				(font
					(size 1 1)
					(thickness 0.15)
				)
				(justify mirror)
			)
		)
		(property "License" "Apache-2.0"
			(at 0 0 180)
			(unlocked yes)
			(layer "B.Fab")
			(hide yes)
			(effects
				(font
					(size 1 1)
					(thickness 0.15)
				)
				(justify mirror)
			)
		)
		(sheetname "/M.2/")
		(sheetfile "m2.kicad_sch")
		(attr exclude_from_pos_files exclude_from_bom)
		(fp_circle
			(center 0 0)
			(end 0.475 0)
			(stroke
				(width 0.05)
				(type default)
			)
			(fill no)
			(layer "B.CrtYd")
		)
		(fp_text user "${REFERENCE}"
			(at -0.4 -2.7 0)
			(layer "B.Fab")
			(effects
				(font
					(size 0.7 0.7)
					(thickness 0.15)
				)
				(justify right top mirror)
			)
		)
		(fp_text user "License: Apache-2.0"
			(at -0.4 -5.101 0)
			(layer "B.Fab")
			(effects
				(font
					(size 0.7 0.7)
					(thickness 0.15)
				)
				(justify right top mirror)
			)
		)
		(fp_text user "Author: Antmicro"
			(at -0.4 -3.901 0)
			(layer "B.Fab")
			(effects
				(font
					(size 0.7 0.7)
					(thickness 0.15)
				)
				(justify right top mirror)
			)
		)
		(pad "1" smd circle
			(at 0 0)
			(size 0.75 0.75)
			(layers "B.Cu" "B.Mask")
			(net 235 "/M.2/M2_M_SMB_CLK")
			(pinfunction "1")
			(pintype "passive")
		)
	)
	(footprint "antmicro-footprints:R_0402_1005Metric"
		(layer "B.Cu")
		(at 196.67 76.1)
		(descr "Resistor SMD 0402")
		(tags "resistor SMD 0402")
		(property "Reference" "R110"
			(at 0.83 -0.36 0)
			(layer "B.SilkS")
			(effects
				(font
					(size 0.7 0.7)
					(thickness 0.15)
				)
				(justify right top mirror)
			)
		)
		(property "Value" "R_0R_0402"
			(at -1.011843 -1.772047 0)
			(layer "B.Fab")
			(effects
				(font
					(size 0.7 0.7)
					(thickness 0.15)
				)
				(justify right top mirror)
			)
		)
		(property "Datasheet" "https://industrial.panasonic.com/cdbs/www-data/pdf/RDA0000/AOA0000C301.pdf"
			(at 0 0 0)
			(layer "B.Fab")
			(hide yes)
			(effects
				(font
					(size 1.27 1.27)
					(thickness 0.15)
				)
				(justify mirror)
			)
		)
		(property "Description" "SMD Chip Resistor, Jumper, 0 ohm, 100 mW, 0402 [1005 Metric], Thick Film, General Purpose"
			(at 0 0 0)
			(layer "B.Fab")
			(hide yes)
			(effects
				(font
					(size 1.27 1.27)
					(thickness 0.15)
				)
				(justify mirror)
			)
		)
		(property "Manufacturer" "Panasonic"
			(at 0 0 180)
			(unlocked yes)
			(layer "B.Fab")
			(hide yes)
			(effects
				(font
					(size 1 1)
					(thickness 0.15)
				)
				(justify mirror)
			)
		)
		(property "MPN" "ERJ2GE0R00X"
			(at 0 0 180)
			(unlocked yes)
			(layer "B.Fab")
			(hide yes)
			(effects
				(font
					(size 1 1)
					(thickness 0.15)
				)
				(justify mirror)
			)
		)
		(property "Val" "0R"
			(at 0 0 180)
			(unlocked yes)
			(layer "B.Fab")
			(hide yes)
			(effects
				(font
					(size 1 1)
					(thickness 0.15)
				)
				(justify mirror)
			)
		)
		(property "License" "Apache-2.0"
			(at 0 0 180)
			(unlocked yes)
			(layer "B.Fab")
			(hide yes)
			(effects
				(font
					(size 1 1)
					(thickness 0.15)
				)
				(justify mirror)
			)
		)
		(property "Author" "Antmicro"
			(at 0 0 180)
			(unlocked yes)
			(layer "B.Fab")
			(hide yes)
			(effects
				(font
					(size 1 1)
					(thickness 0.15)
				)
				(justify mirror)
			)
		)
		(property "Tolerance" "~"
			(at 0 0 180)
			(unlocked yes)
			(layer "B.Fab")
			(hide yes)
			(effects
				(font
					(size 1 1)
					(thickness 0.15)
				)
				(justify mirror)
			)
		)
		(property "Current" "1A"
			(at 0 0 180)
			(unlocked yes)
			(layer "B.Fab")
			(hide yes)
			(effects
				(font
					(size 1 1)
					(thickness 0.15)
				)
				(justify mirror)
			)
		)
		(sheetname "/USB Debug, PD/")
		(sheetfile "usb_debug_pd.kicad_sch")
		(attr smd)
		(fp_rect
			(start -0.925 0.47)
			(end 0.925 -0.47)
			(stroke
				(width 0.05)
				(type default)
			)
			(fill no)
			(layer "B.CrtYd")
		)
		(fp_rect
			(start -0.5 0.25)
			(end 0.5 -0.25)
			(stroke
				(width 0.15)
				(type solid)
			)
			(fill no)
			(layer "B.Fab")
		)
		(fp_text user "Author: Antmicro"
			(at -0.95 -4.169 0)
			(layer "B.Fab")
			(effects
				(font
					(size 0.7 0.7)
					(thickness 0.15)
				)
				(justify right top mirror)
			)
		)
		(fp_text user "License: Apache-2.0"
			(at -0.95 -5.169 0)
			(layer "B.Fab")
			(effects
				(font
					(size 0.7 0.7)
					(thickness 0.15)
				)
				(justify right top mirror)
			)
		)
		(fp_text user "${REFERENCE}"
			(at -0.95 -3.168 0)
			(layer "B.Fab")
			(effects
				(font
					(size 0.7 0.7)
					(thickness 0.15)
				)
				(justify right top mirror)
			)
		)
		(pad "1" smd roundrect
			(at -0.48 0)
			(size 0.59 0.64)
			(layers "B.Cu" "B.Mask" "B.Paste")
			(roundrect_rratio 0.25)
			(net 954 "/SoM_IO/~{PDC_I2C1_IRQ}")
			(pintype "passive")
		)
		(pad "2" smd roundrect
			(at 0.48 0)
			(size 0.59 0.64)
			(layers "B.Cu" "B.Mask" "B.Paste")
			(roundrect_rratio 0.25)
			(net 953 "/USB Debug, PD/PDC_I2C1_IRQn")
			(pintype "passive")
		)
	)
	(footprint "antmicro-footprints:C_0402_1005Metric"
		(layer "B.Cu")
		(at 94.180001 103.6 -90)
		(descr "Capacitor SMD 0402")
		(tags "capacitor SMD 0402")
		(property "Reference" "C330"
			(at -3.8 -0.3 90)
			(layer "B.SilkS")
			(effects
				(font
					(size 0.7 0.7)
					(thickness 0.15)
				)
				(justify left bottom mirror)
			)
		)
		(property "Value" "C_100n_0402"
			(at -1.022927 -2.155213 90)
			(layer "B.Fab")
			(effects
				(font
					(size 0.7 0.7)
					(thickness 0.15)
				)
				(justify left bottom mirror)
			)
		)
		(property "Datasheet" "https://www.murata.com/products/productdetail?partno=GRM155R61H104KE14%23"
			(at 0 0 90)
			(layer "B.Fab")
			(hide yes)
			(effects
				(font
					(size 1.27 1.27)
					(thickness 0.15)
				)
				(justify mirror)
			)
		)
		(property "Description" "SMD Multilayer Ceramic Capacitor, 0.1 µF, 50 V, 0402 [1005 Metric], ± 10%, X5R, GRM Series"
			(at 0 0 90)
			(layer "B.Fab")
			(hide yes)
			(effects
				(font
					(size 1.27 1.27)
					(thickness 0.15)
				)
				(justify mirror)
			)
		)
		(property "Manufacturer" "Murata"
			(at 0 0 90)
			(unlocked yes)
			(layer "B.Fab")
			(hide yes)
			(effects
				(font
					(size 1 1)
					(thickness 0.15)
				)
				(justify mirror)
			)
		)
		(property "MPN" "GRM155R61H104KE14D"
			(at 0 0 90)
			(unlocked yes)
			(layer "B.Fab")
			(hide yes)
			(effects
				(font
					(size 1 1)
					(thickness 0.15)
				)
				(justify mirror)
			)
		)
		(property "Val" "100n"
			(at 0 0 90)
			(unlocked yes)
			(layer "B.Fab")
			(hide yes)
			(effects
				(font
					(size 1 1)
					(thickness 0.15)
				)
				(justify mirror)
			)
		)
		(property "License" "Apache-2.0"
			(at 0 0 90)
			(unlocked yes)
			(layer "B.Fab")
			(hide yes)
			(effects
				(font
					(size 1 1)
					(thickness 0.15)
				)
				(justify mirror)
			)
		)
		(property "Author" "Antmicro"
			(at 0 0 90)
			(unlocked yes)
			(layer "B.Fab")
			(hide yes)
			(effects
				(font
					(size 1 1)
					(thickness 0.15)
				)
				(justify mirror)
			)
		)
		(property "Voltage" "50V"
			(at 0 0 90)
			(unlocked yes)
			(layer "B.Fab")
			(hide yes)
			(effects
				(font
					(size 1 1)
					(thickness 0.15)
				)
				(justify mirror)
			)
		)
		(property "Dielectric" "X5R"
			(at 0 0 90)
			(unlocked yes)
			(layer "B.Fab")
			(hide yes)
			(effects
				(font
					(size 1 1)
					(thickness 0.15)
				)
				(justify mirror)
			)
		)
		(sheetname "/SoM_IO2/")
		(sheetfile "som_io2.kicad_sch")
		(attr smd)
		(fp_poly
			(pts
				(xy -0.925 0.47) (xy 0.925 0.47) (xy 0.925 -0.47) (xy -0.925 -0.47)
			)
			(stroke
				(width 0.05)
				(type default)
			)
			(fill no)
			(layer "B.CrtYd")
		)
		(fp_line
			(start -0.494 0.25)
			(end 0.504 0.25)
			(stroke
				(width 0.15)
				(type solid)
			)
			(layer "B.Fab")
		)
		(fp_line
			(start 0.504 0.25)
			(end 0.504 -0.248)
			(stroke
				(width 0.15)
				(type solid)
			)
			(layer "B.Fab")
		)
		(fp_line
			(start -0.494 -0.248)
			(end -0.494 0.25)
			(stroke
				(width 0.15)
				(type solid)
			)
			(layer "B.Fab")
		)
		(fp_line
			(start 0.504 -0.248)
			(end -0.494 -0.248)
			(stroke
				(width 0.15)
				(type solid)
			)
			(layer "B.Fab")
		)
		(fp_text user "Author: Antmicro"
			(at -0.939 -3.399 90)
			(layer "B.Fab")
			(effects
				(font
					(size 0.7 0.7)
					(thickness 0.15)
				)
				(justify left bottom mirror)
			)
		)
		(fp_text user "License: Apache-2.0"
			(at -0.939 -5.799 90)
			(layer "B.Fab")
			(effects
				(font
					(size 0.7 0.7)
					(thickness 0.15)
				)
				(justify left bottom mirror)
			)
		)
		(fp_text user "${REFERENCE}"
			(at -0.939 -4.599 90)
			(layer "B.Fab")
			(effects
				(font
					(size 0.7 0.7)
					(thickness 0.15)
				)
				(justify left bottom mirror)
			)
		)
		(pad "1" smd roundrect
			(at -0.48 0 270)
			(size 0.59 0.64)
			(layers "B.Cu" "B.Mask" "B.Paste")
			(roundrect_rratio 0.25)
			(net 733 "/Expansion connector/DP1.TX2-")
			(pintype "passive")
		)
		(pad "2" smd roundrect
			(at 0.48 0 270)
			(size 0.59 0.64)
			(layers "B.Cu" "B.Mask" "B.Paste")
			(roundrect_rratio 0.25)
			(net 1250 "/SoM_IO2/DP1.TX2_C-")
			(pintype "passive")
		)
	)
	(footprint "antmicro-footprints:R_0402_1005Metric"
		(layer "B.Cu")
		(at 235.694 107.8)
		(descr "Resistor SMD 0402")
		(tags "resistor SMD 0402")
		(property "Reference" "R269"
			(at -2.894 3.7 0)
			(layer "B.SilkS")
			(effects
				(font
					(size 0.7 0.7)
					(thickness 0.15)
				)
				(justify right top mirror)
			)
		)
		(property "Value" "R_10k_0402"
			(at -1.011843 -1.772046 0)
			(layer "B.Fab")
			(effects
				(font
					(size 0.7 0.7)
					(thickness 0.15)
				)
				(justify right top mirror)
			)
		)
		(property "Datasheet" "https://www.bourns.com/docs/product-datasheets/cr.pdf"
			(at 0 0 0)
			(layer "B.Fab")
			(hide yes)
			(effects
				(font
					(size 1.27 1.27)
					(thickness 0.15)
				)
				(justify mirror)
			)
		)
		(property "Description" "SMD Chip Resistor, 10 kohm, ± 1%, 62.5 mW, 0402 [1005 Metric], Thick Film, General Purpose"
			(at 0 0 0)
			(layer "B.Fab")
			(hide yes)
			(effects
				(font
					(size 1.27 1.27)
					(thickness 0.15)
				)
				(justify mirror)
			)
		)
		(property "Manufacturer" "Bourns"
			(at 0 0 180)
			(unlocked yes)
			(layer "B.Fab")
			(hide yes)
			(effects
				(font
					(size 1 1)
					(thickness 0.15)
				)
				(justify mirror)
			)
		)
		(property "MPN" "CR0402-FX-1002GLF"
			(at 0 0 180)
			(unlocked yes)
			(layer "B.Fab")
			(hide yes)
			(effects
				(font
					(size 1 1)
					(thickness 0.15)
				)
				(justify mirror)
			)
		)
		(property "Val" "10k"
			(at 0 0 180)
			(unlocked yes)
			(layer "B.Fab")
			(hide yes)
			(effects
				(font
					(size 1 1)
					(thickness 0.15)
				)
				(justify mirror)
			)
		)
		(property "License" "Apache-2.0"
			(at 0 0 180)
			(unlocked yes)
			(layer "B.Fab")
			(hide yes)
			(effects
				(font
					(size 1 1)
					(thickness 0.15)
				)
				(justify mirror)
			)
		)
		(property "Author" "Antmicro"
			(at 0 0 180)
			(unlocked yes)
			(layer "B.Fab")
			(hide yes)
			(effects
				(font
					(size 1 1)
					(thickness 0.15)
				)
				(justify mirror)
			)
		)
		(property "Tolerance" "1%"
			(at 0 0 180)
			(unlocked yes)
			(layer "B.Fab")
			(hide yes)
			(effects
				(font
					(size 1 1)
					(thickness 0.15)
				)
				(justify mirror)
			)
		)
		(sheetname "/Recovery USB/")
		(sheetfile "recovery_usb.kicad_sch")
		(attr smd)
		(fp_poly
			(pts
				(xy -0.925 0.47) (xy -0.925 -0.47) (xy 0.925 -0.47) (xy 0.925 0.47)
			)
			(stroke
				(width 0.05)
				(type default)
			)
			(fill no)
			(layer "B.CrtYd")
		)
		(fp_poly
			(pts
				(xy -0.5 0.25) (xy -0.5 -0.25) (xy 0.5 -0.25) (xy 0.5 0.25)
			)
			(stroke
				(width 0.15)
				(type solid)
			)
			(fill no)
			(layer "B.Fab")
		)
		(fp_text user "Author: Antmicro"
			(at -0.95 -4.169 0)
			(layer "B.Fab")
			(effects
				(font
					(size 0.7 0.7)
					(thickness 0.15)
				)
				(justify right top mirror)
			)
		)
		(fp_text user "License: Apache-2.0"
			(at -0.949999 -5.169 0)
			(layer "B.Fab")
			(effects
				(font
					(size 0.7 0.7)
					(thickness 0.15)
				)
				(justify right top mirror)
			)
		)
		(fp_text user "${REFERENCE}"
			(at -0.95 -3.168 0)
			(layer "B.Fab")
			(effects
				(font
					(size 0.7 0.7)
					(thickness 0.15)
				)
				(justify right top mirror)
			)
		)
		(pad "1" smd roundrect
			(at -0.48 0)
			(size 0.59 0.64)
			(layers "B.Cu" "B.Mask" "B.Paste")
			(roundrect_rratio 0.25)
			(net 890 "Net-(Q19-D)")
			(pintype "passive")
		)
		(pad "2" smd roundrect
			(at 0.48 0)
			(size 0.59 0.64)
			(layers "B.Cu" "B.Mask" "B.Paste")
			(roundrect_rratio 0.25)
			(net 1245 "Net-(R265-Pad1)")
			(pintype "passive")
		)
	)
	(footprint "antmicro-footprints:R_0402_1005Metric"
		(layer "B.Cu")
		(at 207.8 82.3 180)
		(descr "Resistor SMD 0402")
		(tags "resistor SMD 0402")
		(property "Reference" "R97"
			(at -3.14 0.6 0)
			(layer "B.SilkS")
			(effects
				(font
					(size 0.7 0.7)
					(thickness 0.15)
				)
				(justify left bottom mirror)
			)
		)
		(property "Value" "R_100k_0402"
			(at -1.011843 -1.772046 0)
			(layer "B.Fab")
			(effects
				(font
					(size 0.7 0.7)
					(thickness 0.15)
				)
				(justify left bottom mirror)
			)
		)
		(property "Datasheet" "https://www.bourns.com/docs/product-datasheets/cr.pdf"
			(at 0 0 0)
			(layer "B.Fab")
			(hide yes)
			(effects
				(font
					(size 1.27 1.27)
					(thickness 0.15)
				)
				(justify mirror)
			)
		)
		(property "Description" "SMD Chip Resistor, 100 kohm, ± 1%, 62.5 mW, 0402 [1005 Metric], Thick Film, General Purpose"
			(at 0 0 0)
			(layer "B.Fab")
			(hide yes)
			(effects
				(font
					(size 1.27 1.27)
					(thickness 0.15)
				)
				(justify mirror)
			)
		)
		(property "Manufacturer" "Bourns"
			(at 0 0 0)
			(unlocked yes)
			(layer "B.Fab")
			(hide yes)
			(effects
				(font
					(size 1 1)
					(thickness 0.15)
				)
				(justify mirror)
			)
		)
		(property "MPN" "CR0402-FX-1003GLF"
			(at 0 0 0)
			(unlocked yes)
			(layer "B.Fab")
			(hide yes)
			(effects
				(font
					(size 1 1)
					(thickness 0.15)
				)
				(justify mirror)
			)
		)
		(property "Val" "100k"
			(at 0 0 0)
			(unlocked yes)
			(layer "B.Fab")
			(hide yes)
			(effects
				(font
					(size 1 1)
					(thickness 0.15)
				)
				(justify mirror)
			)
		)
		(property "License" "Apache-2.0"
			(at 0 0 0)
			(unlocked yes)
			(layer "B.Fab")
			(hide yes)
			(effects
				(font
					(size 1 1)
					(thickness 0.15)
				)
				(justify mirror)
			)
		)
		(property "Author" "Antmicro"
			(at 0 0 0)
			(unlocked yes)
			(layer "B.Fab")
			(hide yes)
			(effects
				(font
					(size 1 1)
					(thickness 0.15)
				)
				(justify mirror)
			)
		)
		(property "Tolerance" "1%"
			(at 0 0 0)
			(unlocked yes)
			(layer "B.Fab")
			(hide yes)
			(effects
				(font
					(size 1 1)
					(thickness 0.15)
				)
				(justify mirror)
			)
		)
		(sheetname "/USB Debug, PD/")
		(sheetfile "usb_debug_pd.kicad_sch")
		(attr smd)
		(fp_poly
			(pts
				(xy -0.925 0.47) (xy 0.925 0.47) (xy 0.925 -0.47) (xy -0.925 -0.47)
			)
			(stroke
				(width 0.05)
				(type default)
			)
			(fill no)
			(layer "B.CrtYd")
		)
		(fp_poly
			(pts
				(xy -0.5 0.25) (xy 0.5 0.25) (xy 0.5 -0.25) (xy -0.5 -0.25)
			)
			(stroke
				(width 0.15)
				(type solid)
			)
			(fill no)
			(layer "B.Fab")
		)
		(fp_text user "${REFERENCE}"
			(at -0.95 -3.168 0)
			(layer "B.Fab")
			(effects
				(font
					(size 0.7 0.7)
					(thickness 0.15)
				)
				(justify left bottom mirror)
			)
		)
		(fp_text user "Author: Antmicro"
			(at -0.95 -4.169 0)
			(layer "B.Fab")
			(effects
				(font
					(size 0.7 0.7)
					(thickness 0.15)
				)
				(justify left bottom mirror)
			)
		)
		(fp_text user "License: Apache-2.0"
			(at -0.949999 -5.169 0)
			(layer "B.Fab")
			(effects
				(font
					(size 0.7 0.7)
					(thickness 0.15)
				)
				(justify left bottom mirror)
			)
		)
		(pad "1" smd roundrect
			(at -0.48 0 180)
			(size 0.59 0.64)
			(layers "B.Cu" "B.Mask" "B.Paste")
			(roundrect_rratio 0.25)
			(net 1 "GND")
			(pintype "passive")
		)
		(pad "2" smd roundrect
			(at 0.48 0 180)
			(size 0.59 0.64)
			(layers "B.Cu" "B.Mask" "B.Paste")
			(roundrect_rratio 0.25)
			(net 935 "/USB Debug, PD/PDC_ADCIN2")
			(pintype "passive")
		)
	)
	(footprint "antmicro-footprints:TP_SMD_0.75mm"
		(layer "B.Cu")
		(at 232.3 79.6 -90)
		(property "Reference" "TP19"
			(at 1.1 0.3 0)
			(layer "B.SilkS")
			(effects
				(font
					(size 0.7 0.7)
					(thickness 0.15)
				)
				(justify left bottom mirror)
			)
		)
		(property "Value" "TP_0.75mm_SMD"
			(at 0 -1.2 90)
			(layer "B.Fab")
			(effects
				(font
					(size 0.7 0.7)
					(thickness 0.15)
				)
				(justify left bottom mirror)
			)
		)
		(property "Description" "SMT test point"
			(at 0 0 90)
			(layer "B.Fab")
			(hide yes)
			(effects
				(font
					(size 1.27 1.27)
					(thickness 0.15)
				)
				(justify mirror)
			)
		)
		(property "MPN" ""
			(at 0 0 90)
			(unlocked yes)
			(layer "B.Fab")
			(hide yes)
			(effects
				(font
					(size 1 1)
					(thickness 0.15)
				)
				(justify mirror)
			)
		)
		(property "Manufacturer" ""
			(at 0 0 90)
			(unlocked yes)
			(layer "B.Fab")
			(hide yes)
			(effects
				(font
					(size 1 1)
					(thickness 0.15)
				)
				(justify mirror)
			)
		)
		(property "Author" "Antmicro"
			(at 0 0 90)
			(unlocked yes)
			(layer "B.Fab")
			(hide yes)
			(effects
				(font
					(size 1 1)
					(thickness 0.15)
				)
				(justify mirror)
			)
		)
		(property "License" "Apache-2.0"
			(at 0 0 90)
			(unlocked yes)
			(layer "B.Fab")
			(hide yes)
			(effects
				(font
					(size 1 1)
					(thickness 0.15)
				)
				(justify mirror)
			)
		)
		(sheetname "/USB Debug, PD/")
		(sheetfile "usb_debug_pd.kicad_sch")
		(attr exclude_from_pos_files exclude_from_bom)
		(fp_circle
			(center 0 0)
			(end 0.475 0)
			(stroke
				(width 0.05)
				(type default)
			)
			(fill no)
			(layer "B.CrtYd")
		)
		(fp_text user "License: Apache-2.0"
			(at -0.4 -5.101 90)
			(layer "B.Fab")
			(effects
				(font
					(size 0.7 0.7)
					(thickness 0.15)
				)
				(justify left bottom mirror)
			)
		)
		(fp_text user "Author: Antmicro"
			(at -0.4 -3.901 90)
			(layer "B.Fab")
			(effects
				(font
					(size 0.7 0.7)
					(thickness 0.15)
				)
				(justify left bottom mirror)
			)
		)
		(fp_text user "${REFERENCE}"
			(at -0.4 -2.7 90)
			(layer "B.Fab")
			(effects
				(font
					(size 0.7 0.7)
					(thickness 0.15)
				)
				(justify left bottom mirror)
			)
		)
		(pad "1" smd circle
			(at 0 0 270)
			(size 0.75 0.75)
			(layers "B.Cu" "B.Mask")
			(net 976 "/USB Debug, PD/USBC0_FLG")
			(pinfunction "1")
			(pintype "passive")
		)
	)
	(footprint "antmicro-footprints:Spacer_Drill3.7mm_H2.5mm_9774025151R"
		(locked yes)
		(layer "B.Cu")
		(at 197.66 104.501 90)
		(descr "Spacer M=3 h=2.5mm fi=5.1mm")
		(property "Reference" "H9"
			(at 0 3.2 90)
			(layer "B.SilkS")
			(effects
				(font
					(size 0.7 0.7)
					(thickness 0.15)
				)
				(justify right top mirror)
			)
		)
		(property "Value" "Spacer_Drill3.7mm_H2.5mm_9774025151R"
			(at 0 -4 90)
			(layer "B.Fab")
			(effects
				(font
					(size 0.7 0.7)
					(thickness 0.15)
				)
				(justify right top mirror)
			)
		)
		(property "Datasheet" "https://www.we-online.com/components/products/datasheet/9774025151R.pdf"
			(at 0 0 90)
			(layer "B.Fab")
			(hide yes)
			(effects
				(font
					(size 1.27 1.27)
					(thickness 0.15)
				)
				(justify mirror)
			)
		)
		(property "Description" "Spacer, SMT, Non Stop, Steel, Swage Round, 5.1 mm x 2.5 mm, M2.5 Thread, WA-SMSI Series"
			(at 0 0 90)
			(layer "B.Fab")
			(hide yes)
			(effects
				(font
					(size 1.27 1.27)
					(thickness 0.15)
				)
				(justify mirror)
			)
		)
		(property "Manufacturer" "Würth Elektronik"
			(at 0 0 270)
			(unlocked yes)
			(layer "B.Fab")
			(hide yes)
			(effects
				(font
					(size 1 1)
					(thickness 0.15)
				)
				(justify mirror)
			)
		)
		(property "MPN" "9774025151R"
			(at 0 0 270)
			(unlocked yes)
			(layer "B.Fab")
			(hide yes)
			(effects
				(font
					(size 1 1)
					(thickness 0.15)
				)
				(justify mirror)
			)
		)
		(property "Author" "Antmicro"
			(at 0 0 270)
			(unlocked yes)
			(layer "B.Fab")
			(hide yes)
			(effects
				(font
					(size 1 1)
					(thickness 0.15)
				)
				(justify mirror)
			)
		)
		(property "License" "Apache-2.0"
			(at 0 0 270)
			(unlocked yes)
			(layer "B.Fab")
			(hide yes)
			(effects
				(font
					(size 1 1)
					(thickness 0.15)
				)
				(justify mirror)
			)
		)
		(sheetname "/M.2/")
		(sheetfile "m2.kicad_sch")
		(solder_paste_margin_ratio -1)
		(attr smd)
		(fp_circle
			(center 0 0)
			(end 3.05 0)
			(stroke
				(width 0.05)
				(type solid)
			)
			(fill no)
			(layer "B.CrtYd")
		)
		(fp_circle
			(center 0 0)
			(end 2.6 0)
			(stroke
				(width 0.15)
				(type solid)
			)
			(fill no)
			(layer "B.Fab")
		)
		(fp_text user "License: Apache-2.0"
			(at -9.6 -8.9 90)
			(layer "B.Fab")
			(effects
				(font
					(size 0.7 0.7)
					(thickness 0.15)
				)
				(justify right top mirror)
			)
		)
		(fp_text user "Author: Antmicro"
			(at -9.6 -7.7 90)
			(layer "B.Fab")
			(effects
				(font
					(size 0.7 0.7)
					(thickness 0.15)
				)
				(justify right top mirror)
			)
		)
		(fp_text user "${REFERENCE}"
			(at -9.6 -6.5 90)
			(layer "B.Fab")
			(effects
				(font
					(size 0.7 0.7)
					(thickness 0.15)
				)
				(justify right top mirror)
			)
		)
		(pad "" smd custom
			(at -1.7 -1.7)
			(size 0.62 0.62)
			(layers "B.Paste")
			(thermal_bridge_angle 90)
			(options
				(clearance outline)
				(anchor circle)
			)
			(primitives
				(gr_arc
					(start 1.266786 0.24747)
					(mid 0.285453 -0.29439)
					(end -0.250195 -1.279127)
					(width 0.2)
				)
				(gr_arc
					(start 1.259603 0.339191)
					(mid 0.218448 -0.232561)
					(end -0.34334 -1.279127)
					(width 0.2)
				)
				(gr_arc
					(start 1.255279 0.431435)
					(mid 0.152481 -0.169693)
					(end -0.436309 -1.279127)
					(width 0.2)
				)
				(gr_arc
					(start 1.253811 0.524161)
					(mid 0.087542 -0.105784)
					(end -0.529126 -1.279127)
					(width 0.2)
				)
				(gr_arc
					(start 1.275473 0.621136)
					(mid 0.0309 -0.033527)
					(end -0.621807 -1.279127)
					(width 0.2)
				)
				(gr_arc
					(start 1.263664 0.711602)
					(mid -0.037759 0.026651)
					(end -0.71437 -1.279127)
					(width 0.2)
				)
				(gr_arc
					(start 1.253435 0.802342)
					(mid -0.105837 0.087395)
					(end -0.806826 -1.279127)
					(width 0.2)
				)
				(gr_arc
					(start 1.267475 0.897258)
					(mid -0.165236 0.156885)
					(end -0.899187 -1.279127)
					(width 0.2)
				)
				(gr_arc
					(start 1.270645 0.990112)
					(mid -0.228522 0.222449)
					(end -0.991463 -1.279127)
					(width 0.2)
				)
				(gr_arc
					(start 1.266278 1.081674)
					(mid -0.294507 0.285313)
					(end -1.083663 -1.279127)
					(width 0.2)
				)
				(gr_line
					(start 1.279127 0.250195)
					(end 1.279127 1.083663)
					(width 0.2)
				)
				(gr_line
					(start -0.250195 -1.279127)
					(end -1.083663 -1.279127)
					(width 0.2)
				)
			)
		)
		(pad "" smd custom
			(at -1.7 1.7 90)
			(size 0.62 0.62)
			(layers "B.Paste")
			(thermal_bridge_angle 90)
			(options
				(clearance outline)
				(anchor circle)
			)
			(primitives
				(gr_arc
					(start 1.266786 0.24747)
					(mid 0.285453 -0.29439)
					(end -0.250195 -1.279127)
					(width 0.2)
				)
				(gr_arc
					(start 1.259603 0.339191)
					(mid 0.218448 -0.232561)
					(end -0.34334 -1.279127)
					(width 0.2)
				)
				(gr_arc
					(start 1.255279 0.431435)
					(mid 0.152481 -0.169693)
					(end -0.436309 -1.279127)
					(width 0.2)
				)
				(gr_arc
					(start 1.253811 0.524161)
					(mid 0.087542 -0.105784)
					(end -0.529126 -1.279127)
					(width 0.2)
				)
				(gr_arc
					(start 1.275473 0.621136)
					(mid 0.0309 -0.033527)
					(end -0.621807 -1.279127)
					(width 0.2)
				)
				(gr_arc
					(start 1.263664 0.711602)
					(mid -0.037759 0.026651)
					(end -0.71437 -1.279127)
					(width 0.2)
				)
				(gr_arc
					(start 1.253435 0.802342)
					(mid -0.105837 0.087395)
					(end -0.806826 -1.279127)
					(width 0.2)
				)
				(gr_arc
					(start 1.267475 0.897258)
					(mid -0.165236 0.156885)
					(end -0.899187 -1.279127)
					(width 0.2)
				)
				(gr_arc
					(start 1.270645 0.990112)
					(mid -0.228522 0.222449)
					(end -0.991463 -1.279127)
					(width 0.2)
				)
				(gr_arc
					(start 1.266278 1.081674)
					(mid -0.294507 0.285313)
					(end -1.083663 -1.279127)
					(width 0.2)
				)
				(gr_line
					(start 1.279127 0.250195)
					(end 1.279127 1.083663)
					(width 0.2)
				)
				(gr_line
					(start -0.250195 -1.279127)
					(end -1.083663 -1.279127)
					(width 0.2)
				)
			)
		)
		(pad "" smd custom
			(at 1.7 -1.7 270)
			(size 0.62 0.62)
			(layers "B.Paste")
			(thermal_bridge_angle 90)
			(options
				(clearance outline)
				(anchor circle)
			)
			(primitives
				(gr_arc
					(start 1.266786 0.24747)
					(mid 0.285453 -0.29439)
					(end -0.250195 -1.279127)
					(width 0.2)
				)
				(gr_arc
					(start 1.259603 0.339191)
					(mid 0.218448 -0.232561)
					(end -0.34334 -1.279127)
					(width 0.2)
				)
				(gr_arc
					(start 1.255279 0.431435)
					(mid 0.152481 -0.169693)
					(end -0.436309 -1.279127)
					(width 0.2)
				)
				(gr_arc
					(start 1.253811 0.524161)
					(mid 0.087542 -0.105784)
					(end -0.529126 -1.279127)
					(width 0.2)
				)
				(gr_arc
					(start 1.275473 0.621136)
					(mid 0.0309 -0.033527)
					(end -0.621807 -1.279127)
					(width 0.2)
				)
				(gr_arc
					(start 1.263664 0.711602)
					(mid -0.037759 0.026651)
					(end -0.71437 -1.279127)
					(width 0.2)
				)
				(gr_arc
					(start 1.253435 0.802342)
					(mid -0.105837 0.087395)
					(end -0.806826 -1.279127)
					(width 0.2)
				)
				(gr_arc
					(start 1.267475 0.897258)
					(mid -0.165236 0.156885)
					(end -0.899187 -1.279127)
					(width 0.2)
				)
				(gr_arc
					(start 1.270645 0.990112)
					(mid -0.228522 0.222449)
					(end -0.991463 -1.279127)
					(width 0.2)
				)
				(gr_arc
					(start 1.266278 1.081674)
					(mid -0.294507 0.285313)
					(end -1.083663 -1.279127)
					(width 0.2)
				)
				(gr_line
					(start 1.279127 0.250195)
					(end 1.279127 1.083663)
					(width 0.2)
				)
				(gr_line
					(start -0.250195 -1.279127)
					(end -1.083663 -1.279127)
					(width 0.2)
				)
			)
		)
		(pad "" smd custom
			(at 1.7 1.7 180)
			(size 0.62 0.62)
			(layers "B.Paste")
			(thermal_bridge_angle 90)
			(options
				(clearance outline)
				(anchor circle)
			)
			(primitives
				(gr_arc
					(start 1.266786 0.24747)
					(mid 0.285453 -0.29439)
					(end -0.250195 -1.279127)
					(width 0.2)
				)
				(gr_arc
					(start 1.259603 0.339191)
					(mid 0.218448 -0.232561)
					(end -0.34334 -1.279127)
					(width 0.2)
				)
				(gr_arc
					(start 1.255279 0.431435)
					(mid 0.152481 -0.169693)
					(end -0.436309 -1.279127)
					(width 0.2)
				)
				(gr_arc
					(start 1.253811 0.524161)
					(mid 0.087542 -0.105784)
					(end -0.529126 -1.279127)
					(width 0.2)
				)
				(gr_arc
					(start 1.275473 0.621136)
					(mid 0.0309 -0.033527)
					(end -0.621807 -1.279127)
					(width 0.2)
				)
				(gr_arc
					(start 1.263664 0.711602)
					(mid -0.037759 0.026651)
					(end -0.71437 -1.279127)
					(width 0.2)
				)
				(gr_arc
					(start 1.253435 0.802342)
					(mid -0.105837 0.087395)
					(end -0.806826 -1.279127)
					(width 0.2)
				)
				(gr_arc
					(start 1.267475 0.897258)
					(mid -0.165236 0.156885)
					(end -0.899187 -1.279127)
					(width 0.2)
				)
				(gr_arc
					(start 1.270645 0.990112)
					(mid -0.228522 0.222449)
					(end -0.991463 -1.279127)
					(width 0.2)
				)
				(gr_arc
					(start 1.266278 1.081674)
					(mid -0.294507 0.285313)
					(end -1.083663 -1.279127)
					(width 0.2)
				)
				(gr_line
					(start 1.279127 0.250195)
					(end 1.279127 1.083663)
					(width 0.2)
				)
				(gr_line
					(start -0.250195 -1.279127)
					(end -1.083663 -1.279127)
					(width 0.2)
				)
			)
		)
		(pad "1" thru_hole circle
			(at 0 0 90)
			(size 6 6)
			(drill 3.7)
			(layers "*.Cu" "*.Mask")
			(remove_unused_layers no)
			(net 1 "GND")
			(pintype "passive")
		)
	)
	(footprint "antmicro-footprints:C_0402_1005Metric"
		(layer "B.Cu")
		(at 94 118.77 180)
		(descr "Capacitor SMD 0402")
		(tags "capacitor SMD 0402")
		(property "Reference" "C211"
			(at -3.8 -0.655 0)
			(layer "B.SilkS")
			(effects
				(font
					(size 0.7 0.7)
					(thickness 0.15)
				)
				(justify left bottom mirror)
			)
		)
		(property "Value" "C_220n_0402"
			(at -1.022927 -2.155213 0)
			(layer "B.Fab")
			(effects
				(font
					(size 0.7 0.7)
					(thickness 0.15)
				)
				(justify left bottom mirror)
			)
		)
		(property "Datasheet" "https://www.yageo.com/en/Chart/Download/pdf/CC0402KRX5R6BB224"
			(at 0 0 0)
			(layer "B.Fab")
			(hide yes)
			(effects
				(font
					(size 1.27 1.27)
					(thickness 0.15)
				)
				(justify mirror)
			)
		)
		(property "Description" "SMD Multilayer Ceramic Capacitor, 0.22 µF, 10 V, 0402 [1005 Metric], ± 10%, X5R, CC Series"
			(at 0 0 0)
			(layer "B.Fab")
			(hide yes)
			(effects
				(font
					(size 1.27 1.27)
					(thickness 0.15)
				)
				(justify mirror)
			)
		)
		(property "MPN" "CC0402KRX5R6BB224"
			(at 0 0 180)
			(unlocked yes)
			(layer "B.Fab")
			(hide yes)
			(effects
				(font
					(size 1 1)
					(thickness 0.15)
				)
				(justify mirror)
			)
		)
		(property "Val" "220n"
			(at 0 0 180)
			(unlocked yes)
			(layer "B.Fab")
			(hide yes)
			(effects
				(font
					(size 1 1)
					(thickness 0.15)
				)
				(justify mirror)
			)
		)
		(property "Voltage" "25V"
			(at 0 0 180)
			(unlocked yes)
			(layer "B.Fab")
			(hide yes)
			(effects
				(font
					(size 1 1)
					(thickness 0.15)
				)
				(justify mirror)
			)
		)
		(property "Dielectric" "X7R"
			(at 0 0 180)
			(unlocked yes)
			(layer "B.Fab")
			(hide yes)
			(effects
				(font
					(size 1 1)
					(thickness 0.15)
				)
				(justify mirror)
			)
		)
		(property "Manufacturer" "YAGEO"
			(at 0 0 180)
			(unlocked yes)
			(layer "B.Fab")
			(hide yes)
			(effects
				(font
					(size 1 1)
					(thickness 0.15)
				)
				(justify mirror)
			)
		)
		(property "License" "Apache-2.0"
			(at 0 0 180)
			(unlocked yes)
			(layer "B.Fab")
			(hide yes)
			(effects
				(font
					(size 1 1)
					(thickness 0.15)
				)
				(justify mirror)
			)
		)
		(property "Author" "Antmicro"
			(at 0 0 180)
			(unlocked yes)
			(layer "B.Fab")
			(hide yes)
			(effects
				(font
					(size 1 1)
					(thickness 0.15)
				)
				(justify mirror)
			)
		)
		(property "Public" "False"
			(at 0 0 180)
			(unlocked yes)
			(layer "B.Fab")
			(hide yes)
			(effects
				(font
					(size 1 1)
					(thickness 0.15)
				)
				(justify mirror)
			)
		)
		(sheetname "/Expansion connector/")
		(sheetfile "expansion_connector.kicad_sch")
		(attr smd)
		(fp_poly
			(pts
				(xy -0.925 0.47) (xy 0.925 0.47) (xy 0.925 -0.47) (xy -0.925 -0.47)
			)
			(stroke
				(width 0.05)
				(type default)
			)
			(fill no)
			(layer "B.CrtYd")
		)
		(fp_line
			(start 0.504 0.25)
			(end 0.504 -0.248)
			(stroke
				(width 0.15)
				(type solid)
			)
			(layer "B.Fab")
		)
		(fp_line
			(start 0.504 -0.248)
			(end -0.494 -0.248)
			(stroke
				(width 0.15)
				(type solid)
			)
			(layer "B.Fab")
		)
		(fp_line
			(start -0.494 0.25)
			(end 0.504 0.25)
			(stroke
				(width 0.15)
				(type solid)
			)
			(layer "B.Fab")
		)
		(fp_line
			(start -0.494 -0.248)
			(end -0.494 0.25)
			(stroke
				(width 0.15)
				(type solid)
			)
			(layer "B.Fab")
		)
		(fp_text user "Author: Antmicro"
			(at -0.939 -3.399 0)
			(layer "B.Fab")
			(effects
				(font
					(size 0.7 0.7)
					(thickness 0.15)
				)
				(justify left bottom mirror)
			)
		)
		(fp_text user "License: Apache-2.0"
			(at -0.939 -5.799 0)
			(layer "B.Fab")
			(effects
				(font
					(size 0.7 0.7)
					(thickness 0.15)
				)
				(justify left bottom mirror)
			)
		)
		(fp_text user "${REFERENCE}"
			(at -0.939 -4.599 0)
			(layer "B.Fab")
			(effects
				(font
					(size 0.7 0.7)
					(thickness 0.15)
				)
				(justify left bottom mirror)
			)
		)
		(pad "1" smd roundrect
			(at -0.48 0 180)
			(size 0.59 0.64)
			(layers "B.Cu" "B.Mask" "B.Paste")
			(roundrect_rratio 0.25)
			(net 459 "/Expansion connector/PCIe_{C3x2}.TX0+")
			(pintype "passive")
		)
		(pad "2" smd roundrect
			(at 0.48 0 180)
			(size 0.59 0.64)
			(layers "B.Cu" "B.Mask" "B.Paste")
			(roundrect_rratio 0.25)
			(net 452 "/Expansion connector/PET0_C3_P")
			(pintype "passive")
		)
	)
	(footprint "antmicro-footprints:R_0402_1005Metric"
		(layer "B.Cu")
		(at 203.4 106.800001)
		(descr "Resistor SMD 0402")
		(tags "resistor SMD 0402")
		(property "Reference" "R283"
			(at 1.1 -0.300001 0)
			(layer "B.SilkS")
			(effects
				(font
					(size 0.7 0.7)
					(thickness 0.15)
				)
				(justify right top mirror)
			)
		)
		(property "Value" "R_0R_0402"
			(at -1.011843 -1.772046 0)
			(layer "B.Fab")
			(effects
				(font
					(size 0.7 0.7)
					(thickness 0.15)
				)
				(justify right top mirror)
			)
		)
		(property "Datasheet" "https://industrial.panasonic.com/cdbs/www-data/pdf/RDA0000/AOA0000C301.pdf"
			(at 0 0 0)
			(layer "B.Fab")
			(hide yes)
			(effects
				(font
					(size 1.27 1.27)
					(thickness 0.15)
				)
				(justify mirror)
			)
		)
		(property "Description" "SMD Chip Resistor, Jumper, 0 ohm, 100 mW, 0402 [1005 Metric], Thick Film, General Purpose"
			(at 0 0 0)
			(layer "B.Fab")
			(hide yes)
			(effects
				(font
					(size 1.27 1.27)
					(thickness 0.15)
				)
				(justify mirror)
			)
		)
		(property "Manufacturer" "Panasonic"
			(at 0 0 180)
			(unlocked yes)
			(layer "B.Fab")
			(hide yes)
			(effects
				(font
					(size 1 1)
					(thickness 0.15)
				)
				(justify mirror)
			)
		)
		(property "MPN" "ERJ2GE0R00X"
			(at 0 0 180)
			(unlocked yes)
			(layer "B.Fab")
			(hide yes)
			(effects
				(font
					(size 1 1)
					(thickness 0.15)
				)
				(justify mirror)
			)
		)
		(property "Val" "0R"
			(at 0 0 180)
			(unlocked yes)
			(layer "B.Fab")
			(hide yes)
			(effects
				(font
					(size 1 1)
					(thickness 0.15)
				)
				(justify mirror)
			)
		)
		(property "License" "Apache-2.0"
			(at 0 0 180)
			(unlocked yes)
			(layer "B.Fab")
			(hide yes)
			(effects
				(font
					(size 1 1)
					(thickness 0.15)
				)
				(justify mirror)
			)
		)
		(property "Author" "Antmicro"
			(at 0 0 180)
			(unlocked yes)
			(layer "B.Fab")
			(hide yes)
			(effects
				(font
					(size 1 1)
					(thickness 0.15)
				)
				(justify mirror)
			)
		)
		(property "Tolerance" "~"
			(at 0 0 180)
			(unlocked yes)
			(layer "B.Fab")
			(hide yes)
			(effects
				(font
					(size 1 1)
					(thickness 0.15)
				)
				(justify mirror)
			)
		)
		(property "Current" "1A"
			(at 0 0 180)
			(unlocked yes)
			(layer "B.Fab")
			(hide yes)
			(effects
				(font
					(size 1 1)
					(thickness 0.15)
				)
				(justify mirror)
			)
		)
		(sheetname "/Recovery USB/")
		(sheetfile "recovery_usb.kicad_sch")
		(attr smd exclude_from_pos_files exclude_from_bom dnp)
		(fp_poly
			(pts
				(xy -0.925 0.47) (xy -0.925 -0.47) (xy 0.925 -0.47) (xy 0.925 0.47)
			)
			(stroke
				(width 0.05)
				(type default)
			)
			(fill no)
			(layer "B.CrtYd")
		)
		(fp_poly
			(pts
				(xy -0.5 0.25) (xy -0.5 -0.25) (xy 0.5 -0.25) (xy 0.5 0.25)
			)
			(stroke
				(width 0.15)
				(type solid)
			)
			(fill no)
			(layer "B.Fab")
		)
		(fp_text user "Author: Antmicro"
			(at -0.95 -4.169 0)
			(layer "B.Fab")
			(effects
				(font
					(size 0.7 0.7)
					(thickness 0.15)
				)
				(justify right top mirror)
			)
		)
		(fp_text user "${REFERENCE}"
			(at -0.95 -3.168 0)
			(layer "B.Fab")
			(effects
				(font
					(size 0.7 0.7)
					(thickness 0.15)
				)
				(justify right top mirror)
			)
		)
		(fp_text user "License: Apache-2.0"
			(at -0.949999 -5.169 0)
			(layer "B.Fab")
			(effects
				(font
					(size 0.7 0.7)
					(thickness 0.15)
				)
				(justify right top mirror)
			)
		)
		(pad "1" smd roundrect
			(at -0.48 0)
			(size 0.59 0.64)
			(layers "B.Cu" "B.Mask" "B.Paste")
			(roundrect_rratio 0.25)
			(net 1026 "/Recovery USB/~{USBC2_INT}")
			(pintype "passive")
		)
		(pad "2" smd roundrect
			(at 0.48 0)
			(size 0.59 0.64)
			(layers "B.Cu" "B.Mask" "B.Paste")
			(roundrect_rratio 0.25)
			(net 1366 "/Recovery USB/~{USBC2_INT_R}")
			(pintype "passive")
		)
	)
	(footprint "antmicro-footprints:C_0603_1608Metric_EIA"
		(layer "B.Cu")
		(at 120.64 69.44 180)
		(descr "Capacitor SMD 0603, IPC-7351 Density Level A")
		(tags "Capacitor 0603")
		(property "Reference" "C24"
			(at -1.16 0.84 0)
			(layer "B.SilkS")
			(effects
				(font
					(size 0.7 0.7)
					(thickness 0.15)
				)
				(justify left bottom mirror)
			)
		)
		(property "Value" "C_22u_16V_0603"
			(at -1.42757 -1.770288 0)
			(layer "B.Fab")
			(effects
				(font
					(size 0.7 0.7)
					(thickness 0.15)
				)
				(justify left bottom mirror)
			)
		)
		(property "Datasheet" "https://product.samsungsem.com/mlcc/CL10A226MO7JZN.do"
			(at 0 0 0)
			(layer "B.Fab")
			(hide yes)
			(effects
				(font
					(size 1.27 1.27)
					(thickness 0.15)
				)
				(justify mirror)
			)
		)
		(property "Description" "SMD Multilayer Ceramic Capacitor"
			(at 0 0 0)
			(layer "B.Fab")
			(hide yes)
			(effects
				(font
					(size 1.27 1.27)
					(thickness 0.15)
				)
				(justify mirror)
			)
		)
		(property "MPN" "CL10A226MO7JZNC"
			(at 0 0 180)
			(unlocked yes)
			(layer "B.Fab")
			(hide yes)
			(effects
				(font
					(size 1 1)
					(thickness 0.15)
				)
				(justify mirror)
			)
		)
		(property "Manufacturer" "Samsung Electro-Mechanics"
			(at 0 0 180)
			(unlocked yes)
			(layer "B.Fab")
			(hide yes)
			(effects
				(font
					(size 1 1)
					(thickness 0.15)
				)
				(justify mirror)
			)
		)
		(property "License" "Apache-2.0"
			(at 0 0 180)
			(unlocked yes)
			(layer "B.Fab")
			(hide yes)
			(effects
				(font
					(size 1 1)
					(thickness 0.15)
				)
				(justify mirror)
			)
		)
		(property "Author" "Antmicro"
			(at 0 0 180)
			(unlocked yes)
			(layer "B.Fab")
			(hide yes)
			(effects
				(font
					(size 1 1)
					(thickness 0.15)
				)
				(justify mirror)
			)
		)
		(property "Val" "22u"
			(at 0 0 180)
			(unlocked yes)
			(layer "B.Fab")
			(hide yes)
			(effects
				(font
					(size 1 1)
					(thickness 0.15)
				)
				(justify mirror)
			)
		)
		(property "Voltage" "16V"
			(at 0 0 180)
			(unlocked yes)
			(layer "B.Fab")
			(hide yes)
			(effects
				(font
					(size 1 1)
					(thickness 0.15)
				)
				(justify mirror)
			)
		)
		(property "Dielectric" "X7R"
			(at 0 0 180)
			(unlocked yes)
			(layer "B.Fab")
			(hide yes)
			(effects
				(font
					(size 1 1)
					(thickness 0.15)
				)
				(justify mirror)
			)
		)
		(property "Public" "False"
			(at 0 0 180)
			(unlocked yes)
			(layer "B.Fab")
			(hide yes)
			(effects
				(font
					(size 1 1)
					(thickness 0.15)
				)
				(justify mirror)
			)
		)
		(sheetname "/SoM_Power/")
		(sheetfile "som_power.kicad_sch")
		(attr smd)
		(fp_line
			(start -0.15 0.55)
			(end 0.15 0.55)
			(stroke
				(width 0.15)
				(type solid)
			)
			(layer "B.SilkS")
		)
		(fp_line
			(start -0.15 -0.55)
			(end 0.15 -0.55)
			(stroke
				(width 0.15)
				(type solid)
			)
			(layer "B.SilkS")
		)
		(fp_rect
			(start -1.25 0.65)
			(end 1.25 -0.65)
			(stroke
				(width 0.05)
				(type solid)
			)
			(fill no)
			(layer "B.CrtYd")
		)
		(fp_rect
			(start -0.8 0.45)
			(end 0.8 -0.45)
			(stroke
				(width 0.15)
				(type solid)
			)
			(fill no)
			(layer "B.Fab")
		)
		(fp_text user "License: Apache-2.0"
			(at -1.682 -5.895 0)
			(layer "B.Fab")
			(effects
				(font
					(size 0.7 0.7)
					(thickness 0.15)
				)
				(justify left bottom mirror)
			)
		)
		(fp_text user "${REFERENCE}"
			(at -1.682 -3.895 0)
			(layer "B.Fab")
			(effects
				(font
					(size 0.7 0.7)
					(thickness 0.15)
				)
				(justify left bottom mirror)
			)
		)
		(fp_text user "Author: Antmicro"
			(at -1.682 -4.894 0)
			(layer "B.Fab")
			(effects
				(font
					(size 0.7 0.7)
					(thickness 0.15)
				)
				(justify left bottom mirror)
			)
		)
		(pad "1" smd roundrect
			(at -0.7 0 180)
			(size 0.8 1.1)
			(layers "B.Cu" "B.Mask" "B.Paste")
			(roundrect_rratio 0.2)
			(net 1 "GND")
			(pintype "passive")
		)
		(pad "2" smd roundrect
			(at 0.7 0 180)
			(size 0.8 1.1)
			(layers "B.Cu" "B.Mask" "B.Paste")
			(roundrect_rratio 0.2)
			(net 213 "+5V_SOM")
			(pintype "passive")
		)
	)
	(footprint "antmicro-footprints:TP_SMD_0.75mm"
		(layer "B.Cu")
		(at 233.5 103.3 180)
		(property "Reference" "TP47"
			(at 0 0.6 0)
			(layer "B.SilkS")
			(effects
				(font
					(size 0.7 0.7)
					(thickness 0.15)
				)
				(justify left bottom mirror)
			)
		)
		(property "Value" "TP_0.75mm_SMD"
			(at 0 -1.2 0)
			(layer "B.Fab")
			(effects
				(font
					(size 0.7 0.7)
					(thickness 0.15)
				)
				(justify left bottom mirror)
			)
		)
		(property "Description" "SMT test point"
			(at 0 0 0)
			(layer "B.Fab")
			(hide yes)
			(effects
				(font
					(size 1.27 1.27)
					(thickness 0.15)
				)
				(justify mirror)
			)
		)
		(property "MPN" ""
			(at 0 0 0)
			(unlocked yes)
			(layer "B.Fab")
			(hide yes)
			(effects
				(font
					(size 1 1)
					(thickness 0.15)
				)
				(justify mirror)
			)
		)
		(property "Manufacturer" ""
			(at 0 0 0)
			(unlocked yes)
			(layer "B.Fab")
			(hide yes)
			(effects
				(font
					(size 1 1)
					(thickness 0.15)
				)
				(justify mirror)
			)
		)
		(property "Author" "Antmicro"
			(at 0 0 0)
			(unlocked yes)
			(layer "B.Fab")
			(hide yes)
			(effects
				(font
					(size 1 1)
					(thickness 0.15)
				)
				(justify mirror)
			)
		)
		(property "License" "Apache-2.0"
			(at 0 0 0)
			(unlocked yes)
			(layer "B.Fab")
			(hide yes)
			(effects
				(font
					(size 1 1)
					(thickness 0.15)
				)
				(justify mirror)
			)
		)
		(sheetname "/Recovery USB/")
		(sheetfile "recovery_usb.kicad_sch")
		(attr exclude_from_pos_files exclude_from_bom)
		(fp_circle
			(center 0 0)
			(end 0.475 0)
			(stroke
				(width 0.05)
				(type default)
			)
			(fill no)
			(layer "B.CrtYd")
		)
		(fp_text user "License: Apache-2.0"
			(at -0.4 -5.101 0)
			(layer "B.Fab")
			(effects
				(font
					(size 0.7 0.7)
					(thickness 0.15)
				)
				(justify left bottom mirror)
			)
		)
		(fp_text user "Author: Antmicro"
			(at -0.4 -3.901 0)
			(layer "B.Fab")
			(effects
				(font
					(size 0.7 0.7)
					(thickness 0.15)
				)
				(justify left bottom mirror)
			)
		)
		(fp_text user "${REFERENCE}"
			(at -0.4 -2.7 0)
			(layer "B.Fab")
			(effects
				(font
					(size 0.7 0.7)
					(thickness 0.15)
				)
				(justify left bottom mirror)
			)
		)
		(pad "1" smd circle
			(at 0 0 180)
			(size 0.75 0.75)
			(layers "B.Cu" "B.Mask")
			(net 287 "/Recovery USB/USBC2_VBUS")
			(pinfunction "1")
			(pintype "passive")
		)
	)
	(footprint "antmicro-footprints:R_0402_1005Metric"
		(layer "B.Cu")
		(at 207.8 80.3 180)
		(descr "Resistor SMD 0402")
		(tags "resistor SMD 0402")
		(property "Reference" "R31"
			(at -3.140532 -0.4 0)
			(layer "B.SilkS")
			(effects
				(font
					(size 0.7 0.7)
					(thickness 0.15)
				)
				(justify left bottom mirror)
			)
		)
		(property "Value" "R_15k_0402"
			(at -1.011843 -1.772047 0)
			(layer "B.Fab")
			(effects
				(font
					(size 0.7 0.7)
					(thickness 0.15)
				)
				(justify left bottom mirror)
			)
		)
		(property "Datasheet" "https://www.bourns.com/docs/product-datasheets/cr.pdf"
			(at 0 0 0)
			(layer "B.Fab")
			(hide yes)
			(effects
				(font
					(size 1.27 1.27)
					(thickness 0.15)
				)
				(justify mirror)
			)
		)
		(property "Description" "SMD Chip Resistor, 15 kohm, ± 1%, 62.5 mW, 0402 [1005 Metric], Thick Film, General Purpose"
			(at 0 0 0)
			(layer "B.Fab")
			(hide yes)
			(effects
				(font
					(size 1.27 1.27)
					(thickness 0.15)
				)
				(justify mirror)
			)
		)
		(property "MPN" "CR0402-FX-1502GLF"
			(at 0 0 0)
			(unlocked yes)
			(layer "B.Fab")
			(hide yes)
			(effects
				(font
					(size 1 1)
					(thickness 0.15)
				)
				(justify mirror)
			)
		)
		(property "Manufacturer" "Bourns"
			(at 0 0 0)
			(unlocked yes)
			(layer "B.Fab")
			(hide yes)
			(effects
				(font
					(size 1 1)
					(thickness 0.15)
				)
				(justify mirror)
			)
		)
		(property "License" "Apache-2.0"
			(at 0 0 0)
			(unlocked yes)
			(layer "B.Fab")
			(hide yes)
			(effects
				(font
					(size 1 1)
					(thickness 0.15)
				)
				(justify mirror)
			)
		)
		(property "Author" "Antmicro"
			(at 0 0 0)
			(unlocked yes)
			(layer "B.Fab")
			(hide yes)
			(effects
				(font
					(size 1 1)
					(thickness 0.15)
				)
				(justify mirror)
			)
		)
		(property "Val" "15k"
			(at 0 0 0)
			(unlocked yes)
			(layer "B.Fab")
			(hide yes)
			(effects
				(font
					(size 1 1)
					(thickness 0.15)
				)
				(justify mirror)
			)
		)
		(property "Tolerance" "1%"
			(at 0 0 0)
			(unlocked yes)
			(layer "B.Fab")
			(hide yes)
			(effects
				(font
					(size 1 1)
					(thickness 0.15)
				)
				(justify mirror)
			)
		)
		(sheetname "/USB Debug, PD/")
		(sheetfile "usb_debug_pd.kicad_sch")
		(attr smd)
		(fp_rect
			(start -0.925 0.47)
			(end 0.925 -0.47)
			(stroke
				(width 0.05)
				(type default)
			)
			(fill no)
			(layer "B.CrtYd")
		)
		(fp_rect
			(start -0.5 0.25)
			(end 0.5 -0.25)
			(stroke
				(width 0.15)
				(type solid)
			)
			(fill no)
			(layer "B.Fab")
		)
		(fp_text user "License: Apache-2.0"
			(at -0.95 -5.169 0)
			(layer "B.Fab")
			(effects
				(font
					(size 0.7 0.7)
					(thickness 0.15)
				)
				(justify left bottom mirror)
			)
		)
		(fp_text user "${REFERENCE}"
			(at -0.95 -3.168 0)
			(layer "B.Fab")
			(effects
				(font
					(size 0.7 0.7)
					(thickness 0.15)
				)
				(justify left bottom mirror)
			)
		)
		(fp_text user "Author: Antmicro"
			(at -0.95 -4.169 0)
			(layer "B.Fab")
			(effects
				(font
					(size 0.7 0.7)
					(thickness 0.15)
				)
				(justify left bottom mirror)
			)
		)
		(pad "1" smd roundrect
			(at -0.48 0 180)
			(size 0.59 0.64)
			(layers "B.Cu" "B.Mask" "B.Paste")
			(roundrect_rratio 0.25)
			(net 1 "GND")
			(pintype "passive")
		)
		(pad "2" smd roundrect
			(at 0.48 0 180)
			(size 0.59 0.64)
			(layers "B.Cu" "B.Mask" "B.Paste")
			(roundrect_rratio 0.25)
			(net 934 "/USB Debug, PD/PDC_ADCIN1")
			(pintype "passive")
		)
	)
	(footprint "antmicro-footprints:C_0402_1005Metric"
		(layer "B.Cu")
		(at 225.521 79.335 90)
		(descr "Capacitor SMD 0402")
		(tags "capacitor SMD 0402")
		(property "Reference" "C149"
			(at -3.865 -0.321 90)
			(layer "B.SilkS")
			(effects
				(font
					(size 0.7 0.7)
					(thickness 0.15)
				)
				(justify right top mirror)
			)
		)
		(property "Value" "C_47p_0402"
			(at -1.022927 -2.155213 90)
			(layer "B.Fab")
			(effects
				(font
					(size 0.7 0.7)
					(thickness 0.15)
				)
				(justify right top mirror)
			)
		)
		(property "Datasheet" "https://www.kemet.com/en/us/capacitors/product/C0402C470J5GACTU.html"
			(at 0 0 90)
			(layer "B.Fab")
			(hide yes)
			(effects
				(font
					(size 1.27 1.27)
					(thickness 0.15)
				)
				(justify mirror)
			)
		)
		(property "Description" "SMD Multilayer Ceramic Capacitor, 47 pF, 50 V, 0402 [1005 Metric], ± 5%, C0G / NP0, C Series KEMET"
			(at 0 0 90)
			(layer "B.Fab")
			(hide yes)
			(effects
				(font
					(size 1.27 1.27)
					(thickness 0.15)
				)
				(justify mirror)
			)
		)
		(property "MPN" "C0402C470J5GACTU"
			(at 0 0 270)
			(unlocked yes)
			(layer "B.Fab")
			(hide yes)
			(effects
				(font
					(size 1 1)
					(thickness 0.15)
				)
				(justify mirror)
			)
		)
		(property "Manufacturer" "KEMET"
			(at 0 0 270)
			(unlocked yes)
			(layer "B.Fab")
			(hide yes)
			(effects
				(font
					(size 1 1)
					(thickness 0.15)
				)
				(justify mirror)
			)
		)
		(property "License" "Apache-2.0"
			(at 0 0 270)
			(unlocked yes)
			(layer "B.Fab")
			(hide yes)
			(effects
				(font
					(size 1 1)
					(thickness 0.15)
				)
				(justify mirror)
			)
		)
		(property "Author" "Antmicro"
			(at 0 0 270)
			(unlocked yes)
			(layer "B.Fab")
			(hide yes)
			(effects
				(font
					(size 1 1)
					(thickness 0.15)
				)
				(justify mirror)
			)
		)
		(property "Val" "47p"
			(at 0 0 270)
			(unlocked yes)
			(layer "B.Fab")
			(hide yes)
			(effects
				(font
					(size 1 1)
					(thickness 0.15)
				)
				(justify mirror)
			)
		)
		(property "Voltage" ""
			(at 0 0 270)
			(unlocked yes)
			(layer "B.Fab")
			(hide yes)
			(effects
				(font
					(size 1 1)
					(thickness 0.15)
				)
				(justify mirror)
			)
		)
		(property "Dielectric" "C0G"
			(at 0 0 270)
			(unlocked yes)
			(layer "B.Fab")
			(hide yes)
			(effects
				(font
					(size 1 1)
					(thickness 0.15)
				)
				(justify mirror)
			)
		)
		(sheetname "/USB Debug, PD/")
		(sheetfile "usb_debug_pd.kicad_sch")
		(attr smd)
		(fp_rect
			(start -0.925 0.47)
			(end 0.925 -0.47)
			(stroke
				(width 0.05)
				(type default)
			)
			(fill no)
			(layer "B.CrtYd")
		)
		(fp_line
			(start 0.504 -0.248)
			(end -0.494 -0.248)
			(stroke
				(width 0.15)
				(type solid)
			)
			(layer "B.Fab")
		)
		(fp_line
			(start -0.494 -0.248)
			(end -0.494 0.25)
			(stroke
				(width 0.15)
				(type solid)
			)
			(layer "B.Fab")
		)
		(fp_line
			(start 0.504 0.25)
			(end 0.504 -0.248)
			(stroke
				(width 0.15)
				(type solid)
			)
			(layer "B.Fab")
		)
		(fp_line
			(start -0.494 0.25)
			(end 0.504 0.25)
			(stroke
				(width 0.15)
				(type solid)
			)
			(layer "B.Fab")
		)
		(fp_text user "License: Apache-2.0"
			(at -0.939 -5.799 90)
			(layer "B.Fab")
			(effects
				(font
					(size 0.7 0.7)
					(thickness 0.15)
				)
				(justify right top mirror)
			)
		)
		(fp_text user "Author: Antmicro"
			(at -0.939 -3.399 90)
			(layer "B.Fab")
			(effects
				(font
					(size 0.7 0.7)
					(thickness 0.15)
				)
				(justify right top mirror)
			)
		)
		(fp_text user "${REFERENCE}"
			(at -0.939 -4.599 90)
			(layer "B.Fab")
			(effects
				(font
					(size 0.7 0.7)
					(thickness 0.15)
				)
				(justify right top mirror)
			)
		)
		(pad "1" smd roundrect
			(at -0.48 0 90)
			(size 0.59 0.64)
			(layers "B.Cu" "B.Mask" "B.Paste")
			(roundrect_rratio 0.25)
			(net 1 "GND")
			(pintype "passive")
		)
		(pad "2" smd roundrect
			(at 0.48 0 90)
			(size 0.59 0.64)
			(layers "B.Cu" "B.Mask" "B.Paste")
			(roundrect_rratio 0.25)
			(net 488 "/USB Debug, PD/USBC0_D_N")
			(pintype "passive")
		)
	)
	(footprint "antmicro-footprints:TP_SMD_0.75mm"
		(layer "B.Cu")
		(at 89.96 76.59 90)
		(property "Reference" "TP58"
			(at 0.39 0.64 180)
			(layer "B.SilkS")
			(effects
				(font
					(size 0.7 0.7)
					(thickness 0.15)
				)
				(justify right top mirror)
			)
		)
		(property "Value" "TP_0.75mm_SMD"
			(at 0 -1.2 90)
			(layer "B.Fab")
			(effects
				(font
					(size 0.7 0.7)
					(thickness 0.15)
				)
				(justify right top mirror)
			)
		)
		(property "Description" "SMT test point"
			(at 0 0 90)
			(layer "B.Fab")
			(hide yes)
			(effects
				(font
					(size 1.27 1.27)
					(thickness 0.15)
				)
				(justify mirror)
			)
		)
		(property "MPN" ""
			(at 0 0 270)
			(unlocked yes)
			(layer "B.Fab")
			(hide yes)
			(effects
				(font
					(size 1 1)
					(thickness 0.15)
				)
				(justify mirror)
			)
		)
		(property "Manufacturer" ""
			(at 0 0 270)
			(unlocked yes)
			(layer "B.Fab")
			(hide yes)
			(effects
				(font
					(size 1 1)
					(thickness 0.15)
				)
				(justify mirror)
			)
		)
		(property "Author" "Antmicro"
			(at 0 0 270)
			(unlocked yes)
			(layer "B.Fab")
			(hide yes)
			(effects
				(font
					(size 1 1)
					(thickness 0.15)
				)
				(justify mirror)
			)
		)
		(property "License" "Apache-2.0"
			(at 0 0 270)
			(unlocked yes)
			(layer "B.Fab")
			(hide yes)
			(effects
				(font
					(size 1 1)
					(thickness 0.15)
				)
				(justify mirror)
			)
		)
		(sheetname "/SoM_Power/")
		(sheetfile "som_power.kicad_sch")
		(attr exclude_from_pos_files exclude_from_bom)
		(fp_circle
			(center 0 0)
			(end 0.475 0)
			(stroke
				(width 0.05)
				(type default)
			)
			(fill no)
			(layer "B.CrtYd")
		)
		(fp_text user "Author: Antmicro"
			(at -0.4 -3.901 90)
			(layer "B.Fab")
			(effects
				(font
					(size 0.7 0.7)
					(thickness 0.15)
				)
				(justify right top mirror)
			)
		)
		(fp_text user "${REFERENCE}"
			(at -0.4 -2.7 90)
			(layer "B.Fab")
			(effects
				(font
					(size 0.7 0.7)
					(thickness 0.15)
				)
				(justify right top mirror)
			)
		)
		(fp_text user "License: Apache-2.0"
			(at -0.4 -5.101 90)
			(layer "B.Fab")
			(effects
				(font
					(size 0.7 0.7)
					(thickness 0.15)
				)
				(justify right top mirror)
			)
		)
		(pad "1" smd circle
			(at 0 0 90)
			(size 0.75 0.75)
			(layers "B.Cu" "B.Mask")
			(net 739 "Net-(J1A-GPIO56)")
			(pinfunction "1")
			(pintype "passive")
		)
	)
	(footprint "antmicro-footprints:R_0402_1005Metric"
		(layer "B.Cu")
		(at 195.9 87.8 90)
		(descr "Resistor SMD 0402")
		(tags "resistor SMD 0402")
		(property "Reference" "R382"
			(at -3.7 -0.4 90)
			(layer "B.SilkS")
			(effects
				(font
					(size 0.7 0.7)
					(thickness 0.15)
				)
				(justify right top mirror)
			)
		)
		(property "Value" "R_0R_0402"
			(at -1.011843 -1.772047 90)
			(layer "B.Fab")
			(effects
				(font
					(size 0.7 0.7)
					(thickness 0.15)
				)
				(justify right top mirror)
			)
		)
		(property "Datasheet" "https://industrial.panasonic.com/cdbs/www-data/pdf/RDA0000/AOA0000C301.pdf"
			(at 0 0 90)
			(layer "B.Fab")
			(hide yes)
			(effects
				(font
					(size 1.27 1.27)
					(thickness 0.15)
				)
				(justify mirror)
			)
		)
		(property "Description" "SMD Chip Resistor, Jumper, 0 ohm, 100 mW, 0402 [1005 Metric], Thick Film, General Purpose"
			(at 0 0 90)
			(layer "B.Fab")
			(hide yes)
			(effects
				(font
					(size 1.27 1.27)
					(thickness 0.15)
				)
				(justify mirror)
			)
		)
		(property "MPN" "ERJ2GE0R00X"
			(at 0 0 270)
			(unlocked yes)
			(layer "B.Fab")
			(hide yes)
			(effects
				(font
					(size 1 1)
					(thickness 0.15)
				)
				(justify mirror)
			)
		)
		(property "Manufacturer" "Panasonic"
			(at 0 0 270)
			(unlocked yes)
			(layer "B.Fab")
			(hide yes)
			(effects
				(font
					(size 1 1)
					(thickness 0.15)
				)
				(justify mirror)
			)
		)
		(property "License" "Apache-2.0"
			(at 0 0 270)
			(unlocked yes)
			(layer "B.Fab")
			(hide yes)
			(effects
				(font
					(size 1 1)
					(thickness 0.15)
				)
				(justify mirror)
			)
		)
		(property "Author" "Antmicro"
			(at 0 0 270)
			(unlocked yes)
			(layer "B.Fab")
			(hide yes)
			(effects
				(font
					(size 1 1)
					(thickness 0.15)
				)
				(justify mirror)
			)
		)
		(property "Val" "0R"
			(at 0 0 270)
			(unlocked yes)
			(layer "B.Fab")
			(hide yes)
			(effects
				(font
					(size 1 1)
					(thickness 0.15)
				)
				(justify mirror)
			)
		)
		(property "Tolerance" "~"
			(at 0 0 270)
			(unlocked yes)
			(layer "B.Fab")
			(hide yes)
			(effects
				(font
					(size 1 1)
					(thickness 0.15)
				)
				(justify mirror)
			)
		)
		(property "Current" "1A"
			(at 0 0 270)
			(unlocked yes)
			(layer "B.Fab")
			(hide yes)
			(effects
				(font
					(size 1 1)
					(thickness 0.15)
				)
				(justify mirror)
			)
		)
		(sheetname "/USB Debug, PD/")
		(sheetfile "usb_debug_pd.kicad_sch")
		(attr smd)
		(fp_rect
			(start -0.925 0.47)
			(end 0.925 -0.47)
			(stroke
				(width 0.05)
				(type default)
			)
			(fill no)
			(layer "B.CrtYd")
		)
		(fp_rect
			(start -0.5 0.25)
			(end 0.5 -0.25)
			(stroke
				(width 0.15)
				(type solid)
			)
			(fill no)
			(layer "B.Fab")
		)
		(fp_text user "Author: Antmicro"
			(at -0.95 -4.169 90)
			(layer "B.Fab")
			(effects
				(font
					(size 0.7 0.7)
					(thickness 0.15)
				)
				(justify right top mirror)
			)
		)
		(fp_text user "License: Apache-2.0"
			(at -0.95 -5.169 90)
			(layer "B.Fab")
			(effects
				(font
					(size 0.7 0.7)
					(thickness 0.15)
				)
				(justify right top mirror)
			)
		)
		(fp_text user "${REFERENCE}"
			(at -0.95 -3.168 90)
			(layer "B.Fab")
			(effects
				(font
					(size 0.7 0.7)
					(thickness 0.15)
				)
				(justify right top mirror)
			)
		)
		(pad "1" smd roundrect
			(at -0.48 0 90)
			(size 0.59 0.64)
			(layers "B.Cu" "B.Mask" "B.Paste")
			(roundrect_rratio 0.25)
			(net 811 "/USB Debug, PD/MOSI")
			(pintype "passive")
		)
		(pad "2" smd roundrect
			(at 0.48 0 90)
			(size 0.59 0.64)
			(layers "B.Cu" "B.Mask" "B.Paste")
			(roundrect_rratio 0.25)
			(net 940 "/USB Debug, PD/PDC_MOSI")
			(pintype "passive")
		)
	)
	(footprint "antmicro-footprints:TP_SMD_0.75mm"
		(layer "B.Cu")
		(at 199 73.6 180)
		(property "Reference" "TP92"
			(at -1.3 0.6 0)
			(layer "B.SilkS")
			(effects
				(font
					(size 0.7 0.7)
					(thickness 0.15)
				)
				(justify left bottom mirror)
			)
		)
		(property "Value" "TP_0.75mm_SMD"
			(at 0 -1.2 0)
			(layer "B.Fab")
			(effects
				(font
					(size 0.7 0.7)
					(thickness 0.15)
				)
				(justify left bottom mirror)
			)
		)
		(property "Description" "SMT test point"
			(at 0 0 0)
			(layer "B.Fab")
			(hide yes)
			(effects
				(font
					(size 1.27 1.27)
					(thickness 0.15)
				)
				(justify mirror)
			)
		)
		(property "MPN" ""
			(at 0 0 0)
			(unlocked yes)
			(layer "B.Fab")
			(hide yes)
			(effects
				(font
					(size 1 1)
					(thickness 0.15)
				)
				(justify mirror)
			)
		)
		(property "Manufacturer" ""
			(at 0 0 0)
			(unlocked yes)
			(layer "B.Fab")
			(hide yes)
			(effects
				(font
					(size 1 1)
					(thickness 0.15)
				)
				(justify mirror)
			)
		)
		(property "Author" "Antmicro"
			(at 0 0 0)
			(unlocked yes)
			(layer "B.Fab")
			(hide yes)
			(effects
				(font
					(size 1 1)
					(thickness 0.15)
				)
				(justify mirror)
			)
		)
		(property "License" "Apache-2.0"
			(at 0 0 0)
			(unlocked yes)
			(layer "B.Fab")
			(hide yes)
			(effects
				(font
					(size 1 1)
					(thickness 0.15)
				)
				(justify mirror)
			)
		)
		(sheetname "/USB Debug, PD/")
		(sheetfile "usb_debug_pd.kicad_sch")
		(attr exclude_from_pos_files exclude_from_bom)
		(fp_circle
			(center 0 0)
			(end 0.475 0)
			(stroke
				(width 0.05)
				(type default)
			)
			(fill no)
			(layer "B.CrtYd")
		)
		(fp_text user "Author: Antmicro"
			(at -0.4 -3.901 0)
			(layer "B.Fab")
			(effects
				(font
					(size 0.7 0.7)
					(thickness 0.15)
				)
				(justify left bottom mirror)
			)
		)
		(fp_text user "License: Apache-2.0"
			(at -0.4 -5.101 0)
			(layer "B.Fab")
			(effects
				(font
					(size 0.7 0.7)
					(thickness 0.15)
				)
				(justify left bottom mirror)
			)
		)
		(fp_text user "${REFERENCE}"
			(at -0.4 -2.7 0)
			(layer "B.Fab")
			(effects
				(font
					(size 0.7 0.7)
					(thickness 0.15)
				)
				(justify left bottom mirror)
			)
		)
		(pad "1" smd circle
			(at 0 0 180)
			(size 0.75 0.75)
			(layers "B.Cu" "B.Mask")
			(net 945 "/USB Debug, PD/DEBUG_SCL")
			(pinfunction "1")
			(pintype "passive")
		)
	)
	(footprint "antmicro-footprints:TP_SMD_0.75mm"
		(layer "B.Cu")
		(at 141.3 76.65 90)
		(property "Reference" "TP8"
			(at -0.98 -1.42 90)
			(layer "B.SilkS")
			(effects
				(font
					(size 0.7 0.7)
					(thickness 0.15)
				)
				(justify right top mirror)
			)
		)
		(property "Value" "TP_0.75mm_SMD"
			(at 0 -1.2 90)
			(layer "B.Fab")
			(effects
				(font
					(size 0.7 0.7)
					(thickness 0.15)
				)
				(justify right top mirror)
			)
		)
		(property "Description" "SMT test point"
			(at 0 0 90)
			(layer "B.Fab")
			(hide yes)
			(effects
				(font
					(size 1.27 1.27)
					(thickness 0.15)
				)
				(justify mirror)
			)
		)
		(property "MPN" ""
			(at 0 0 270)
			(unlocked yes)
			(layer "B.Fab")
			(hide yes)
			(effects
				(font
					(size 1 1)
					(thickness 0.15)
				)
				(justify mirror)
			)
		)
		(property "Manufacturer" ""
			(at 0 0 270)
			(unlocked yes)
			(layer "B.Fab")
			(hide yes)
			(effects
				(font
					(size 1 1)
					(thickness 0.15)
				)
				(justify mirror)
			)
		)
		(property "Author" "Antmicro"
			(at 0 0 270)
			(unlocked yes)
			(layer "B.Fab")
			(hide yes)
			(effects
				(font
					(size 1 1)
					(thickness 0.15)
				)
				(justify mirror)
			)
		)
		(property "License" "Apache-2.0"
			(at 0 0 270)
			(unlocked yes)
			(layer "B.Fab")
			(hide yes)
			(effects
				(font
					(size 1 1)
					(thickness 0.15)
				)
				(justify mirror)
			)
		)
		(sheetname "/SoM_Power/")
		(sheetfile "som_power.kicad_sch")
		(attr exclude_from_pos_files exclude_from_bom)
		(fp_circle
			(center 0 0)
			(end 0.475 0)
			(stroke
				(width 0.05)
				(type default)
			)
			(fill no)
			(layer "B.CrtYd")
		)
		(fp_text user "${REFERENCE}"
			(at -0.4 -2.7 90)
			(layer "B.Fab")
			(effects
				(font
					(size 0.7 0.7)
					(thickness 0.15)
				)
				(justify right top mirror)
			)
		)
		(fp_text user "Author: Antmicro"
			(at -0.4 -3.901 90)
			(layer "B.Fab")
			(effects
				(font
					(size 0.7 0.7)
					(thickness 0.15)
				)
				(justify right top mirror)
			)
		)
		(fp_text user "License: Apache-2.0"
			(at -0.4 -5.101 90)
			(layer "B.Fab")
			(effects
				(font
					(size 0.7 0.7)
					(thickness 0.15)
				)
				(justify right top mirror)
			)
		)
		(pad "1" smd circle
			(at 0 0 90)
			(size 0.75 0.75)
			(layers "B.Cu" "B.Mask")
			(net 673 "Net-(J1A-THERM_SHDN_REQ_N)")
			(pinfunction "1")
			(pintype "passive")
		)
	)
	(footprint "antmicro-footprints:Mech_M2_2280_H2.5mm"
		(layer "B.Cu")
		(at 197.665 104.6405 90)
		(property "Reference" "A1"
			(at 0 -8.89 90)
			(layer "B.SilkS")
			(hide yes)
			(effects
				(font
					(size 0.7 0.7)
					(thickness 0.15)
				)
				(justify left bottom mirror)
			)
		)
		(property "Value" "Mech_M2_2280_H2.5mm"
			(at 0 -6.857 90)
			(layer "B.Fab")
			(effects
				(font
					(size 0.7 0.7)
					(thickness 0.15)
				)
				(justify left bottom mirror)
			)
		)
		(property "Description" "Mechanical model for M2 2280 2.5mm module"
			(at 0 0 90)
			(layer "B.Fab")
			(hide yes)
			(effects
				(font
					(size 1.27 1.27)
					(thickness 0.15)
				)
				(justify mirror)
			)
		)
		(property "Manufacturer" ""
			(at 0 0 270)
			(unlocked yes)
			(layer "B.Fab")
			(hide yes)
			(effects
				(font
					(size 1 1)
					(thickness 0.15)
				)
				(justify mirror)
			)
		)
		(property "MPN" ""
			(at 0 0 270)
			(unlocked yes)
			(layer "B.Fab")
			(hide yes)
			(effects
				(font
					(size 1 1)
					(thickness 0.15)
				)
				(justify mirror)
			)
		)
		(property "Author" "Antmicro"
			(at 0 0 270)
			(unlocked yes)
			(layer "B.Fab")
			(hide yes)
			(effects
				(font
					(size 1 1)
					(thickness 0.15)
				)
				(justify mirror)
			)
		)
		(property "License" "Apache-2.0"
			(at 0 0 270)
			(unlocked yes)
			(layer "B.Fab")
			(hide yes)
			(effects
				(font
					(size 1 1)
					(thickness 0.15)
				)
				(justify mirror)
			)
		)
		(sheetname "/M.2/")
		(sheetfile "m2.kicad_sch")
		(attr exclude_from_pos_files exclude_from_bom allow_missing_courtyard dnp)
		(fp_rect
			(start -10.922 -0.0508)
			(end 11.0236 -80.0608)
			(stroke
				(width 0.15)
				(type solid)
			)
			(fill no)
			(layer "B.Fab")
		)
		(fp_text user "Author: Antmicro"
			(at -12.2428 -83.1912 90)
			(layer "B.Fab")
			(effects
				(font
					(size 0.7 0.7)
					(thickness 0.15)
				)
				(justify right top mirror)
			)
		)
		(fp_text user "License: Apache-2.0"
			(at -12.2428 -84.3922 90)
			(layer "B.Fab")
			(effects
				(font
					(size 0.7 0.7)
					(thickness 0.15)
				)
				(justify right top mirror)
			)
		)
		(fp_text user "${REFERENCE}"
			(at -12.2428 -81.9912 90)
			(layer "B.Fab")
			(effects
				(font
					(size 0.7 0.7)
					(thickness 0.15)
				)
				(justify right top mirror)
			)
		)
	)
	(footprint "antmicro-footprints:R_0402_1005Metric"
		(layer "B.Cu")
		(at 124.6 133.925)
		(descr "Resistor SMD 0402")
		(tags "resistor SMD 0402")
		(property "Reference" "R226"
			(at -1.2 -5.55 0)
			(layer "B.SilkS")
			(effects
				(font
					(size 0.7 0.7)
					(thickness 0.15)
				)
				(justify right top mirror)
			)
		)
		(property "Value" "R_0R_0402"
			(at -1.011843 -1.772046 0)
			(layer "B.Fab")
			(effects
				(font
					(size 0.7 0.7)
					(thickness 0.15)
				)
				(justify right top mirror)
			)
		)
		(property "Datasheet" "https://industrial.panasonic.com/cdbs/www-data/pdf/RDA0000/AOA0000C301.pdf"
			(at 0 0 0)
			(layer "B.Fab")
			(hide yes)
			(effects
				(font
					(size 1.27 1.27)
					(thickness 0.15)
				)
				(justify mirror)
			)
		)
		(property "Description" "SMD Chip Resistor, Jumper, 0 ohm, 100 mW, 0402 [1005 Metric], Thick Film, General Purpose"
			(at 0 0 0)
			(layer "B.Fab")
			(hide yes)
			(effects
				(font
					(size 1.27 1.27)
					(thickness 0.15)
				)
				(justify mirror)
			)
		)
		(property "Manufacturer" "Panasonic"
			(at 0 0 180)
			(unlocked yes)
			(layer "B.Fab")
			(hide yes)
			(effects
				(font
					(size 1 1)
					(thickness 0.15)
				)
				(justify mirror)
			)
		)
		(property "MPN" "ERJ2GE0R00X"
			(at 0 0 180)
			(unlocked yes)
			(layer "B.Fab")
			(hide yes)
			(effects
				(font
					(size 1 1)
					(thickness 0.15)
				)
				(justify mirror)
			)
		)
		(property "Val" "0R"
			(at 0 0 180)
			(unlocked yes)
			(layer "B.Fab")
			(hide yes)
			(effects
				(font
					(size 1 1)
					(thickness 0.15)
				)
				(justify mirror)
			)
		)
		(property "License" "Apache-2.0"
			(at 0 0 180)
			(unlocked yes)
			(layer "B.Fab")
			(hide yes)
			(effects
				(font
					(size 1 1)
					(thickness 0.15)
				)
				(justify mirror)
			)
		)
		(property "Author" "Antmicro"
			(at 0 0 180)
			(unlocked yes)
			(layer "B.Fab")
			(hide yes)
			(effects
				(font
					(size 1 1)
					(thickness 0.15)
				)
				(justify mirror)
			)
		)
		(property "Tolerance" "~"
			(at 0 0 180)
			(unlocked yes)
			(layer "B.Fab")
			(hide yes)
			(effects
				(font
					(size 1 1)
					(thickness 0.15)
				)
				(justify mirror)
			)
		)
		(property "Current" "1A"
			(at 0 0 0)
			(unlocked yes)
			(layer "B.Fab")
			(hide yes)
			(effects
				(font
					(size 1 1)
					(thickness 0.15)
				)
				(justify mirror)
			)
		)
		(property "Public" "False"
			(at 0 0 0)
			(unlocked yes)
			(layer "B.Fab")
			(hide yes)
			(effects
				(font
					(size 1 1)
					(thickness 0.15)
				)
				(justify mirror)
			)
		)
		(sheetname "/M.2/")
		(sheetfile "m2.kicad_sch")
		(attr smd)
		(fp_poly
			(pts
				(xy -0.925 0.47) (xy 0.925 0.47) (xy 0.925 -0.47) (xy -0.925 -0.47)
			)
			(stroke
				(width 0.05)
				(type default)
			)
			(fill no)
			(layer "B.CrtYd")
		)
		(fp_poly
			(pts
				(xy -0.5 0.25) (xy 0.5 0.25) (xy 0.5 -0.25) (xy -0.5 -0.25)
			)
			(stroke
				(width 0.15)
				(type solid)
			)
			(fill no)
			(layer "B.Fab")
		)
		(fp_text user "Author: Antmicro"
			(at -0.95 -4.169 0)
			(layer "B.Fab")
			(effects
				(font
					(size 0.7 0.7)
					(thickness 0.15)
				)
				(justify right top mirror)
			)
		)
		(fp_text user "${REFERENCE}"
			(at -0.95 -3.168 0)
			(layer "B.Fab")
			(effects
				(font
					(size 0.7 0.7)
					(thickness 0.15)
				)
				(justify right top mirror)
			)
		)
		(fp_text user "License: Apache-2.0"
			(at -0.949999 -5.169 0)
			(layer "B.Fab")
			(effects
				(font
					(size 0.7 0.7)
					(thickness 0.15)
				)
				(justify right top mirror)
			)
		)
		(pad "1" smd roundrect
			(at -0.48 0)
			(size 0.59 0.64)
			(layers "B.Cu" "B.Mask" "B.Paste")
			(roundrect_rratio 0.25)
			(net 247 "/M.2/M2_E_W_DIS_2")
			(pintype "passive")
		)
		(pad "2" smd roundrect
			(at 0.48 0)
			(size 0.59 0.64)
			(layers "B.Cu" "B.Mask" "B.Paste")
			(roundrect_rratio 0.25)
			(net 1167 "/M.2/M2_E.W_DIS_2")
			(pintype "passive")
		)
	)
	(footprint "antmicro-footprints:TP_SMD_0.75mm"
		(layer "B.Cu")
		(at 140.45 128.7)
		(property "Reference" "TP86"
			(at -0.85 0.5 180)
			(layer "B.SilkS")
			(effects
				(font
					(size 0.7 0.7)
					(thickness 0.15)
				)
				(justify left bottom mirror)
			)
		)
		(property "Value" "TP_0.75mm_SMD"
			(at 0 -1.2 180)
			(layer "B.Fab")
			(effects
				(font
					(size 0.7 0.7)
					(thickness 0.15)
				)
				(justify left bottom mirror)
			)
		)
		(property "Description" "SMT test point"
			(at 0 0 180)
			(layer "B.Fab")
			(hide yes)
			(effects
				(font
					(size 1.27 1.27)
					(thickness 0.15)
				)
				(justify mirror)
			)
		)
		(property "MPN" ""
			(at 0 0 180)
			(unlocked yes)
			(layer "B.Fab")
			(hide yes)
			(effects
				(font
					(size 1 1)
					(thickness 0.15)
				)
				(justify mirror)
			)
		)
		(property "Manufacturer" ""
			(at 0 0 180)
			(unlocked yes)
			(layer "B.Fab")
			(hide yes)
			(effects
				(font
					(size 1 1)
					(thickness 0.15)
				)
				(justify mirror)
			)
		)
		(property "Author" "Antmicro"
			(at 0 0 180)
			(unlocked yes)
			(layer "B.Fab")
			(hide yes)
			(effects
				(font
					(size 1 1)
					(thickness 0.15)
				)
				(justify mirror)
			)
		)
		(property "License" "Apache-2.0"
			(at 0 0 180)
			(unlocked yes)
			(layer "B.Fab")
			(hide yes)
			(effects
				(font
					(size 1 1)
					(thickness 0.15)
				)
				(justify mirror)
			)
		)
		(sheetname "/SoM_Power/")
		(sheetfile "som_power.kicad_sch")
		(attr exclude_from_pos_files exclude_from_bom)
		(fp_circle
			(center 0 0)
			(end 0.475 0)
			(stroke
				(width 0.05)
				(type default)
			)
			(fill no)
			(layer "B.CrtYd")
		)
		(fp_text user "Author: Antmicro"
			(at -0.4 -3.901 180)
			(layer "B.Fab")
			(effects
				(font
					(size 0.7 0.7)
					(thickness 0.15)
				)
				(justify left bottom mirror)
			)
		)
		(fp_text user "License: Apache-2.0"
			(at -0.4 -5.101 180)
			(layer "B.Fab")
			(effects
				(font
					(size 0.7 0.7)
					(thickness 0.15)
				)
				(justify left bottom mirror)
			)
		)
		(fp_text user "${REFERENCE}"
			(at -0.4 -2.7 180)
			(layer "B.Fab")
			(effects
				(font
					(size 0.7 0.7)
					(thickness 0.15)
				)
				(justify left bottom mirror)
			)
		)
		(pad "1" smd circle
			(at 0 0)
			(size 0.75 0.75)
			(layers "B.Cu" "B.Mask")
			(net 1293 "/DCDC/CARRIER_PWR_ON")
			(pinfunction "1")
			(pintype "passive")
		)
	)
	(footprint "antmicro-footprints:C_0402_1005Metric"
		(layer "B.Cu")
		(at 123.79 70.68 180)
		(descr "Capacitor SMD 0402")
		(tags "capacitor SMD 0402")
		(property "Reference" "C25"
			(at -3.06 -0.39 0)
			(layer "B.SilkS")
			(effects
				(font
					(size 0.7 0.7)
					(thickness 0.15)
				)
				(justify left bottom mirror)
			)
		)
		(property "Value" "C_10u_0402"
			(at -1.022927 -2.155213 0)
			(layer "B.Fab")
			(effects
				(font
					(size 0.7 0.7)
					(thickness 0.15)
				)
				(justify left bottom mirror)
			)
		)
		(property "Datasheet" "https://www.yageo.com/en/Chart/Download/pdf/CC0402MRX5R5BB106"
			(at 0 0 0)
			(layer "B.Fab")
			(hide yes)
			(effects
				(font
					(size 1.27 1.27)
					(thickness 0.15)
				)
				(justify mirror)
			)
		)
		(property "Description" "SMD Multilayer Ceramic Capacitor, 10 µF, 6.3 V, 0402 [1005 Metric], ± 20%, X5R, CC Series"
			(at 0 0 0)
			(layer "B.Fab")
			(hide yes)
			(effects
				(font
					(size 1.27 1.27)
					(thickness 0.15)
				)
				(justify mirror)
			)
		)
		(property "MPN" "CC0402MRX5R5BB106"
			(at 0 0 180)
			(unlocked yes)
			(layer "B.Fab")
			(hide yes)
			(effects
				(font
					(size 1 1)
					(thickness 0.15)
				)
				(justify mirror)
			)
		)
		(property "Manufacturer" "YAGEO"
			(at 0 0 180)
			(unlocked yes)
			(layer "B.Fab")
			(hide yes)
			(effects
				(font
					(size 1 1)
					(thickness 0.15)
				)
				(justify mirror)
			)
		)
		(property "License" "Apache-2.0"
			(at 0 0 180)
			(unlocked yes)
			(layer "B.Fab")
			(hide yes)
			(effects
				(font
					(size 1 1)
					(thickness 0.15)
				)
				(justify mirror)
			)
		)
		(property "Author" "Antmicro"
			(at 0 0 180)
			(unlocked yes)
			(layer "B.Fab")
			(hide yes)
			(effects
				(font
					(size 1 1)
					(thickness 0.15)
				)
				(justify mirror)
			)
		)
		(property "Val" "10u"
			(at 0 0 180)
			(unlocked yes)
			(layer "B.Fab")
			(hide yes)
			(effects
				(font
					(size 1 1)
					(thickness 0.15)
				)
				(justify mirror)
			)
		)
		(property "Voltage" ""
			(at 0 0 180)
			(unlocked yes)
			(layer "B.Fab")
			(hide yes)
			(effects
				(font
					(size 1 1)
					(thickness 0.15)
				)
				(justify mirror)
			)
		)
		(property "Dielectric" "template_dielectric"
			(at 0 0 180)
			(unlocked yes)
			(layer "B.Fab")
			(hide yes)
			(effects
				(font
					(size 1 1)
					(thickness 0.15)
				)
				(justify mirror)
			)
		)
		(sheetname "/SoM_Power/")
		(sheetfile "som_power.kicad_sch")
		(attr smd)
		(fp_rect
			(start -0.925 0.47)
			(end 0.925 -0.47)
			(stroke
				(width 0.05)
				(type default)
			)
			(fill no)
			(layer "B.CrtYd")
		)
		(fp_line
			(start 0.504 0.25)
			(end 0.504 -0.248)
			(stroke
				(width 0.15)
				(type solid)
			)
			(layer "B.Fab")
		)
		(fp_line
			(start 0.504 -0.248)
			(end -0.494 -0.248)
			(stroke
				(width 0.15)
				(type solid)
			)
			(layer "B.Fab")
		)
		(fp_line
			(start -0.494 0.25)
			(end 0.504 0.25)
			(stroke
				(width 0.15)
				(type solid)
			)
			(layer "B.Fab")
		)
		(fp_line
			(start -0.494 -0.248)
			(end -0.494 0.25)
			(stroke
				(width 0.15)
				(type solid)
			)
			(layer "B.Fab")
		)
		(fp_text user "${REFERENCE}"
			(at -0.939 -4.599 0)
			(layer "B.Fab")
			(effects
				(font
					(size 0.7 0.7)
					(thickness 0.15)
				)
				(justify left bottom mirror)
			)
		)
		(fp_text user "License: Apache-2.0"
			(at -0.939 -5.799 0)
			(layer "B.Fab")
			(effects
				(font
					(size 0.7 0.7)
					(thickness 0.15)
				)
				(justify left bottom mirror)
			)
		)
		(fp_text user "Author: Antmicro"
			(at -0.939 -3.399 0)
			(layer "B.Fab")
			(effects
				(font
					(size 0.7 0.7)
					(thickness 0.15)
				)
				(justify left bottom mirror)
			)
		)
		(pad "1" smd roundrect
			(at -0.48 0 180)
			(size 0.59 0.64)
			(layers "B.Cu" "B.Mask" "B.Paste")
			(roundrect_rratio 0.25)
			(net 1 "GND")
			(pintype "passive")
		)
		(pad "2" smd roundrect
			(at 0.48 0 180)
			(size 0.59 0.64)
			(layers "B.Cu" "B.Mask" "B.Paste")
			(roundrect_rratio 0.25)
			(net 213 "+5V_SOM")
			(pintype "passive")
		)
	)
	(footprint "antmicro-footprints:C_0402_1005Metric"
		(layer "B.Cu")
		(at 205.226 150.6 180)
		(descr "Capacitor SMD 0402")
		(tags "capacitor SMD 0402")
		(property "Reference" "C173"
			(at -1.14 0.699 0)
			(layer "B.SilkS")
			(effects
				(font
					(size 0.7 0.7)
					(thickness 0.15)
				)
				(justify left bottom mirror)
			)
		)
		(property "Value" "C_100n_0402"
			(at -1.022927 -2.155213 0)
			(layer "B.Fab")
			(effects
				(font
					(size 0.7 0.7)
					(thickness 0.15)
				)
				(justify left bottom mirror)
			)
		)
		(property "Datasheet" "https://www.murata.com/products/productdetail?partno=GRM155R61H104KE14%23"
			(at 0 0 0)
			(layer "B.Fab")
			(hide yes)
			(effects
				(font
					(size 1.27 1.27)
					(thickness 0.15)
				)
				(justify mirror)
			)
		)
		(property "Description" "SMD Multilayer Ceramic Capacitor, 0.1 µF, 50 V, 0402 [1005 Metric], ± 10%, X5R, GRM Series"
			(at 0 0 0)
			(layer "B.Fab")
			(hide yes)
			(effects
				(font
					(size 1.27 1.27)
					(thickness 0.15)
				)
				(justify mirror)
			)
		)
		(property "MPN" "GRM155R61H104KE14D"
			(at 0 0 0)
			(unlocked yes)
			(layer "B.Fab")
			(hide yes)
			(effects
				(font
					(size 1 1)
					(thickness 0.15)
				)
				(justify mirror)
			)
		)
		(property "Manufacturer" "Murata"
			(at 0 0 0)
			(unlocked yes)
			(layer "B.Fab")
			(hide yes)
			(effects
				(font
					(size 1 1)
					(thickness 0.15)
				)
				(justify mirror)
			)
		)
		(property "License" "Apache-2.0"
			(at 0 0 0)
			(unlocked yes)
			(layer "B.Fab")
			(hide yes)
			(effects
				(font
					(size 1 1)
					(thickness 0.15)
				)
				(justify mirror)
			)
		)
		(property "Author" "Antmicro"
			(at 0 0 0)
			(unlocked yes)
			(layer "B.Fab")
			(hide yes)
			(effects
				(font
					(size 1 1)
					(thickness 0.15)
				)
				(justify mirror)
			)
		)
		(property "Val" "100n"
			(at 0 0 0)
			(unlocked yes)
			(layer "B.Fab")
			(hide yes)
			(effects
				(font
					(size 1 1)
					(thickness 0.15)
				)
				(justify mirror)
			)
		)
		(property "Voltage" "50V"
			(at 0 0 0)
			(unlocked yes)
			(layer "B.Fab")
			(hide yes)
			(effects
				(font
					(size 1 1)
					(thickness 0.15)
				)
				(justify mirror)
			)
		)
		(property "Dielectric" "X5R"
			(at 0 0 0)
			(unlocked yes)
			(layer "B.Fab")
			(hide yes)
			(effects
				(font
					(size 1 1)
					(thickness 0.15)
				)
				(justify mirror)
			)
		)
		(sheetname "/SFP/")
		(sheetfile "sfp.kicad_sch")
		(attr smd)
		(fp_rect
			(start -0.925 0.47)
			(end 0.925 -0.47)
			(stroke
				(width 0.05)
				(type default)
			)
			(fill no)
			(layer "B.CrtYd")
		)
		(fp_line
			(start 0.504 0.25)
			(end 0.504 -0.248)
			(stroke
				(width 0.15)
				(type solid)
			)
			(layer "B.Fab")
		)
		(fp_line
			(start 0.504 -0.248)
			(end -0.494 -0.248)
			(stroke
				(width 0.15)
				(type solid)
			)
			(layer "B.Fab")
		)
		(fp_line
			(start -0.494 0.25)
			(end 0.504 0.25)
			(stroke
				(width 0.15)
				(type solid)
			)
			(layer "B.Fab")
		)
		(fp_line
			(start -0.494 -0.248)
			(end -0.494 0.25)
			(stroke
				(width 0.15)
				(type solid)
			)
			(layer "B.Fab")
		)
		(fp_text user "License: Apache-2.0"
			(at -0.939 -5.799 0)
			(layer "B.Fab")
			(effects
				(font
					(size 0.7 0.7)
					(thickness 0.15)
				)
				(justify left bottom mirror)
			)
		)
		(fp_text user "${REFERENCE}"
			(at -0.939 -4.599 0)
			(layer "B.Fab")
			(effects
				(font
					(size 0.7 0.7)
					(thickness 0.15)
				)
				(justify left bottom mirror)
			)
		)
		(fp_text user "Author: Antmicro"
			(at -0.939 -3.399 0)
			(layer "B.Fab")
			(effects
				(font
					(size 0.7 0.7)
					(thickness 0.15)
				)
				(justify left bottom mirror)
			)
		)
		(pad "1" smd roundrect
			(at -0.48 0 180)
			(size 0.59 0.64)
			(layers "B.Cu" "B.Mask" "B.Paste")
			(roundrect_rratio 0.25)
			(net 1 "GND")
			(pintype "passive")
		)
		(pad "2" smd roundrect
			(at 0.48 0 180)
			(size 0.59 0.64)
			(layers "B.Cu" "B.Mask" "B.Paste")
			(roundrect_rratio 0.25)
			(net 379 "/SFP/SH")
			(pintype "passive")
		)
	)
	(footprint "antmicro-footprints:C_0805_2012Metric"
		(layer "B.Cu")
		(at 100.1 132.3 180)
		(descr "Capacitor SMD 0805")
		(tags "capacitor SMD 0805")
		(property "Reference" "C230"
			(at -5.1 -0.5 0)
			(layer "B.SilkS")
			(effects
				(font
					(size 0.7 0.7)
					(thickness 0.15)
				)
				(justify left bottom mirror)
			)
		)
		(property "Value" "C_22u_25V_0805"
			(at -2.055717 -1.963152 0)
			(layer "B.Fab")
			(effects
				(font
					(size 0.7 0.7)
					(thickness 0.15)
				)
				(justify left bottom mirror)
			)
		)
		(property "Datasheet" "https://product.samsungsem.com/mlcc/CL21A226MAYNNN.do"
			(at 0 0 0)
			(layer "B.Fab")
			(hide yes)
			(effects
				(font
					(size 1.27 1.27)
					(thickness 0.15)
				)
				(justify mirror)
			)
		)
		(property "Description" "SMT Multilayer Ceramic Capacitor, 22uF, +/-20%, 25V, X5R, 0805 [2012 Metric]"
			(at 0 0 0)
			(layer "B.Fab")
			(hide yes)
			(effects
				(font
					(size 1.27 1.27)
					(thickness 0.15)
				)
				(justify mirror)
			)
		)
		(property "MPN" "CL21A226MAYNNNE"
			(at 0 0 180)
			(unlocked yes)
			(layer "B.Fab")
			(hide yes)
			(effects
				(font
					(size 1 1)
					(thickness 0.15)
				)
				(justify mirror)
			)
		)
		(property "Val" "22u"
			(at 0 0 180)
			(unlocked yes)
			(layer "B.Fab")
			(hide yes)
			(effects
				(font
					(size 1 1)
					(thickness 0.15)
				)
				(justify mirror)
			)
		)
		(property "Voltage" "25V"
			(at 0 0 180)
			(unlocked yes)
			(layer "B.Fab")
			(hide yes)
			(effects
				(font
					(size 1 1)
					(thickness 0.15)
				)
				(justify mirror)
			)
		)
		(property "Dielectric" "X5R"
			(at 0 0 180)
			(unlocked yes)
			(layer "B.Fab")
			(hide yes)
			(effects
				(font
					(size 1 1)
					(thickness 0.15)
				)
				(justify mirror)
			)
		)
		(property "Manufacturer" "Samsung Electro-Mechanics"
			(at 0 0 180)
			(unlocked yes)
			(layer "B.Fab")
			(hide yes)
			(effects
				(font
					(size 1 1)
					(thickness 0.15)
				)
				(justify mirror)
			)
		)
		(property "License" "Apache-2.0"
			(at 0 0 180)
			(unlocked yes)
			(layer "B.Fab")
			(hide yes)
			(effects
				(font
					(size 1 1)
					(thickness 0.15)
				)
				(justify mirror)
			)
		)
		(property "Author" "Antmicro"
			(at 0 0 180)
			(unlocked yes)
			(layer "B.Fab")
			(hide yes)
			(effects
				(font
					(size 1 1)
					(thickness 0.15)
				)
				(justify mirror)
			)
		)
		(property "Public" "False"
			(at 0 0 180)
			(unlocked yes)
			(layer "B.Fab")
			(hide yes)
			(effects
				(font
					(size 1 1)
					(thickness 0.15)
				)
				(justify mirror)
			)
		)
		(sheetname "/Expansion connector/")
		(sheetfile "expansion_connector.kicad_sch")
		(attr smd)
		(fp_line
			(start -0.3 0.7)
			(end 0.3 0.7)
			(stroke
				(width 0.15)
				(type solid)
			)
			(layer "B.SilkS")
		)
		(fp_line
			(start -0.3 -0.7)
			(end 0.3 -0.7)
			(stroke
				(width 0.15)
				(type solid)
			)
			(layer "B.SilkS")
		)
		(fp_rect
			(start 1.95 0.9)
			(end -1.95 -0.9)
			(stroke
				(width 0.05)
				(type default)
			)
			(fill no)
			(layer "B.CrtYd")
		)
		(fp_rect
			(start -0.95 0.675)
			(end 0.95 -0.675)
			(stroke
				(width 0.15)
				(type solid)
			)
			(fill no)
			(layer "B.Fab")
		)
		(fp_text user "License: Apache-2.0"
			(at -1.9 -4.947 0)
			(layer "B.Fab")
			(effects
				(font
					(size 0.7 0.7)
					(thickness 0.15)
				)
				(justify left bottom mirror)
			)
		)
		(fp_text user "${REFERENCE}"
			(at -1.9 -3.947 0)
			(layer "B.Fab")
			(effects
				(font
					(size 0.7 0.7)
					(thickness 0.15)
				)
				(justify left bottom mirror)
			)
		)
		(fp_text user "Author: Antmicro"
			(at -1.9 -5.947 0)
			(layer "B.Fab")
			(effects
				(font
					(size 0.7 0.7)
					(thickness 0.15)
				)
				(justify left bottom mirror)
			)
		)
		(pad "1" smd roundrect
			(at -1.1 0 180)
			(size 1.2 1.3)
			(layers "B.Cu" "B.Mask" "B.Paste")
			(roundrect_rratio 0.25)
			(net 1 "GND")
			(pintype "passive")
		)
		(pad "2" smd roundrect
			(at 1.1 0 180)
			(size 1.2 1.3)
			(layers "B.Cu" "B.Mask" "B.Paste")
			(roundrect_rratio 0.25)
			(net 307 "/Expansion connector/+5V_FMC")
			(pintype "passive")
		)
	)
	(footprint "antmicro-footprints:TP_SMD_0.75mm"
		(layer "B.Cu")
		(at 91.4 85.1 90)
		(property "Reference" "TP52"
			(at -3.2 -0.5 90)
			(layer "B.SilkS")
			(effects
				(font
					(size 0.7 0.7)
					(thickness 0.15)
				)
				(justify right top mirror)
			)
		)
		(property "Value" "TP_0.75mm_SMD"
			(at 0 -1.2 90)
			(layer "B.Fab")
			(effects
				(font
					(size 0.7 0.7)
					(thickness 0.15)
				)
				(justify right top mirror)
			)
		)
		(property "Description" "SMT test point"
			(at 0 0 90)
			(layer "B.Fab")
			(hide yes)
			(effects
				(font
					(size 1.27 1.27)
					(thickness 0.15)
				)
				(justify mirror)
			)
		)
		(property "MPN" ""
			(at 0 0 270)
			(unlocked yes)
			(layer "B.Fab")
			(hide yes)
			(effects
				(font
					(size 1 1)
					(thickness 0.15)
				)
				(justify mirror)
			)
		)
		(property "Manufacturer" ""
			(at 0 0 270)
			(unlocked yes)
			(layer "B.Fab")
			(hide yes)
			(effects
				(font
					(size 1 1)
					(thickness 0.15)
				)
				(justify mirror)
			)
		)
		(property "Author" "Antmicro"
			(at 0 0 270)
			(unlocked yes)
			(layer "B.Fab")
			(hide yes)
			(effects
				(font
					(size 1 1)
					(thickness 0.15)
				)
				(justify mirror)
			)
		)
		(property "License" "Apache-2.0"
			(at 0 0 270)
			(unlocked yes)
			(layer "B.Fab")
			(hide yes)
			(effects
				(font
					(size 1 1)
					(thickness 0.15)
				)
				(justify mirror)
			)
		)
		(sheetname "/SoM_Power/")
		(sheetfile "som_power.kicad_sch")
		(attr exclude_from_pos_files exclude_from_bom)
		(fp_circle
			(center 0 0)
			(end 0.475 0)
			(stroke
				(width 0.05)
				(type default)
			)
			(fill no)
			(layer "B.CrtYd")
		)
		(fp_text user "License: Apache-2.0"
			(at -0.4 -5.101 90)
			(layer "B.Fab")
			(effects
				(font
					(size 0.7 0.7)
					(thickness 0.15)
				)
				(justify right top mirror)
			)
		)
		(fp_text user "${REFERENCE}"
			(at -0.4 -2.7 90)
			(layer "B.Fab")
			(effects
				(font
					(size 0.7 0.7)
					(thickness 0.15)
				)
				(justify right top mirror)
			)
		)
		(fp_text user "Author: Antmicro"
			(at -0.4 -3.901 90)
			(layer "B.Fab")
			(effects
				(font
					(size 0.7 0.7)
					(thickness 0.15)
				)
				(justify right top mirror)
			)
		)
		(pad "1" smd circle
			(at 0 0 90)
			(size 0.75 0.75)
			(layers "B.Cu" "B.Mask")
			(net 563 "Net-(J1A-UFS0_REF_CLK)")
			(pinfunction "1")
			(pintype "passive")
		)
	)
	(footprint "antmicro-footprints:TP_SMD_0.75mm"
		(layer "B.Cu")
		(at 95.35 70.65 90)
		(property "Reference" "TP54"
			(at -1.435 -1.38 90)
			(layer "B.SilkS")
			(effects
				(font
					(size 0.7 0.7)
					(thickness 0.15)
				)
				(justify right top mirror)
			)
		)
		(property "Value" "TP_0.75mm_SMD"
			(at 0 -1.2 90)
			(layer "B.Fab")
			(effects
				(font
					(size 0.7 0.7)
					(thickness 0.15)
				)
				(justify right top mirror)
			)
		)
		(property "Description" "SMT test point"
			(at 0 0 90)
			(layer "B.Fab")
			(hide yes)
			(effects
				(font
					(size 1.27 1.27)
					(thickness 0.15)
				)
				(justify mirror)
			)
		)
		(property "MPN" ""
			(at 0 0 270)
			(unlocked yes)
			(layer "B.Fab")
			(hide yes)
			(effects
				(font
					(size 1 1)
					(thickness 0.15)
				)
				(justify mirror)
			)
		)
		(property "Manufacturer" ""
			(at 0 0 270)
			(unlocked yes)
			(layer "B.Fab")
			(hide yes)
			(effects
				(font
					(size 1 1)
					(thickness 0.15)
				)
				(justify mirror)
			)
		)
		(property "Author" "Antmicro"
			(at 0 0 270)
			(unlocked yes)
			(layer "B.Fab")
			(hide yes)
			(effects
				(font
					(size 1 1)
					(thickness 0.15)
				)
				(justify mirror)
			)
		)
		(property "License" "Apache-2.0"
			(at 0 0 270)
			(unlocked yes)
			(layer "B.Fab")
			(hide yes)
			(effects
				(font
					(size 1 1)
					(thickness 0.15)
				)
				(justify mirror)
			)
		)
		(sheetname "/SoM_Power/")
		(sheetfile "som_power.kicad_sch")
		(attr exclude_from_pos_files exclude_from_bom)
		(fp_circle
			(center 0 0)
			(end 0.475 0)
			(stroke
				(width 0.05)
				(type default)
			)
			(fill no)
			(layer "B.CrtYd")
		)
		(fp_text user "Author: Antmicro"
			(at -0.4 -3.901 90)
			(layer "B.Fab")
			(effects
				(font
					(size 0.7 0.7)
					(thickness 0.15)
				)
				(justify right top mirror)
			)
		)
		(fp_text user "${REFERENCE}"
			(at -0.4 -2.7 90)
			(layer "B.Fab")
			(effects
				(font
					(size 0.7 0.7)
					(thickness 0.15)
				)
				(justify right top mirror)
			)
		)
		(fp_text user "License: Apache-2.0"
			(at -0.4 -5.101 90)
			(layer "B.Fab")
			(effects
				(font
					(size 0.7 0.7)
					(thickness 0.15)
				)
				(justify right top mirror)
			)
		)
		(pad "1" smd circle
			(at 0 0 90)
			(size 0.75 0.75)
			(layers "B.Cu" "B.Mask")
			(net 793 "/SoM_Power/~{SLEEP_REQ}")
			(pinfunction "1")
			(pintype "passive")
		)
	)
	(footprint "antmicro-footprints:R_0402_1005Metric"
		(layer "B.Cu")
		(at 95 55.5 -90)
		(descr "Resistor SMD 0402")
		(tags "resistor SMD 0402")
		(property "Reference" "R307"
			(at 1 -0.5 90)
			(layer "B.SilkS")
			(effects
				(font
					(size 0.7 0.7)
					(thickness 0.15)
				)
				(justify left bottom mirror)
			)
		)
		(property "Value" "R_10k_0402"
			(at -1.011843 -1.772046 90)
			(layer "B.Fab")
			(effects
				(font
					(size 0.7 0.7)
					(thickness 0.15)
				)
				(justify left bottom mirror)
			)
		)
		(property "Datasheet" "https://www.bourns.com/docs/product-datasheets/cr.pdf"
			(at 0 0 90)
			(layer "B.Fab")
			(hide yes)
			(effects
				(font
					(size 1.27 1.27)
					(thickness 0.15)
				)
				(justify mirror)
			)
		)
		(property "Description" "SMD Chip Resistor, 10 kohm, ± 1%, 62.5 mW, 0402 [1005 Metric], Thick Film, General Purpose"
			(at 0 0 90)
			(layer "B.Fab")
			(hide yes)
			(effects
				(font
					(size 1.27 1.27)
					(thickness 0.15)
				)
				(justify mirror)
			)
		)
		(property "MPN" "CR0402-FX-1002GLF"
			(at 0 0 90)
			(unlocked yes)
			(layer "B.Fab")
			(hide yes)
			(effects
				(font
					(size 1 1)
					(thickness 0.15)
				)
				(justify mirror)
			)
		)
		(property "Manufacturer" "Bourns"
			(at 0 0 90)
			(unlocked yes)
			(layer "B.Fab")
			(hide yes)
			(effects
				(font
					(size 1 1)
					(thickness 0.15)
				)
				(justify mirror)
			)
		)
		(property "License" "Apache-2.0"
			(at 0 0 90)
			(unlocked yes)
			(layer "B.Fab")
			(hide yes)
			(effects
				(font
					(size 1 1)
					(thickness 0.15)
				)
				(justify mirror)
			)
		)
		(property "Author" "Antmicro"
			(at 0 0 90)
			(unlocked yes)
			(layer "B.Fab")
			(hide yes)
			(effects
				(font
					(size 1 1)
					(thickness 0.15)
				)
				(justify mirror)
			)
		)
		(property "Val" "10k"
			(at 0 0 90)
			(unlocked yes)
			(layer "B.Fab")
			(hide yes)
			(effects
				(font
					(size 1 1)
					(thickness 0.15)
				)
				(justify mirror)
			)
		)
		(property "Tolerance" "1%"
			(at 0 0 90)
			(unlocked yes)
			(layer "B.Fab")
			(hide yes)
			(effects
				(font
					(size 1 1)
					(thickness 0.15)
				)
				(justify mirror)
			)
		)
		(sheetname "/SoM_Power/")
		(sheetfile "som_power.kicad_sch")
		(attr smd)
		(fp_poly
			(pts
				(xy -0.925 0.47) (xy 0.925 0.47) (xy 0.925 -0.47) (xy -0.925 -0.47)
			)
			(stroke
				(width 0.05)
				(type default)
			)
			(fill no)
			(layer "B.CrtYd")
		)
		(fp_poly
			(pts
				(xy -0.5 0.25) (xy 0.5 0.25) (xy 0.5 -0.25) (xy -0.5 -0.25)
			)
			(stroke
				(width 0.15)
				(type solid)
			)
			(fill no)
			(layer "B.Fab")
		)
		(fp_text user "${REFERENCE}"
			(at -0.95 -3.168 90)
			(layer "B.Fab")
			(effects
				(font
					(size 0.7 0.7)
					(thickness 0.15)
				)
				(justify left bottom mirror)
			)
		)
		(fp_text user "License: Apache-2.0"
			(at -0.949999 -5.169 90)
			(layer "B.Fab")
			(effects
				(font
					(size 0.7 0.7)
					(thickness 0.15)
				)
				(justify left bottom mirror)
			)
		)
		(fp_text user "Author: Antmicro"
			(at -0.95 -4.169 90)
			(layer "B.Fab")
			(effects
				(font
					(size 0.7 0.7)
					(thickness 0.15)
				)
				(justify left bottom mirror)
			)
		)
		(pad "1" smd roundrect
			(at -0.48 0 270)
			(size 0.59 0.64)
			(layers "B.Cu" "B.Mask" "B.Paste")
			(roundrect_rratio 0.25)
			(net 1 "GND")
			(pintype "passive")
		)
		(pad "2" smd roundrect
			(at 0.48 0 270)
			(size 0.59 0.64)
			(layers "B.Cu" "B.Mask" "B.Paste")
			(roundrect_rratio 0.25)
			(net 1036 "Net-(R307-Pad2)")
			(pintype "passive")
		)
	)
	(footprint "antmicro-footprints:R_0402_1005Metric"
		(layer "B.Cu")
		(at 64.1 70.4 90)
		(descr "Resistor SMD 0402")
		(tags "resistor SMD 0402")
		(property "Reference" "R399"
			(at -2.2 3.7 90)
			(layer "B.SilkS")
			(effects
				(font
					(size 0.7 0.7)
					(thickness 0.15)
				)
				(justify right top mirror)
			)
		)
		(property "Value" "R_0R_0402"
			(at -1.011843 -1.772047 90)
			(layer "B.Fab")
			(effects
				(font
					(size 0.7 0.7)
					(thickness 0.15)
				)
				(justify right top mirror)
			)
		)
		(property "Datasheet" "https://industrial.panasonic.com/cdbs/www-data/pdf/RDA0000/AOA0000C301.pdf"
			(at 0 0 90)
			(layer "B.Fab")
			(hide yes)
			(effects
				(font
					(size 1.27 1.27)
					(thickness 0.15)
				)
				(justify mirror)
			)
		)
		(property "Description" "SMD Chip Resistor, Jumper, 0 ohm, 100 mW, 0402 [1005 Metric], Thick Film, General Purpose"
			(at 0 0 90)
			(layer "B.Fab")
			(hide yes)
			(effects
				(font
					(size 1.27 1.27)
					(thickness 0.15)
				)
				(justify mirror)
			)
		)
		(property "MPN" "ERJ2GE0R00X"
			(at 0 0 270)
			(unlocked yes)
			(layer "B.Fab")
			(hide yes)
			(effects
				(font
					(size 1 1)
					(thickness 0.15)
				)
				(justify mirror)
			)
		)
		(property "Manufacturer" "Panasonic"
			(at 0 0 270)
			(unlocked yes)
			(layer "B.Fab")
			(hide yes)
			(effects
				(font
					(size 1 1)
					(thickness 0.15)
				)
				(justify mirror)
			)
		)
		(property "License" "Apache-2.0"
			(at 0 0 270)
			(unlocked yes)
			(layer "B.Fab")
			(hide yes)
			(effects
				(font
					(size 1 1)
					(thickness 0.15)
				)
				(justify mirror)
			)
		)
		(property "Author" "Antmicro"
			(at 0 0 270)
			(unlocked yes)
			(layer "B.Fab")
			(hide yes)
			(effects
				(font
					(size 1 1)
					(thickness 0.15)
				)
				(justify mirror)
			)
		)
		(property "Val" "0R"
			(at 0 0 270)
			(unlocked yes)
			(layer "B.Fab")
			(hide yes)
			(effects
				(font
					(size 1 1)
					(thickness 0.15)
				)
				(justify mirror)
			)
		)
		(property "Tolerance" "~"
			(at 0 0 270)
			(unlocked yes)
			(layer "B.Fab")
			(hide yes)
			(effects
				(font
					(size 1 1)
					(thickness 0.15)
				)
				(justify mirror)
			)
		)
		(property "Current" "1A"
			(at 0 0 270)
			(unlocked yes)
			(layer "B.Fab")
			(hide yes)
			(effects
				(font
					(size 1 1)
					(thickness 0.15)
				)
				(justify mirror)
			)
		)
		(sheetname "/CSI/")
		(sheetfile "csi.kicad_sch")
		(attr smd)
		(fp_rect
			(start -0.925 0.47)
			(end 0.925 -0.47)
			(stroke
				(width 0.05)
				(type default)
			)
			(fill no)
			(layer "B.CrtYd")
		)
		(fp_rect
			(start -0.5 0.25)
			(end 0.5 -0.25)
			(stroke
				(width 0.15)
				(type solid)
			)
			(fill no)
			(layer "B.Fab")
		)
		(fp_text user "License: Apache-2.0"
			(at -0.95 -5.169 90)
			(layer "B.Fab")
			(effects
				(font
					(size 0.7 0.7)
					(thickness 0.15)
				)
				(justify right top mirror)
			)
		)
		(fp_text user "${REFERENCE}"
			(at -0.95 -3.168 90)
			(layer "B.Fab")
			(effects
				(font
					(size 0.7 0.7)
					(thickness 0.15)
				)
				(justify right top mirror)
			)
		)
		(fp_text user "Author: Antmicro"
			(at -0.95 -4.169 90)
			(layer "B.Fab")
			(effects
				(font
					(size 0.7 0.7)
					(thickness 0.15)
				)
				(justify right top mirror)
			)
		)
		(pad "1" smd roundrect
			(at -0.48 0 90)
			(size 0.59 0.64)
			(layers "B.Cu" "B.Mask" "B.Paste")
			(roundrect_rratio 0.25)
			(net 1376 "Net-(J11-Pad41)")
			(pintype "passive")
		)
		(pad "2" smd roundrect
			(at 0.48 0 90)
			(size 0.59 0.64)
			(layers "B.Cu" "B.Mask" "B.Paste")
			(roundrect_rratio 0.25)
			(net 986 "/CSI/SDA_CAM1")
			(pintype "passive")
		)
	)
	(footprint "antmicro-footprints:TP_SMD_0.75mm"
		(layer "B.Cu")
		(at 156.7 140.7 -90)
		(property "Reference" "TP89"
			(at 0.5 -0.5 90)
			(layer "B.SilkS")
			(effects
				(font
					(size 0.7 0.7)
					(thickness 0.15)
				)
				(justify left bottom mirror)
			)
		)
		(property "Value" "TP_0.75mm_SMD"
			(at 0 -1.2 90)
			(layer "B.Fab")
			(effects
				(font
					(size 0.7 0.7)
					(thickness 0.15)
				)
				(justify left bottom mirror)
			)
		)
		(property "Description" "SMT test point"
			(at 0 0 90)
			(layer "B.Fab")
			(hide yes)
			(effects
				(font
					(size 1.27 1.27)
					(thickness 0.15)
				)
				(justify mirror)
			)
		)
		(property "MPN" ""
			(at 0 0 90)
			(unlocked yes)
			(layer "B.Fab")
			(hide yes)
			(effects
				(font
					(size 1 1)
					(thickness 0.15)
				)
				(justify mirror)
			)
		)
		(property "Manufacturer" ""
			(at 0 0 90)
			(unlocked yes)
			(layer "B.Fab")
			(hide yes)
			(effects
				(font
					(size 1 1)
					(thickness 0.15)
				)
				(justify mirror)
			)
		)
		(property "Author" "Antmicro"
			(at 0 0 90)
			(unlocked yes)
			(layer "B.Fab")
			(hide yes)
			(effects
				(font
					(size 1 1)
					(thickness 0.15)
				)
				(justify mirror)
			)
		)
		(property "License" "Apache-2.0"
			(at 0 0 90)
			(unlocked yes)
			(layer "B.Fab")
			(hide yes)
			(effects
				(font
					(size 1 1)
					(thickness 0.15)
				)
				(justify mirror)
			)
		)
		(sheetname "/Peripherals/")
		(sheetfile "peripherals.kicad_sch")
		(attr exclude_from_pos_files exclude_from_bom)
		(fp_circle
			(center 0 0)
			(end 0.475 0)
			(stroke
				(width 0.05)
				(type default)
			)
			(fill no)
			(layer "B.CrtYd")
		)
		(fp_text user "Author: Antmicro"
			(at -0.4 -3.901 90)
			(layer "B.Fab")
			(effects
				(font
					(size 0.7 0.7)
					(thickness 0.15)
				)
				(justify left bottom mirror)
			)
		)
		(fp_text user "${REFERENCE}"
			(at -0.4 -2.7 90)
			(layer "B.Fab")
			(effects
				(font
					(size 0.7 0.7)
					(thickness 0.15)
				)
				(justify left bottom mirror)
			)
		)
		(fp_text user "License: Apache-2.0"
			(at -0.4 -5.101 90)
			(layer "B.Fab")
			(effects
				(font
					(size 0.7 0.7)
					(thickness 0.15)
				)
				(justify left bottom mirror)
			)
		)
		(pad "1" smd circle
			(at 0 0 270)
			(size 0.75 0.75)
			(layers "B.Cu" "B.Mask")
			(net 97 "/Peripherals/FAN_PWM")
			(pinfunction "1")
			(pintype "passive")
		)
	)
	(footprint "antmicro-footprints:R_0402_1005Metric"
		(layer "B.Cu")
		(at 238.1 83.55 180)
		(descr "Resistor SMD 0402")
		(tags "resistor SMD 0402")
		(property "Reference" "R153"
			(at -1.625 -2.149999 0)
			(layer "B.SilkS")
			(effects
				(font
					(size 0.7 0.7)
					(thickness 0.15)
				)
				(justify left bottom mirror)
			)
		)
		(property "Value" "R_2k2_0402"
			(at -1.011843 -1.772046 0)
			(layer "B.Fab")
			(effects
				(font
					(size 0.7 0.7)
					(thickness 0.15)
				)
				(justify left bottom mirror)
			)
		)
		(property "Datasheet" "https://www.bourns.com/docs/product-datasheets/cr.pdf"
			(at 0 0 0)
			(layer "B.Fab")
			(hide yes)
			(effects
				(font
					(size 1.27 1.27)
					(thickness 0.15)
				)
				(justify mirror)
			)
		)
		(property "Description" "SMD Chip Resistor, 2.2 kohm, ± 1%, 62.5 mW, 0402 [1005 Metric], Thick Film, General Purpose"
			(at 0 0 0)
			(layer "B.Fab")
			(hide yes)
			(effects
				(font
					(size 1.27 1.27)
					(thickness 0.15)
				)
				(justify mirror)
			)
		)
		(property "Manufacturer" "Bourns"
			(at 0 0 0)
			(unlocked yes)
			(layer "B.Fab")
			(hide yes)
			(effects
				(font
					(size 1 1)
					(thickness 0.15)
				)
				(justify mirror)
			)
		)
		(property "MPN" "CR0402-FX-2201GLF"
			(at 0 0 0)
			(unlocked yes)
			(layer "B.Fab")
			(hide yes)
			(effects
				(font
					(size 1 1)
					(thickness 0.15)
				)
				(justify mirror)
			)
		)
		(property "Val" "2k2"
			(at 0 0 0)
			(unlocked yes)
			(layer "B.Fab")
			(hide yes)
			(effects
				(font
					(size 1 1)
					(thickness 0.15)
				)
				(justify mirror)
			)
		)
		(property "License" "Apache-2.0"
			(at 0 0 0)
			(unlocked yes)
			(layer "B.Fab")
			(hide yes)
			(effects
				(font
					(size 1 1)
					(thickness 0.15)
				)
				(justify mirror)
			)
		)
		(property "Author" "Antmicro"
			(at 0 0 0)
			(unlocked yes)
			(layer "B.Fab")
			(hide yes)
			(effects
				(font
					(size 1 1)
					(thickness 0.15)
				)
				(justify mirror)
			)
		)
		(property "Tolerance" "1%"
			(at 0 0 0)
			(unlocked yes)
			(layer "B.Fab")
			(hide yes)
			(effects
				(font
					(size 1 1)
					(thickness 0.15)
				)
				(justify mirror)
			)
		)
		(sheetname "/USB Debug, PD/")
		(sheetfile "usb_debug_pd.kicad_sch")
		(attr smd)
		(fp_poly
			(pts
				(xy -0.925 0.47) (xy -0.925 -0.47) (xy 0.925 -0.47) (xy 0.925 0.47)
			)
			(stroke
				(width 0.05)
				(type default)
			)
			(fill no)
			(layer "B.CrtYd")
		)
		(fp_poly
			(pts
				(xy -0.5 0.25) (xy -0.5 -0.25) (xy 0.5 -0.25) (xy 0.5 0.25)
			)
			(stroke
				(width 0.15)
				(type solid)
			)
			(fill no)
			(layer "B.Fab")
		)
		(fp_text user "${REFERENCE}"
			(at -0.95 -3.168 0)
			(layer "B.Fab")
			(effects
				(font
					(size 0.7 0.7)
					(thickness 0.15)
				)
				(justify left bottom mirror)
			)
		)
		(fp_text user "Author: Antmicro"
			(at -0.95 -4.169 0)
			(layer "B.Fab")
			(effects
				(font
					(size 0.7 0.7)
					(thickness 0.15)
				)
				(justify left bottom mirror)
			)
		)
		(fp_text user "License: Apache-2.0"
			(at -0.949999 -5.169 0)
			(layer "B.Fab")
			(effects
				(font
					(size 0.7 0.7)
					(thickness 0.15)
				)
				(justify left bottom mirror)
			)
		)
		(pad "1" smd roundrect
			(at -0.48 0 180)
			(size 0.59 0.64)
			(layers "B.Cu" "B.Mask" "B.Paste")
			(roundrect_rratio 0.25)
			(net 1 "GND")
			(pintype "passive")
		)
		(pad "2" smd roundrect
			(at 0.48 0 180)
			(size 0.59 0.64)
			(layers "B.Cu" "B.Mask" "B.Paste")
			(roundrect_rratio 0.25)
			(net 978 "/USB Debug, PD/USBC0_ISET")
			(pintype "passive")
		)
	)
	(footprint "antmicro-footprints:TP_SMD_0.75mm"
		(layer "B.Cu")
		(at 140.2 63.8 -90)
		(property "Reference" "TP97"
			(at 0.5 -0.3 90)
			(layer "B.SilkS")
			(effects
				(font
					(size 0.7 0.7)
					(thickness 0.15)
				)
				(justify left bottom mirror)
			)
		)
		(property "Value" "TP_0.75mm_SMD"
			(at 0 -1.2 90)
			(layer "B.Fab")
			(effects
				(font
					(size 0.7 0.7)
					(thickness 0.15)
				)
				(justify left bottom mirror)
			)
		)
		(property "Description" "SMT test point"
			(at 0 0 90)
			(layer "B.Fab")
			(hide yes)
			(effects
				(font
					(size 1.27 1.27)
					(thickness 0.15)
				)
				(justify mirror)
			)
		)
		(property "MPN" ""
			(at 0 0 90)
			(unlocked yes)
			(layer "B.Fab")
			(hide yes)
			(effects
				(font
					(size 1 1)
					(thickness 0.15)
				)
				(justify mirror)
			)
		)
		(property "Manufacturer" ""
			(at 0 0 90)
			(unlocked yes)
			(layer "B.Fab")
			(hide yes)
			(effects
				(font
					(size 1 1)
					(thickness 0.15)
				)
				(justify mirror)
			)
		)
		(property "Author" "Antmicro"
			(at 0 0 90)
			(unlocked yes)
			(layer "B.Fab")
			(hide yes)
			(effects
				(font
					(size 1 1)
					(thickness 0.15)
				)
				(justify mirror)
			)
		)
		(property "License" "Apache-2.0"
			(at 0 0 90)
			(unlocked yes)
			(layer "B.Fab")
			(hide yes)
			(effects
				(font
					(size 1 1)
					(thickness 0.15)
				)
				(justify mirror)
			)
		)
		(sheetname "/Peripherals/")
		(sheetfile "peripherals.kicad_sch")
		(attr exclude_from_pos_files exclude_from_bom)
		(fp_circle
			(center 0 0)
			(end 0.475 0)
			(stroke
				(width 0.05)
				(type default)
			)
			(fill no)
			(layer "B.CrtYd")
		)
		(fp_text user "Author: Antmicro"
			(at -0.4 -3.901 90)
			(layer "B.Fab")
			(effects
				(font
					(size 0.7 0.7)
					(thickness 0.15)
				)
				(justify left bottom mirror)
			)
		)
		(fp_text user "${REFERENCE}"
			(at -0.4 -2.7 90)
			(layer "B.Fab")
			(effects
				(font
					(size 0.7 0.7)
					(thickness 0.15)
				)
				(justify left bottom mirror)
			)
		)
		(fp_text user "License: Apache-2.0"
			(at -0.4 -5.101 90)
			(layer "B.Fab")
			(effects
				(font
					(size 0.7 0.7)
					(thickness 0.15)
				)
				(justify left bottom mirror)
			)
		)
		(pad "1" smd circle
			(at 0 0 270)
			(size 0.75 0.75)
			(layers "B.Cu" "B.Mask")
			(net 90 "/Peripherals/I2C_CONN_PEN")
			(pinfunction "1")
			(pintype "passive")
		)
	)
	(footprint "antmicro-footprints:C_0402_1005Metric"
		(layer "B.Cu")
		(at 235.9 135)
		(descr "Capacitor SMD 0402")
		(tags "capacitor SMD 0402")
		(property "Reference" "C104"
			(at 1.084 -0.413 0)
			(layer "B.SilkS")
			(effects
				(font
					(size 0.7 0.7)
					(thickness 0.15)
				)
				(justify right top mirror)
			)
		)
		(property "Value" "C_100n_0402"
			(at -1.022927 -2.155213 0)
			(layer "B.Fab")
			(effects
				(font
					(size 0.7 0.7)
					(thickness 0.15)
				)
				(justify right top mirror)
			)
		)
		(property "Datasheet" "https://www.murata.com/products/productdetail?partno=GRM155R61H104KE14%23"
			(at 0 0 0)
			(layer "B.Fab")
			(hide yes)
			(effects
				(font
					(size 1.27 1.27)
					(thickness 0.15)
				)
				(justify mirror)
			)
		)
		(property "Description" "SMD Multilayer Ceramic Capacitor, 0.1 µF, 50 V, 0402 [1005 Metric], ± 10%, X5R, GRM Series"
			(at 0 0 0)
			(layer "B.Fab")
			(hide yes)
			(effects
				(font
					(size 1.27 1.27)
					(thickness 0.15)
				)
				(justify mirror)
			)
		)
		(property "Manufacturer" "Murata"
			(at 0 0 180)
			(unlocked yes)
			(layer "B.Fab")
			(hide yes)
			(effects
				(font
					(size 1 1)
					(thickness 0.15)
				)
				(justify mirror)
			)
		)
		(property "MPN" "GRM155R61H104KE14D"
			(at 0 0 180)
			(unlocked yes)
			(layer "B.Fab")
			(hide yes)
			(effects
				(font
					(size 1 1)
					(thickness 0.15)
				)
				(justify mirror)
			)
		)
		(property "Val" "100n"
			(at 0 0 180)
			(unlocked yes)
			(layer "B.Fab")
			(hide yes)
			(effects
				(font
					(size 1 1)
					(thickness 0.15)
				)
				(justify mirror)
			)
		)
		(property "License" "Apache-2.0"
			(at 0 0 180)
			(unlocked yes)
			(layer "B.Fab")
			(hide yes)
			(effects
				(font
					(size 1 1)
					(thickness 0.15)
				)
				(justify mirror)
			)
		)
		(property "Author" "Antmicro"
			(at 0 0 180)
			(unlocked yes)
			(layer "B.Fab")
			(hide yes)
			(effects
				(font
					(size 1 1)
					(thickness 0.15)
				)
				(justify mirror)
			)
		)
		(property "Voltage" "50V"
			(at 0 0 180)
			(unlocked yes)
			(layer "B.Fab")
			(hide yes)
			(effects
				(font
					(size 1 1)
					(thickness 0.15)
				)
				(justify mirror)
			)
		)
		(property "Dielectric" "X5R"
			(at 0 0 180)
			(unlocked yes)
			(layer "B.Fab")
			(hide yes)
			(effects
				(font
					(size 1 1)
					(thickness 0.15)
				)
				(justify mirror)
			)
		)
		(sheetname "/USB Hub/")
		(sheetfile "usb_hub.kicad_sch")
		(attr smd)
		(fp_poly
			(pts
				(xy -0.925 0.47) (xy -0.925 -0.47) (xy 0.925 -0.47) (xy 0.925 0.47)
			)
			(stroke
				(width 0.05)
				(type default)
			)
			(fill no)
			(layer "B.CrtYd")
		)
		(fp_line
			(start -0.494 -0.248)
			(end -0.494 0.25)
			(stroke
				(width 0.15)
				(type solid)
			)
			(layer "B.Fab")
		)
		(fp_line
			(start -0.494 0.25)
			(end 0.504 0.25)
			(stroke
				(width 0.15)
				(type solid)
			)
			(layer "B.Fab")
		)
		(fp_line
			(start 0.504 -0.248)
			(end -0.494 -0.248)
			(stroke
				(width 0.15)
				(type solid)
			)
			(layer "B.Fab")
		)
		(fp_line
			(start 0.504 0.25)
			(end 0.504 -0.248)
			(stroke
				(width 0.15)
				(type solid)
			)
			(layer "B.Fab")
		)
		(fp_text user "${REFERENCE}"
			(at -0.939 -4.599 0)
			(layer "B.Fab")
			(effects
				(font
					(size 0.7 0.7)
					(thickness 0.15)
				)
				(justify right top mirror)
			)
		)
		(fp_text user "License: Apache-2.0"
			(at -0.939 -5.799 0)
			(layer "B.Fab")
			(effects
				(font
					(size 0.7 0.7)
					(thickness 0.15)
				)
				(justify right top mirror)
			)
		)
		(fp_text user "Author: Antmicro"
			(at -0.939 -3.399 0)
			(layer "B.Fab")
			(effects
				(font
					(size 0.7 0.7)
					(thickness 0.15)
				)
				(justify right top mirror)
			)
		)
		(pad "1" smd roundrect
			(at -0.48 0)
			(size 0.59 0.64)
			(layers "B.Cu" "B.Mask" "B.Paste")
			(roundrect_rratio 0.25)
			(net 5 "+5V")
			(pintype "passive")
		)
		(pad "2" smd roundrect
			(at 0.48 0)
			(size 0.59 0.64)
			(layers "B.Cu" "B.Mask" "B.Paste")
			(roundrect_rratio 0.25)
			(net 1 "GND")
			(pintype "passive")
		)
	)
	(footprint "antmicro-footprints:Spacer_Drill3.7mm_H8mm_9774080151R"
		(locked yes)
		(layer "B.Cu")
		(at 152.430532 143.71 180)
		(descr "Spacer M=3 h=8mm fi=5.1mm")
		(property "Reference" "H12"
			(at 0 3.2 0)
			(layer "B.SilkS")
			(effects
				(font
					(size 0.7 0.7)
					(thickness 0.15)
				)
				(justify left bottom mirror)
			)
		)
		(property "Value" "Spacer_Drill3.7mm_H8mm_9774080151R"
			(at 0 -4 0)
			(layer "B.Fab")
			(effects
				(font
					(size 0.7 0.7)
					(thickness 0.15)
				)
				(justify left bottom mirror)
			)
		)
		(property "Datasheet" "https://www.we-online.com/components/products/datasheet/9774080151R.pdf"
			(at 0 0 0)
			(layer "B.Fab")
			(hide yes)
			(effects
				(font
					(size 1.27 1.27)
					(thickness 0.15)
				)
				(justify mirror)
			)
		)
		(property "Description" "Spacer, SMT, Non Stop, Steel, Swage Round, 5.1 mm x 8 mm, M2.5 Thread, WA-SMSI Series"
			(at 0 0 0)
			(layer "B.Fab")
			(hide yes)
			(effects
				(font
					(size 1.27 1.27)
					(thickness 0.15)
				)
				(justify mirror)
			)
		)
		(property "Manufacturer" "Würth Elektronik"
			(at 0 0 180)
			(unlocked yes)
			(layer "B.Fab")
			(hide yes)
			(effects
				(font
					(size 1 1)
					(thickness 0.15)
				)
				(justify mirror)
			)
		)
		(property "MPN" "9774080151R"
			(at 0 0 180)
			(unlocked yes)
			(layer "B.Fab")
			(hide yes)
			(effects
				(font
					(size 1 1)
					(thickness 0.15)
				)
				(justify mirror)
			)
		)
		(property "Author" "Antmicro"
			(at 0 0 180)
			(unlocked yes)
			(layer "B.Fab")
			(hide yes)
			(effects
				(font
					(size 1 1)
					(thickness 0.15)
				)
				(justify mirror)
			)
		)
		(property "License" "Apache-2.0"
			(at 0 0 180)
			(unlocked yes)
			(layer "B.Fab")
			(hide yes)
			(effects
				(font
					(size 1 1)
					(thickness 0.15)
				)
				(justify mirror)
			)
		)
		(sheetname "/")
		(sheetfile "jetson-agx-thor-baseboard.kicad_sch")
		(solder_paste_margin_ratio -1)
		(attr smd)
		(fp_circle
			(center 0 0)
			(end 3.05 0)
			(stroke
				(width 0.05)
				(type solid)
			)
			(fill no)
			(layer "B.CrtYd")
		)
		(fp_circle
			(center 0 0)
			(end 2.6 0)
			(stroke
				(width 0.15)
				(type solid)
			)
			(fill no)
			(layer "B.Fab")
		)
		(fp_text user "${REFERENCE}"
			(at -9.6 -6.5 0)
			(layer "B.Fab")
			(effects
				(font
					(size 0.7 0.7)
					(thickness 0.15)
				)
				(justify left bottom mirror)
			)
		)
		(fp_text user "Author: Antmicro"
			(at -9.6 -7.7 0)
			(layer "B.Fab")
			(effects
				(font
					(size 0.7 0.7)
					(thickness 0.15)
				)
				(justify left bottom mirror)
			)
		)
		(fp_text user "License: Apache-2.0"
			(at -9.6 -8.9 0)
			(layer "B.Fab")
			(effects
				(font
					(size 0.7 0.7)
					(thickness 0.15)
				)
				(justify left bottom mirror)
			)
		)
		(pad "" smd custom
			(at -1.7 -1.7 90)
			(size 0.62 0.62)
			(layers "B.Paste")
			(thermal_bridge_angle 90)
			(options
				(clearance outline)
				(anchor circle)
			)
			(primitives
				(gr_arc
					(start 1.266786 0.24747)
					(mid 0.285453 -0.29439)
					(end -0.250195 -1.279127)
					(width 0.2)
				)
				(gr_arc
					(start 1.259603 0.339191)
					(mid 0.218448 -0.232561)
					(end -0.34334 -1.279127)
					(width 0.2)
				)
				(gr_arc
					(start 1.255279 0.431435)
					(mid 0.152481 -0.169693)
					(end -0.436309 -1.279127)
					(width 0.2)
				)
				(gr_arc
					(start 1.253811 0.524161)
					(mid 0.087542 -0.105784)
					(end -0.529126 -1.279127)
					(width 0.2)
				)
				(gr_arc
					(start 1.275473 0.621136)
					(mid 0.0309 -0.033527)
					(end -0.621807 -1.279127)
					(width 0.2)
				)
				(gr_arc
					(start 1.263664 0.711602)
					(mid -0.037759 0.026651)
					(end -0.71437 -1.279127)
					(width 0.2)
				)
				(gr_arc
					(start 1.253435 0.802342)
					(mid -0.105837 0.087395)
					(end -0.806826 -1.279127)
					(width 0.2)
				)
				(gr_arc
					(start 1.267475 0.897258)
					(mid -0.165236 0.156885)
					(end -0.899187 -1.279127)
					(width 0.2)
				)
				(gr_arc
					(start 1.270645 0.990112)
					(mid -0.228522 0.222449)
					(end -0.991463 -1.279127)
					(width 0.2)
				)
				(gr_arc
					(start 1.266278 1.081674)
					(mid -0.294507 0.285313)
					(end -1.083663 -1.279127)
					(width 0.2)
				)
				(gr_line
					(start 1.279127 0.250195)
					(end 1.279127 1.083663)
					(width 0.2)
				)
				(gr_line
					(start -0.250195 -1.279127)
					(end -1.083663 -1.279127)
					(width 0.2)
				)
			)
		)
		(pad "" smd custom
			(at -1.7 1.7 180)
			(size 0.62 0.62)
			(layers "B.Paste")
			(thermal_bridge_angle 90)
			(options
				(clearance outline)
				(anchor circle)
			)
			(primitives
				(gr_arc
					(start 1.266786 0.24747)
					(mid 0.285453 -0.29439)
					(end -0.250195 -1.279127)
					(width 0.2)
				)
				(gr_arc
					(start 1.259603 0.339191)
					(mid 0.218448 -0.232561)
					(end -0.34334 -1.279127)
					(width 0.2)
				)
				(gr_arc
					(start 1.255279 0.431435)
					(mid 0.152481 -0.169693)
					(end -0.436309 -1.279127)
					(width 0.2)
				)
				(gr_arc
					(start 1.253811 0.524161)
					(mid 0.087542 -0.105784)
					(end -0.529126 -1.279127)
					(width 0.2)
				)
				(gr_arc
					(start 1.275473 0.621136)
					(mid 0.0309 -0.033527)
					(end -0.621807 -1.279127)
					(width 0.2)
				)
				(gr_arc
					(start 1.263664 0.711602)
					(mid -0.037759 0.026651)
					(end -0.71437 -1.279127)
					(width 0.2)
				)
				(gr_arc
					(start 1.253435 0.802342)
					(mid -0.105837 0.087395)
					(end -0.806826 -1.279127)
					(width 0.2)
				)
				(gr_arc
					(start 1.267475 0.897258)
					(mid -0.165236 0.156885)
					(end -0.899187 -1.279127)
					(width 0.2)
				)
				(gr_arc
					(start 1.270645 0.990112)
					(mid -0.228522 0.222449)
					(end -0.991463 -1.279127)
					(width 0.2)
				)
				(gr_arc
					(start 1.266278 1.081674)
					(mid -0.294507 0.285313)
					(end -1.083663 -1.279127)
					(width 0.2)
				)
				(gr_line
					(start 1.279127 0.250195)
					(end 1.279127 1.083663)
					(width 0.2)
				)
				(gr_line
					(start -0.250195 -1.279127)
					(end -1.083663 -1.279127)
					(width 0.2)
				)
			)
		)
		(pad "" smd custom
			(at 1.7 -1.7)
			(size 0.62 0.62)
			(layers "B.Paste")
			(thermal_bridge_angle 90)
			(options
				(clearance outline)
				(anchor circle)
			)
			(primitives
				(gr_arc
					(start 1.266786 0.24747)
					(mid 0.285453 -0.29439)
					(end -0.250195 -1.279127)
					(width 0.2)
				)
				(gr_arc
					(start 1.259603 0.339191)
					(mid 0.218448 -0.232561)
					(end -0.34334 -1.279127)
					(width 0.2)
				)
				(gr_arc
					(start 1.255279 0.431435)
					(mid 0.152481 -0.169693)
					(end -0.436309 -1.279127)
					(width 0.2)
				)
				(gr_arc
					(start 1.253811 0.524161)
					(mid 0.087542 -0.105784)
					(end -0.529126 -1.279127)
					(width 0.2)
				)
				(gr_arc
					(start 1.275473 0.621136)
					(mid 0.0309 -0.033527)
					(end -0.621807 -1.279127)
					(width 0.2)
				)
				(gr_arc
					(start 1.263664 0.711602)
					(mid -0.037759 0.026651)
					(end -0.71437 -1.279127)
					(width 0.2)
				)
				(gr_arc
					(start 1.253435 0.802342)
					(mid -0.105837 0.087395)
					(end -0.806826 -1.279127)
					(width 0.2)
				)
				(gr_arc
					(start 1.267475 0.897258)
					(mid -0.165236 0.156885)
					(end -0.899187 -1.279127)
					(width 0.2)
				)
				(gr_arc
					(start 1.270645 0.990112)
					(mid -0.228522 0.222449)
					(end -0.991463 -1.279127)
					(width 0.2)
				)
				(gr_arc
					(start 1.266278 1.081674)
					(mid -0.294507 0.285313)
					(end -1.083663 -1.279127)
					(width 0.2)
				)
				(gr_line
					(start 1.279127 0.250195)
					(end 1.279127 1.083663)
					(width 0.2)
				)
				(gr_line
					(start -0.250195 -1.279127)
					(end -1.083663 -1.279127)
					(width 0.2)
				)
			)
		)
		(pad "" smd custom
			(at 1.7 1.7 270)
			(size 0.62 0.62)
			(layers "B.Paste")
			(thermal_bridge_angle 90)
			(options
				(clearance outline)
				(anchor circle)
			)
			(primitives
				(gr_arc
					(start 1.266786 0.24747)
					(mid 0.285453 -0.29439)
					(end -0.250195 -1.279127)
					(width 0.2)
				)
				(gr_arc
					(start 1.259603 0.339191)
					(mid 0.218448 -0.232561)
					(end -0.34334 -1.279127)
					(width 0.2)
				)
				(gr_arc
					(start 1.255279 0.431435)
					(mid 0.152481 -0.169693)
					(end -0.436309 -1.279127)
					(width 0.2)
				)
				(gr_arc
					(start 1.253811 0.524161)
					(mid 0.087542 -0.105784)
					(end -0.529126 -1.279127)
					(width 0.2)
				)
				(gr_arc
					(start 1.275473 0.621136)
					(mid 0.0309 -0.033527)
					(end -0.621807 -1.279127)
					(width 0.2)
				)
				(gr_arc
					(start 1.263664 0.711602)
					(mid -0.037759 0.026651)
					(end -0.71437 -1.279127)
					(width 0.2)
				)
				(gr_arc
					(start 1.253435 0.802342)
					(mid -0.105837 0.087395)
					(end -0.806826 -1.279127)
					(width 0.2)
				)
				(gr_arc
					(start 1.267475 0.897258)
					(mid -0.165236 0.156885)
					(end -0.899187 -1.279127)
					(width 0.2)
				)
				(gr_arc
					(start 1.270645 0.990112)
					(mid -0.228522 0.222449)
					(end -0.991463 -1.279127)
					(width 0.2)
				)
				(gr_arc
					(start 1.266278 1.081674)
					(mid -0.294507 0.285313)
					(end -1.083663 -1.279127)
					(width 0.2)
				)
				(gr_line
					(start 1.279127 0.250195)
					(end 1.279127 1.083663)
					(width 0.2)
				)
				(gr_line
					(start -0.250195 -1.279127)
					(end -1.083663 -1.279127)
					(width 0.2)
				)
			)
		)
		(pad "1" thru_hole circle
			(at 0 0 180)
			(size 6 6)
			(drill 3.7)
			(layers "*.Cu" "*.Mask")
			(remove_unused_layers no)
			(net 1 "GND")
			(pintype "passive")
		)
	)
	(footprint "antmicro-footprints:C_0402_1005Metric"
		(layer "B.Cu")
		(at 230.07 103.6 180)
		(descr "Capacitor SMD 0402")
		(tags "capacitor SMD 0402")
		(property "Reference" "C116"
			(at 0.9 -0.4 0)
			(layer "B.SilkS")
			(effects
				(font
					(size 0.7 0.7)
					(thickness 0.15)
				)
				(justify left bottom mirror)
			)
		)
		(property "Value" "C_100n_0402"
			(at -1.022927 -2.155213 0)
			(layer "B.Fab")
			(effects
				(font
					(size 0.7 0.7)
					(thickness 0.15)
				)
				(justify left bottom mirror)
			)
		)
		(property "Datasheet" "https://www.murata.com/products/productdetail?partno=GRM155R61H104KE14%23"
			(at 0 0 0)
			(layer "B.Fab")
			(hide yes)
			(effects
				(font
					(size 1.27 1.27)
					(thickness 0.15)
				)
				(justify mirror)
			)
		)
		(property "Description" "SMD Multilayer Ceramic Capacitor, 0.1 µF, 50 V, 0402 [1005 Metric], ± 10%, X5R, GRM Series"
			(at 0 0 0)
			(layer "B.Fab")
			(hide yes)
			(effects
				(font
					(size 1.27 1.27)
					(thickness 0.15)
				)
				(justify mirror)
			)
		)
		(property "Manufacturer" "Murata"
			(at 0 0 0)
			(unlocked yes)
			(layer "B.Fab")
			(hide yes)
			(effects
				(font
					(size 1 1)
					(thickness 0.15)
				)
				(justify mirror)
			)
		)
		(property "MPN" "GRM155R61H104KE14D"
			(at 0 0 0)
			(unlocked yes)
			(layer "B.Fab")
			(hide yes)
			(effects
				(font
					(size 1 1)
					(thickness 0.15)
				)
				(justify mirror)
			)
		)
		(property "Val" "100n"
			(at 0 0 0)
			(unlocked yes)
			(layer "B.Fab")
			(hide yes)
			(effects
				(font
					(size 1 1)
					(thickness 0.15)
				)
				(justify mirror)
			)
		)
		(property "License" "Apache-2.0"
			(at 0 0 0)
			(unlocked yes)
			(layer "B.Fab")
			(hide yes)
			(effects
				(font
					(size 1 1)
					(thickness 0.15)
				)
				(justify mirror)
			)
		)
		(property "Author" "Antmicro"
			(at 0 0 0)
			(unlocked yes)
			(layer "B.Fab")
			(hide yes)
			(effects
				(font
					(size 1 1)
					(thickness 0.15)
				)
				(justify mirror)
			)
		)
		(property "Voltage" "50V"
			(at 0 0 0)
			(unlocked yes)
			(layer "B.Fab")
			(hide yes)
			(effects
				(font
					(size 1 1)
					(thickness 0.15)
				)
				(justify mirror)
			)
		)
		(property "Dielectric" "X5R"
			(at 0 0 0)
			(unlocked yes)
			(layer "B.Fab")
			(hide yes)
			(effects
				(font
					(size 1 1)
					(thickness 0.15)
				)
				(justify mirror)
			)
		)
		(sheetname "/Recovery USB/")
		(sheetfile "recovery_usb.kicad_sch")
		(attr smd)
		(fp_poly
			(pts
				(xy -0.925 0.47) (xy 0.925 0.47) (xy 0.925 -0.47) (xy -0.925 -0.47)
			)
			(stroke
				(width 0.05)
				(type default)
			)
			(fill no)
			(layer "B.CrtYd")
		)
		(fp_line
			(start 0.504 0.25)
			(end 0.504 -0.248)
			(stroke
				(width 0.15)
				(type solid)
			)
			(layer "B.Fab")
		)
		(fp_line
			(start 0.504 -0.248)
			(end -0.494 -0.248)
			(stroke
				(width 0.15)
				(type solid)
			)
			(layer "B.Fab")
		)
		(fp_line
			(start -0.494 0.25)
			(end 0.504 0.25)
			(stroke
				(width 0.15)
				(type solid)
			)
			(layer "B.Fab")
		)
		(fp_line
			(start -0.494 -0.248)
			(end -0.494 0.25)
			(stroke
				(width 0.15)
				(type solid)
			)
			(layer "B.Fab")
		)
		(fp_text user "${REFERENCE}"
			(at -0.939 -4.599 0)
			(layer "B.Fab")
			(effects
				(font
					(size 0.7 0.7)
					(thickness 0.15)
				)
				(justify left bottom mirror)
			)
		)
		(fp_text user "License: Apache-2.0"
			(at -0.939 -5.799 0)
			(layer "B.Fab")
			(effects
				(font
					(size 0.7 0.7)
					(thickness 0.15)
				)
				(justify left bottom mirror)
			)
		)
		(fp_text user "Author: Antmicro"
			(at -0.939 -3.399 0)
			(layer "B.Fab")
			(effects
				(font
					(size 0.7 0.7)
					(thickness 0.15)
				)
				(justify left bottom mirror)
			)
		)
		(pad "1" smd roundrect
			(at -0.48 0 180)
			(size 0.59 0.64)
			(layers "B.Cu" "B.Mask" "B.Paste")
			(roundrect_rratio 0.25)
			(net 287 "/Recovery USB/USBC2_VBUS")
			(pintype "passive")
		)
		(pad "2" smd roundrect
			(at 0.48 0 180)
			(size 0.59 0.64)
			(layers "B.Cu" "B.Mask" "B.Paste")
			(roundrect_rratio 0.25)
			(net 1 "GND")
			(pintype "passive")
		)
	)
	(footprint "antmicro-footprints:R_0402_1005Metric"
		(layer "B.Cu")
		(at 214.6 102)
		(descr "Resistor SMD 0402")
		(tags "resistor SMD 0402")
		(property "Reference" "R267"
			(at -3.775 -0.4 0)
			(layer "B.SilkS")
			(effects
				(font
					(size 0.7 0.7)
					(thickness 0.15)
				)
				(justify right top mirror)
			)
		)
		(property "Value" "R_887k_0402"
			(at -1.011843 -1.772046 0)
			(layer "B.Fab")
			(effects
				(font
					(size 0.7 0.7)
					(thickness 0.15)
				)
				(justify right top mirror)
			)
		)
		(property "Datasheet" "https://eu.mouser.com/datasheet/2/315/AOA0000C304-1149620.pdf"
			(at 0 0 0)
			(layer "B.Fab")
			(hide yes)
			(effects
				(font
					(size 1.27 1.27)
					(thickness 0.15)
				)
				(justify mirror)
			)
		)
		(property "Description" "SMD Chip Resistor"
			(at 0 0 0)
			(layer "B.Fab")
			(hide yes)
			(effects
				(font
					(size 1.27 1.27)
					(thickness 0.15)
				)
				(justify mirror)
			)
		)
		(property "MPN" "ERJ-2RKF8873X"
			(at 0 0 180)
			(unlocked yes)
			(layer "B.Fab")
			(hide yes)
			(effects
				(font
					(size 1 1)
					(thickness 0.15)
				)
				(justify mirror)
			)
		)
		(property "Manufacturer" "Panasonic"
			(at 0 0 180)
			(unlocked yes)
			(layer "B.Fab")
			(hide yes)
			(effects
				(font
					(size 1 1)
					(thickness 0.15)
				)
				(justify mirror)
			)
		)
		(property "License" "Apache-2.0"
			(at 0 0 180)
			(unlocked yes)
			(layer "B.Fab")
			(hide yes)
			(effects
				(font
					(size 1 1)
					(thickness 0.15)
				)
				(justify mirror)
			)
		)
		(property "Author" "Antmicro"
			(at 0 0 180)
			(unlocked yes)
			(layer "B.Fab")
			(hide yes)
			(effects
				(font
					(size 1 1)
					(thickness 0.15)
				)
				(justify mirror)
			)
		)
		(property "Val" "887k"
			(at 0 0 180)
			(unlocked yes)
			(layer "B.Fab")
			(hide yes)
			(effects
				(font
					(size 1 1)
					(thickness 0.15)
				)
				(justify mirror)
			)
		)
		(property "Tolerance" "1%"
			(at 0 0 180)
			(unlocked yes)
			(layer "B.Fab")
			(hide yes)
			(effects
				(font
					(size 1 1)
					(thickness 0.15)
				)
				(justify mirror)
			)
		)
		(sheetname "/Recovery USB/")
		(sheetfile "recovery_usb.kicad_sch")
		(attr smd)
		(fp_poly
			(pts
				(xy -0.925 0.47) (xy 0.925 0.47) (xy 0.925 -0.47) (xy -0.925 -0.47)
			)
			(stroke
				(width 0.05)
				(type default)
			)
			(fill no)
			(layer "B.CrtYd")
		)
		(fp_poly
			(pts
				(xy -0.5 0.25) (xy 0.5 0.25) (xy 0.5 -0.25) (xy -0.5 -0.25)
			)
			(stroke
				(width 0.15)
				(type solid)
			)
			(fill no)
			(layer "B.Fab")
		)
		(fp_text user "License: Apache-2.0"
			(at -0.949999 -5.169 0)
			(layer "B.Fab")
			(effects
				(font
					(size 0.7 0.7)
					(thickness 0.15)
				)
				(justify right top mirror)
			)
		)
		(fp_text user "${REFERENCE}"
			(at -0.95 -3.168 0)
			(layer "B.Fab")
			(effects
				(font
					(size 0.7 0.7)
					(thickness 0.15)
				)
				(justify right top mirror)
			)
		)
		(fp_text user "Author: Antmicro"
			(at -0.95 -4.169 0)
			(layer "B.Fab")
			(effects
				(font
					(size 0.7 0.7)
					(thickness 0.15)
				)
				(justify right top mirror)
			)
		)
		(pad "1" smd roundrect
			(at -0.48 0)
			(size 0.59 0.64)
			(layers "B.Cu" "B.Mask" "B.Paste")
			(roundrect_rratio 0.25)
			(net 1246 "/Recovery USB/USBC2_VBUS_DET_MUX")
			(pintype "passive")
		)
		(pad "2" smd roundrect
			(at 0.48 0)
			(size 0.59 0.64)
			(layers "B.Cu" "B.Mask" "B.Paste")
			(roundrect_rratio 0.25)
			(net 287 "/Recovery USB/USBC2_VBUS")
			(pintype "passive")
		)
	)
	(footprint "antmicro-footprints:R_0402_1005Metric"
		(layer "B.Cu")
		(at 65.4 65.7 -90)
		(descr "Resistor SMD 0402")
		(tags "resistor SMD 0402")
		(property "Reference" "R171"
			(at 0.9 -0.5 90)
			(layer "B.SilkS")
			(effects
				(font
					(size 0.7 0.7)
					(thickness 0.15)
				)
				(justify left bottom mirror)
			)
		)
		(property "Value" "R_2k2_0402"
			(at -1.011843 -1.772047 90)
			(layer "B.Fab")
			(effects
				(font
					(size 0.7 0.7)
					(thickness 0.15)
				)
				(justify left bottom mirror)
			)
		)
		(property "Datasheet" "https://www.bourns.com/docs/product-datasheets/cr.pdf"
			(at 0 0 90)
			(layer "B.Fab")
			(hide yes)
			(effects
				(font
					(size 1.27 1.27)
					(thickness 0.15)
				)
				(justify mirror)
			)
		)
		(property "Description" "SMD Chip Resistor, 2.2 kohm, ± 1%, 62.5 mW, 0402 [1005 Metric], Thick Film, General Purpose"
			(at 0 0 90)
			(layer "B.Fab")
			(hide yes)
			(effects
				(font
					(size 1.27 1.27)
					(thickness 0.15)
				)
				(justify mirror)
			)
		)
		(property "MPN" "CR0402-FX-2201GLF"
			(at 0 0 90)
			(unlocked yes)
			(layer "B.Fab")
			(hide yes)
			(effects
				(font
					(size 1 1)
					(thickness 0.15)
				)
				(justify mirror)
			)
		)
		(property "Manufacturer" "Bourns"
			(at 0 0 90)
			(unlocked yes)
			(layer "B.Fab")
			(hide yes)
			(effects
				(font
					(size 1 1)
					(thickness 0.15)
				)
				(justify mirror)
			)
		)
		(property "License" "Apache-2.0"
			(at 0 0 90)
			(unlocked yes)
			(layer "B.Fab")
			(hide yes)
			(effects
				(font
					(size 1 1)
					(thickness 0.15)
				)
				(justify mirror)
			)
		)
		(property "Author" "Antmicro"
			(at 0 0 90)
			(unlocked yes)
			(layer "B.Fab")
			(hide yes)
			(effects
				(font
					(size 1 1)
					(thickness 0.15)
				)
				(justify mirror)
			)
		)
		(property "Val" "2k2"
			(at 0 0 90)
			(unlocked yes)
			(layer "B.Fab")
			(hide yes)
			(effects
				(font
					(size 1 1)
					(thickness 0.15)
				)
				(justify mirror)
			)
		)
		(property "Tolerance" "1%"
			(at 0 0 90)
			(unlocked yes)
			(layer "B.Fab")
			(hide yes)
			(effects
				(font
					(size 1 1)
					(thickness 0.15)
				)
				(justify mirror)
			)
		)
		(sheetname "/CSI/")
		(sheetfile "csi.kicad_sch")
		(attr smd)
		(fp_rect
			(start -0.925 0.47)
			(end 0.925 -0.47)
			(stroke
				(width 0.05)
				(type default)
			)
			(fill no)
			(layer "B.CrtYd")
		)
		(fp_rect
			(start -0.5 0.25)
			(end 0.5 -0.25)
			(stroke
				(width 0.15)
				(type solid)
			)
			(fill no)
			(layer "B.Fab")
		)
		(fp_text user "${REFERENCE}"
			(at -0.95 -3.168 90)
			(layer "B.Fab")
			(effects
				(font
					(size 0.7 0.7)
					(thickness 0.15)
				)
				(justify left bottom mirror)
			)
		)
		(fp_text user "License: Apache-2.0"
			(at -0.95 -5.169 90)
			(layer "B.Fab")
			(effects
				(font
					(size 0.7 0.7)
					(thickness 0.15)
				)
				(justify left bottom mirror)
			)
		)
		(fp_text user "Author: Antmicro"
			(at -0.95 -4.169 90)
			(layer "B.Fab")
			(effects
				(font
					(size 0.7 0.7)
					(thickness 0.15)
				)
				(justify left bottom mirror)
			)
		)
		(pad "1" smd roundrect
			(at -0.48 0 270)
			(size 0.59 0.64)
			(layers "B.Cu" "B.Mask" "B.Paste")
			(roundrect_rratio 0.25)
			(net 990 "/CSI/CSIB_I2C_VCC")
			(pintype "passive")
		)
		(pad "2" smd roundrect
			(at 0.48 0 270)
			(size 0.59 0.64)
			(layers "B.Cu" "B.Mask" "B.Paste")
			(roundrect_rratio 0.25)
			(net 993 "/CSI/SDA_CAM2")
			(pintype "passive")
		)
	)
	(footprint "antmicro-footprints:SOT-23-6"
		(layer "B.Cu")
		(at 179.245 80.38 90)
		(property "Reference" "U62"
			(at -0.92 -2.645 90)
			(layer "B.SilkS")
			(effects
				(font
					(size 0.7 0.7)
					(thickness 0.15)
				)
				(justify right top mirror)
			)
		)
		(property "Value" "LTC4412IS6"
			(at -1.75 -2.693 90)
			(layer "B.Fab")
			(effects
				(font
					(size 0.7 0.7)
					(thickness 0.15)
				)
				(justify right top mirror)
			)
		)
		(property "Datasheet" "https://www.analog.com/media/en/technical-documentation/data-sheets/4412fb.pdf"
			(at 0 0.057 90)
			(layer "B.Fab")
			(hide yes)
			(effects
				(font
					(size 1.27 1.27)
					(thickness 0.15)
				)
				(justify mirror)
			)
		)
		(property "Description" "Ideal diode controller"
			(at 0 0.057 90)
			(layer "B.Fab")
			(hide yes)
			(effects
				(font
					(size 1.27 1.27)
					(thickness 0.15)
				)
				(justify mirror)
			)
		)
		(property "MPN" "LTC4412IS6#TRMPBF"
			(at 0 0 270)
			(unlocked yes)
			(layer "B.Fab")
			(hide yes)
			(effects
				(font
					(size 1 1)
					(thickness 0.15)
				)
				(justify mirror)
			)
		)
		(property "Manufacturer" "Analog Devices"
			(at 0 0 270)
			(unlocked yes)
			(layer "B.Fab")
			(hide yes)
			(effects
				(font
					(size 1 1)
					(thickness 0.15)
				)
				(justify mirror)
			)
		)
		(property "Author" "Antmicro"
			(at 0 0 270)
			(unlocked yes)
			(layer "B.Fab")
			(hide yes)
			(effects
				(font
					(size 1 1)
					(thickness 0.15)
				)
				(justify mirror)
			)
		)
		(property "License" "Apache-2.0"
			(at 0 0 270)
			(unlocked yes)
			(layer "B.Fab")
			(hide yes)
			(effects
				(font
					(size 1 1)
					(thickness 0.15)
				)
				(justify mirror)
			)
		)
		(sheetname "/Power/")
		(sheetfile "power.kicad_sch")
		(attr smd exclude_from_pos_files exclude_from_bom dnp)
		(fp_line
			(start 1.45 -0.643)
			(end 1.45 -0.343)
			(stroke
				(width 0.12)
				(type solid)
			)
			(layer "B.SilkS")
		)
		(fp_line
			(start 1.3 -0.643)
			(end 1.45 -0.643)
			(stroke
				(width 0.12)
				(type solid)
			)
			(layer "B.SilkS")
		)
		(fp_line
			(start -1.45 -0.643)
			(end -1.45 -0.343)
			(stroke
				(width 0.12)
				(type solid)
			)
			(layer "B.SilkS")
		)
		(fp_line
			(start 1.45 0.757)
			(end 1.45 0.457)
			(stroke
				(width 0.12)
				(type solid)
			)
			(layer "B.SilkS")
		)
		(fp_line
			(start 1.3 0.757)
			(end 1.45 0.757)
			(stroke
				(width 0.12)
				(type solid)
			)
			(layer "B.SilkS")
		)
		(fp_line
			(start -1.3 0.757)
			(end -1.45 0.757)
			(stroke
				(width 0.12)
				(type solid)
			)
			(layer "B.SilkS")
		)
		(fp_line
			(start -1.45 0.757)
			(end -1.45 0.457)
			(stroke
				(width 0.12)
				(type solid)
			)
			(layer "B.SilkS")
		)
		(fp_rect
			(start -1.55 1.85)
			(end 1.55 -1.75)
			(stroke
				(width 0.05)
				(type solid)
			)
			(fill no)
			(layer "B.CrtYd")
		)
		(fp_line
			(start 1.5 -0.643)
			(end -1.5 -0.643)
			(stroke
				(width 0.1)
				(type solid)
			)
			(layer "B.Fab")
		)
		(fp_line
			(start -1.5 -0.643)
			(end -1.5 0.757)
			(stroke
				(width 0.1)
				(type solid)
			)
			(layer "B.Fab")
		)
		(fp_line
			(start 1.5 0.757)
			(end 1.5 -0.643)
			(stroke
				(width 0.1)
				(type solid)
			)
			(layer "B.Fab")
		)
		(fp_line
			(start -1.5 0.757)
			(end 1.5 0.757)
			(stroke
				(width 0.1)
				(type solid)
			)
			(layer "B.Fab")
		)
		(fp_text user "."
			(at -1.3 -2.495 90)
			(layer "B.SilkS")
			(effects
				(font
					(size 1 1)
					(thickness 0.15)
				)
				(justify mirror)
			)
		)
		(fp_text user "License: Apache-2.0"
			(at -1.75 -6.5 90)
			(layer "B.Fab")
			(effects
				(font
					(size 0.7 0.7)
					(thickness 0.15)
				)
				(justify right top mirror)
			)
		)
		(fp_text user "Author: Antmicro"
			(at -1.829 -5.25 90)
			(layer "B.Fab")
			(effects
				(font
					(size 0.7 0.7)
					(thickness 0.15)
				)
				(justify right top mirror)
			)
		)
		(fp_text user "${REFERENCE}"
			(at -1.75 -4 90)
			(layer "B.Fab")
			(effects
				(font
					(size 0.7 0.7)
					(thickness 0.15)
				)
				(justify right top mirror)
			)
		)
		(pad "1" smd roundrect
			(at -0.954 -1.1 90)
			(size 0.55 1)
			(layers "B.Cu" "B.Mask" "B.Paste")
			(roundrect_rratio 0.15)
			(net 525 "/Power/USBPD2_HV")
			(pinfunction "IN")
			(pintype "power_in")
		)
		(pad "2" smd roundrect
			(at -0.003 -1.1 90)
			(size 0.55 1)
			(layers "B.Cu" "B.Mask" "B.Paste")
			(roundrect_rratio 0.15)
			(net 1 "GND")
			(pinfunction "GND")
			(pintype "power_in")
		)
		(pad "3" smd roundrect
			(at 0.947 -1.1 90)
			(size 0.55 1)
			(layers "B.Cu" "B.Mask" "B.Paste")
			(roundrect_rratio 0.15)
			(net 1 "GND")
			(pinfunction "CTL")
			(pintype "input")
		)
		(pad "4" smd roundrect
			(at 0.947 1.214 90)
			(size 0.55 1)
			(layers "B.Cu" "B.Mask" "B.Paste")
			(roundrect_rratio 0.15)
			(net 1225 "unconnected-(U62-STAT-Pad4)")
			(pinfunction "STAT")
			(pintype "output+no_connect")
		)
		(pad "5" smd roundrect
			(at -0.003 1.214 90)
			(size 0.55 1)
			(layers "B.Cu" "B.Mask" "B.Paste")
			(roundrect_rratio 0.15)
			(net 1201 "Net-(Q23-G)")
			(pinfunction "GATE")
			(pintype "output")
		)
		(pad "6" smd roundrect
			(at -0.954 1.214 90)
			(size 0.55 1)
			(layers "B.Cu" "B.Mask" "B.Paste")
			(roundrect_rratio 0.15)
			(net 13 "VCC")
			(pinfunction "SENSE")
			(pintype "input")
		)
	)
	(footprint "antmicro-footprints:C_0402_1005Metric"
		(layer "B.Cu")
		(at 113.92 70.61)
		(descr "Capacitor SMD 0402")
		(tags "capacitor SMD 0402")
		(property "Reference" "C16"
			(at -0.82 0.69 0)
			(layer "B.SilkS")
			(effects
				(font
					(size 0.7 0.7)
					(thickness 0.15)
				)
				(justify right top mirror)
			)
		)
		(property "Value" "C_10u_0402"
			(at -1.022927 -2.155213 0)
			(layer "B.Fab")
			(effects
				(font
					(size 0.7 0.7)
					(thickness 0.15)
				)
				(justify right top mirror)
			)
		)
		(property "Datasheet" "https://www.yageo.com/en/Chart/Download/pdf/CC0402MRX5R5BB106"
			(at 0 0 0)
			(layer "B.Fab")
			(hide yes)
			(effects
				(font
					(size 1.27 1.27)
					(thickness 0.15)
				)
				(justify mirror)
			)
		)
		(property "Description" "SMD Multilayer Ceramic Capacitor, 10 µF, 6.3 V, 0402 [1005 Metric], ± 20%, X5R, CC Series"
			(at 0 0 0)
			(layer "B.Fab")
			(hide yes)
			(effects
				(font
					(size 1.27 1.27)
					(thickness 0.15)
				)
				(justify mirror)
			)
		)
		(property "MPN" "CC0402MRX5R5BB106"
			(at 0 0 0)
			(unlocked yes)
			(layer "B.Fab")
			(hide yes)
			(effects
				(font
					(size 1 1)
					(thickness 0.15)
				)
				(justify mirror)
			)
		)
		(property "Manufacturer" "YAGEO"
			(at 0 0 0)
			(unlocked yes)
			(layer "B.Fab")
			(hide yes)
			(effects
				(font
					(size 1 1)
					(thickness 0.15)
				)
				(justify mirror)
			)
		)
		(property "License" "Apache-2.0"
			(at 0 0 0)
			(unlocked yes)
			(layer "B.Fab")
			(hide yes)
			(effects
				(font
					(size 1 1)
					(thickness 0.15)
				)
				(justify mirror)
			)
		)
		(property "Author" "Antmicro"
			(at 0 0 0)
			(unlocked yes)
			(layer "B.Fab")
			(hide yes)
			(effects
				(font
					(size 1 1)
					(thickness 0.15)
				)
				(justify mirror)
			)
		)
		(property "Val" "10u"
			(at 0 0 0)
			(unlocked yes)
			(layer "B.Fab")
			(hide yes)
			(effects
				(font
					(size 1 1)
					(thickness 0.15)
				)
				(justify mirror)
			)
		)
		(property "Voltage" ""
			(at 0 0 0)
			(unlocked yes)
			(layer "B.Fab")
			(hide yes)
			(effects
				(font
					(size 1 1)
					(thickness 0.15)
				)
				(justify mirror)
			)
		)
		(property "Dielectric" "template_dielectric"
			(at 0 0 0)
			(unlocked yes)
			(layer "B.Fab")
			(hide yes)
			(effects
				(font
					(size 1 1)
					(thickness 0.15)
				)
				(justify mirror)
			)
		)
		(sheetname "/SoM_Power/")
		(sheetfile "som_power.kicad_sch")
		(attr smd)
		(fp_rect
			(start -0.925 0.47)
			(end 0.925 -0.47)
			(stroke
				(width 0.05)
				(type default)
			)
			(fill no)
			(layer "B.CrtYd")
		)
		(fp_line
			(start -0.494 -0.248)
			(end -0.494 0.25)
			(stroke
				(width 0.15)
				(type solid)
			)
			(layer "B.Fab")
		)
		(fp_line
			(start -0.494 0.25)
			(end 0.504 0.25)
			(stroke
				(width 0.15)
				(type solid)
			)
			(layer "B.Fab")
		)
		(fp_line
			(start 0.504 -0.248)
			(end -0.494 -0.248)
			(stroke
				(width 0.15)
				(type solid)
			)
			(layer "B.Fab")
		)
		(fp_line
			(start 0.504 0.25)
			(end 0.504 -0.248)
			(stroke
				(width 0.15)
				(type solid)
			)
			(layer "B.Fab")
		)
		(fp_text user "License: Apache-2.0"
			(at -0.939 -5.799 0)
			(layer "B.Fab")
			(effects
				(font
					(size 0.7 0.7)
					(thickness 0.15)
				)
				(justify right top mirror)
			)
		)
		(fp_text user "${REFERENCE}"
			(at -0.939 -4.599 0)
			(layer "B.Fab")
			(effects
				(font
					(size 0.7 0.7)
					(thickness 0.15)
				)
				(justify right top mirror)
			)
		)
		(fp_text user "Author: Antmicro"
			(at -0.939 -3.399 0)
			(layer "B.Fab")
			(effects
				(font
					(size 0.7 0.7)
					(thickness 0.15)
				)
				(justify right top mirror)
			)
		)
		(pad "1" smd roundrect
			(at -0.48 0)
			(size 0.59 0.64)
			(layers "B.Cu" "B.Mask" "B.Paste")
			(roundrect_rratio 0.25)
			(net 1 "GND")
			(pintype "passive")
		)
		(pad "2" smd roundrect
			(at 0.48 0)
			(size 0.59 0.64)
			(layers "B.Cu" "B.Mask" "B.Paste")
			(roundrect_rratio 0.25)
			(net 213 "+5V_SOM")
			(pintype "passive")
		)
	)
	(footprint "antmicro-footprints:R_0402_1005Metric"
		(layer "B.Cu")
		(at 187.8 121.7 90)
		(descr "Resistor SMD 0402")
		(tags "resistor SMD 0402")
		(property "Reference" "R386"
			(at -3.7 -0.4 90)
			(layer "B.SilkS")
			(effects
				(font
					(size 0.7 0.7)
					(thickness 0.15)
				)
				(justify right top mirror)
			)
		)
		(property "Value" "R_0R_0402"
			(at -1.011843 -1.772047 90)
			(layer "B.Fab")
			(effects
				(font
					(size 0.7 0.7)
					(thickness 0.15)
				)
				(justify right top mirror)
			)
		)
		(property "Datasheet" "https://industrial.panasonic.com/cdbs/www-data/pdf/RDA0000/AOA0000C301.pdf"
			(at 0 0 90)
			(layer "B.Fab")
			(hide yes)
			(effects
				(font
					(size 1.27 1.27)
					(thickness 0.15)
				)
				(justify mirror)
			)
		)
		(property "Description" "SMD Chip Resistor, Jumper, 0 ohm, 100 mW, 0402 [1005 Metric], Thick Film, General Purpose"
			(at 0 0 90)
			(layer "B.Fab")
			(hide yes)
			(effects
				(font
					(size 1.27 1.27)
					(thickness 0.15)
				)
				(justify mirror)
			)
		)
		(property "MPN" "ERJ2GE0R00X"
			(at 0 0 270)
			(unlocked yes)
			(layer "B.Fab")
			(hide yes)
			(effects
				(font
					(size 1 1)
					(thickness 0.15)
				)
				(justify mirror)
			)
		)
		(property "Manufacturer" "Panasonic"
			(at 0 0 270)
			(unlocked yes)
			(layer "B.Fab")
			(hide yes)
			(effects
				(font
					(size 1 1)
					(thickness 0.15)
				)
				(justify mirror)
			)
		)
		(property "License" "Apache-2.0"
			(at 0 0 270)
			(unlocked yes)
			(layer "B.Fab")
			(hide yes)
			(effects
				(font
					(size 1 1)
					(thickness 0.15)
				)
				(justify mirror)
			)
		)
		(property "Author" "Antmicro"
			(at 0 0 270)
			(unlocked yes)
			(layer "B.Fab")
			(hide yes)
			(effects
				(font
					(size 1 1)
					(thickness 0.15)
				)
				(justify mirror)
			)
		)
		(property "Val" "0R"
			(at 0 0 270)
			(unlocked yes)
			(layer "B.Fab")
			(hide yes)
			(effects
				(font
					(size 1 1)
					(thickness 0.15)
				)
				(justify mirror)
			)
		)
		(property "Tolerance" "~"
			(at 0 0 270)
			(unlocked yes)
			(layer "B.Fab")
			(hide yes)
			(effects
				(font
					(size 1 1)
					(thickness 0.15)
				)
				(justify mirror)
			)
		)
		(property "Current" "1A"
			(at 0 0 270)
			(unlocked yes)
			(layer "B.Fab")
			(hide yes)
			(effects
				(font
					(size 1 1)
					(thickness 0.15)
				)
				(justify mirror)
			)
		)
		(sheetname "/USB Debug, PD/")
		(sheetfile "usb_debug_pd.kicad_sch")
		(attr smd exclude_from_pos_files exclude_from_bom dnp)
		(fp_rect
			(start -0.925 0.47)
			(end 0.925 -0.47)
			(stroke
				(width 0.05)
				(type default)
			)
			(fill no)
			(layer "B.CrtYd")
		)
		(fp_rect
			(start -0.5 0.25)
			(end 0.5 -0.25)
			(stroke
				(width 0.15)
				(type solid)
			)
			(fill no)
			(layer "B.Fab")
		)
		(fp_text user "Author: Antmicro"
			(at -0.95 -4.169 90)
			(layer "B.Fab")
			(effects
				(font
					(size 0.7 0.7)
					(thickness 0.15)
				)
				(justify right top mirror)
			)
		)
		(fp_text user "${REFERENCE}"
			(at -0.95 -3.168 90)
			(layer "B.Fab")
			(effects
				(font
					(size 0.7 0.7)
					(thickness 0.15)
				)
				(justify right top mirror)
			)
		)
		(fp_text user "License: Apache-2.0"
			(at -0.95 -5.169 90)
			(layer "B.Fab")
			(effects
				(font
					(size 0.7 0.7)
					(thickness 0.15)
				)
				(justify right top mirror)
			)
		)
		(pad "1" smd roundrect
			(at -0.48 0 90)
			(size 0.59 0.64)
			(layers "B.Cu" "B.Mask" "B.Paste")
			(roundrect_rratio 0.25)
			(net 810 "/USB Debug, PD/MISO")
			(pintype "passive")
		)
		(pad "2" smd roundrect
			(at 0.48 0 90)
			(size 0.59 0.64)
			(layers "B.Cu" "B.Mask" "B.Paste")
			(roundrect_rratio 0.25)
			(net 923 "/USB Debug, PD/SPI_{HUB_DEBUG}.MISO")
			(pintype "passive")
		)
	)
	(footprint "antmicro-footprints:R_0402_1005Metric"
		(layer "B.Cu")
		(at 71.1 64.3)
		(descr "Resistor SMD 0402")
		(tags "resistor SMD 0402")
		(property "Reference" "R398"
			(at 0.9 -0.3 0)
			(layer "B.SilkS")
			(effects
				(font
					(size 0.7 0.7)
					(thickness 0.15)
				)
				(justify right top mirror)
			)
		)
		(property "Value" "R_0R_0402"
			(at -1.011843 -1.772047 0)
			(layer "B.Fab")
			(effects
				(font
					(size 0.7 0.7)
					(thickness 0.15)
				)
				(justify right top mirror)
			)
		)
		(property "Datasheet" "https://industrial.panasonic.com/cdbs/www-data/pdf/RDA0000/AOA0000C301.pdf"
			(at 0 0 0)
			(layer "B.Fab")
			(hide yes)
			(effects
				(font
					(size 1.27 1.27)
					(thickness 0.15)
				)
				(justify mirror)
			)
		)
		(property "Description" "SMD Chip Resistor, Jumper, 0 ohm, 100 mW, 0402 [1005 Metric], Thick Film, General Purpose"
			(at 0 0 0)
			(layer "B.Fab")
			(hide yes)
			(effects
				(font
					(size 1.27 1.27)
					(thickness 0.15)
				)
				(justify mirror)
			)
		)
		(property "MPN" "ERJ2GE0R00X"
			(at 0 0 180)
			(unlocked yes)
			(layer "B.Fab")
			(hide yes)
			(effects
				(font
					(size 1 1)
					(thickness 0.15)
				)
				(justify mirror)
			)
		)
		(property "Manufacturer" "Panasonic"
			(at 0 0 180)
			(unlocked yes)
			(layer "B.Fab")
			(hide yes)
			(effects
				(font
					(size 1 1)
					(thickness 0.15)
				)
				(justify mirror)
			)
		)
		(property "License" "Apache-2.0"
			(at 0 0 180)
			(unlocked yes)
			(layer "B.Fab")
			(hide yes)
			(effects
				(font
					(size 1 1)
					(thickness 0.15)
				)
				(justify mirror)
			)
		)
		(property "Author" "Antmicro"
			(at 0 0 180)
			(unlocked yes)
			(layer "B.Fab")
			(hide yes)
			(effects
				(font
					(size 1 1)
					(thickness 0.15)
				)
				(justify mirror)
			)
		)
		(property "Val" "0R"
			(at 0 0 180)
			(unlocked yes)
			(layer "B.Fab")
			(hide yes)
			(effects
				(font
					(size 1 1)
					(thickness 0.15)
				)
				(justify mirror)
			)
		)
		(property "Tolerance" "~"
			(at 0 0 180)
			(unlocked yes)
			(layer "B.Fab")
			(hide yes)
			(effects
				(font
					(size 1 1)
					(thickness 0.15)
				)
				(justify mirror)
			)
		)
		(property "Current" "1A"
			(at 0 0 180)
			(unlocked yes)
			(layer "B.Fab")
			(hide yes)
			(effects
				(font
					(size 1 1)
					(thickness 0.15)
				)
				(justify mirror)
			)
		)
		(sheetname "/CSI/")
		(sheetfile "csi.kicad_sch")
		(attr smd)
		(fp_rect
			(start -0.925 0.47)
			(end 0.925 -0.47)
			(stroke
				(width 0.05)
				(type default)
			)
			(fill no)
			(layer "B.CrtYd")
		)
		(fp_rect
			(start -0.5 0.25)
			(end 0.5 -0.25)
			(stroke
				(width 0.15)
				(type solid)
			)
			(fill no)
			(layer "B.Fab")
		)
		(fp_text user "License: Apache-2.0"
			(at -0.95 -5.169 0)
			(layer "B.Fab")
			(effects
				(font
					(size 0.7 0.7)
					(thickness 0.15)
				)
				(justify right top mirror)
			)
		)
		(fp_text user "${REFERENCE}"
			(at -0.95 -3.168 0)
			(layer "B.Fab")
			(effects
				(font
					(size 0.7 0.7)
					(thickness 0.15)
				)
				(justify right top mirror)
			)
		)
		(fp_text user "Author: Antmicro"
			(at -0.95 -4.169 0)
			(layer "B.Fab")
			(effects
				(font
					(size 0.7 0.7)
					(thickness 0.15)
				)
				(justify right top mirror)
			)
		)
		(pad "1" smd roundrect
			(at -0.48 0)
			(size 0.59 0.64)
			(layers "B.Cu" "B.Mask" "B.Paste")
			(roundrect_rratio 0.25)
			(net 992 "/CSI/SCL_CAM3")
			(pintype "passive")
		)
		(pad "2" smd roundrect
			(at 0.48 0)
			(size 0.59 0.64)
			(layers "B.Cu" "B.Mask" "B.Paste")
			(roundrect_rratio 0.25)
			(net 938 "Net-(J10-Pad42)")
			(pintype "passive")
		)
	)
	(footprint "antmicro-footprints:R_0402_1005Metric"
		(layer "B.Cu")
		(at 207 66.95 180)
		(descr "Resistor SMD 0402")
		(tags "resistor SMD 0402")
		(property "Reference" "R174"
			(at 1.069 -0.304 0)
			(layer "B.SilkS")
			(effects
				(font
					(size 0.7 0.7)
					(thickness 0.15)
				)
				(justify left bottom mirror)
			)
		)
		(property "Value" "R_10k_0402"
			(at -1.011843 -1.772046 0)
			(layer "B.Fab")
			(effects
				(font
					(size 0.7 0.7)
					(thickness 0.15)
				)
				(justify left bottom mirror)
			)
		)
		(property "Datasheet" "https://www.bourns.com/docs/product-datasheets/cr.pdf"
			(at 0 0 0)
			(layer "B.Fab")
			(hide yes)
			(effects
				(font
					(size 1.27 1.27)
					(thickness 0.15)
				)
				(justify mirror)
			)
		)
		(property "Description" "SMD Chip Resistor, 10 kohm, ± 1%, 62.5 mW, 0402 [1005 Metric], Thick Film, General Purpose"
			(at 0 0 0)
			(layer "B.Fab")
			(hide yes)
			(effects
				(font
					(size 1.27 1.27)
					(thickness 0.15)
				)
				(justify mirror)
			)
		)
		(property "Manufacturer" "Bourns"
			(at 0 0 0)
			(unlocked yes)
			(layer "B.Fab")
			(hide yes)
			(effects
				(font
					(size 1 1)
					(thickness 0.15)
				)
				(justify mirror)
			)
		)
		(property "MPN" "CR0402-FX-1002GLF"
			(at 0 0 0)
			(unlocked yes)
			(layer "B.Fab")
			(hide yes)
			(effects
				(font
					(size 1 1)
					(thickness 0.15)
				)
				(justify mirror)
			)
		)
		(property "Val" "10k"
			(at 0 0 0)
			(unlocked yes)
			(layer "B.Fab")
			(hide yes)
			(effects
				(font
					(size 1 1)
					(thickness 0.15)
				)
				(justify mirror)
			)
		)
		(property "License" "Apache-2.0"
			(at 0 0 0)
			(unlocked yes)
			(layer "B.Fab")
			(hide yes)
			(effects
				(font
					(size 1 1)
					(thickness 0.15)
				)
				(justify mirror)
			)
		)
		(property "Author" "Antmicro"
			(at 0 0 0)
			(unlocked yes)
			(layer "B.Fab")
			(hide yes)
			(effects
				(font
					(size 1 1)
					(thickness 0.15)
				)
				(justify mirror)
			)
		)
		(property "Tolerance" "1%"
			(at 0 0 0)
			(unlocked yes)
			(layer "B.Fab")
			(hide yes)
			(effects
				(font
					(size 1 1)
					(thickness 0.15)
				)
				(justify mirror)
			)
		)
		(sheetname "/CSI/")
		(sheetfile "csi.kicad_sch")
		(attr smd exclude_from_pos_files exclude_from_bom dnp)
		(fp_poly
			(pts
				(xy -0.925 0.47) (xy -0.925 -0.47) (xy 0.925 -0.47) (xy 0.925 0.47)
			)
			(stroke
				(width 0.05)
				(type default)
			)
			(fill no)
			(layer "B.CrtYd")
		)
		(fp_poly
			(pts
				(xy -0.5 0.25) (xy -0.5 -0.25) (xy 0.5 -0.25) (xy 0.5 0.25)
			)
			(stroke
				(width 0.15)
				(type solid)
			)
			(fill no)
			(layer "B.Fab")
		)
		(fp_text user "${REFERENCE}"
			(at -0.95 -3.168 0)
			(layer "B.Fab")
			(effects
				(font
					(size 0.7 0.7)
					(thickness 0.15)
				)
				(justify left bottom mirror)
			)
		)
		(fp_text user "Author: Antmicro"
			(at -0.95 -4.169 0)
			(layer "B.Fab")
			(effects
				(font
					(size 0.7 0.7)
					(thickness 0.15)
				)
				(justify left bottom mirror)
			)
		)
		(fp_text user "License: Apache-2.0"
			(at -0.949999 -5.169 0)
			(layer "B.Fab")
			(effects
				(font
					(size 0.7 0.7)
					(thickness 0.15)
				)
				(justify left bottom mirror)
			)
		)
		(pad "1" smd roundrect
			(at -0.48 0 180)
			(size 0.59 0.64)
			(layers "B.Cu" "B.Mask" "B.Paste")
			(roundrect_rratio 0.25)
			(net 123 "/CSI/CAM_CTRL.CSIB_PEN")
			(pintype "passive")
		)
		(pad "2" smd roundrect
			(at 0.48 0 180)
			(size 0.59 0.64)
			(layers "B.Cu" "B.Mask" "B.Paste")
			(roundrect_rratio 0.25)
			(net 2 "+3V3")
			(pintype "passive")
		)
	)
	(footprint "antmicro-footprints:TP_SMD_0.75mm"
		(layer "B.Cu")
		(at 63 74.8 -90)
		(property "Reference" "TP110"
			(at -0.7 -1.5 270)
			(layer "B.SilkS")
			(effects
				(font
					(size 0.7 0.7)
					(thickness 0.15)
				)
				(justify left bottom mirror)
			)
		)
		(property "Value" "TP_0.75mm_SMD"
			(at 0 -1.2 90)
			(layer "B.Fab")
			(effects
				(font
					(size 0.7 0.7)
					(thickness 0.15)
				)
				(justify left bottom mirror)
			)
		)
		(property "Description" "SMT test point"
			(at 0 0 90)
			(layer "B.Fab")
			(hide yes)
			(effects
				(font
					(size 1.27 1.27)
					(thickness 0.15)
				)
				(justify mirror)
			)
		)
		(property "MPN" ""
			(at 0 0 90)
			(unlocked yes)
			(layer "B.Fab")
			(hide yes)
			(effects
				(font
					(size 1 1)
					(thickness 0.15)
				)
				(justify mirror)
			)
		)
		(property "Manufacturer" ""
			(at 0 0 90)
			(unlocked yes)
			(layer "B.Fab")
			(hide yes)
			(effects
				(font
					(size 1 1)
					(thickness 0.15)
				)
				(justify mirror)
			)
		)
		(property "Author" "Antmicro"
			(at 0 0 90)
			(unlocked yes)
			(layer "B.Fab")
			(hide yes)
			(effects
				(font
					(size 1 1)
					(thickness 0.15)
				)
				(justify mirror)
			)
		)
		(property "License" "Apache-2.0"
			(at 0 0 90)
			(unlocked yes)
			(layer "B.Fab")
			(hide yes)
			(effects
				(font
					(size 1 1)
					(thickness 0.15)
				)
				(justify mirror)
			)
		)
		(sheetname "/Expansion connector/")
		(sheetfile "expansion_connector.kicad_sch")
		(attr exclude_from_pos_files exclude_from_bom)
		(fp_circle
			(center 0 0)
			(end 0.475 0)
			(stroke
				(width 0.05)
				(type default)
			)
			(fill no)
			(layer "B.CrtYd")
		)
		(fp_text user "${REFERENCE}"
			(at -0.4 -2.7 90)
			(layer "B.Fab")
			(effects
				(font
					(size 0.7 0.7)
					(thickness 0.15)
				)
				(justify left bottom mirror)
			)
		)
		(fp_text user "License: Apache-2.0"
			(at -0.4 -5.101 90)
			(layer "B.Fab")
			(effects
				(font
					(size 0.7 0.7)
					(thickness 0.15)
				)
				(justify left bottom mirror)
			)
		)
		(fp_text user "Author: Antmicro"
			(at -0.4 -3.901 90)
			(layer "B.Fab")
			(effects
				(font
					(size 0.7 0.7)
					(thickness 0.15)
				)
				(justify left bottom mirror)
			)
		)
		(pad "1" smd circle
			(at 0 0 270)
			(size 0.75 0.75)
			(layers "B.Cu" "B.Mask")
			(net 753 "Net-(J18-PadK01)")
			(pinfunction "1")
			(pintype "passive")
		)
	)
	(footprint "antmicro-footprints:C_0402_1005Metric"
		(layer "B.Cu")
		(at 235.694 109.85)
		(descr "Capacitor SMD 0402")
		(tags "capacitor SMD 0402")
		(property "Reference" "C114"
			(at -2.894 3.55 0)
			(layer "B.SilkS")
			(effects
				(font
					(size 0.7 0.7)
					(thickness 0.15)
				)
				(justify right top mirror)
			)
		)
		(property "Value" "C_100n_0402"
			(at -1.022927 -2.155213 0)
			(layer "B.Fab")
			(effects
				(font
					(size 0.7 0.7)
					(thickness 0.15)
				)
				(justify right top mirror)
			)
		)
		(property "Datasheet" "https://www.murata.com/products/productdetail?partno=GRM155R61H104KE14%23"
			(at 0 0 0)
			(layer "B.Fab")
			(hide yes)
			(effects
				(font
					(size 1.27 1.27)
					(thickness 0.15)
				)
				(justify mirror)
			)
		)
		(property "Description" "SMD Multilayer Ceramic Capacitor, 0.1 µF, 50 V, 0402 [1005 Metric], ± 10%, X5R, GRM Series"
			(at 0 0 0)
			(layer "B.Fab")
			(hide yes)
			(effects
				(font
					(size 1.27 1.27)
					(thickness 0.15)
				)
				(justify mirror)
			)
		)
		(property "Manufacturer" "Murata"
			(at 0 0 180)
			(unlocked yes)
			(layer "B.Fab")
			(hide yes)
			(effects
				(font
					(size 1 1)
					(thickness 0.15)
				)
				(justify mirror)
			)
		)
		(property "MPN" "GRM155R61H104KE14D"
			(at 0 0 180)
			(unlocked yes)
			(layer "B.Fab")
			(hide yes)
			(effects
				(font
					(size 1 1)
					(thickness 0.15)
				)
				(justify mirror)
			)
		)
		(property "Val" "100n"
			(at 0 0 180)
			(unlocked yes)
			(layer "B.Fab")
			(hide yes)
			(effects
				(font
					(size 1 1)
					(thickness 0.15)
				)
				(justify mirror)
			)
		)
		(property "License" "Apache-2.0"
			(at 0 0 180)
			(unlocked yes)
			(layer "B.Fab")
			(hide yes)
			(effects
				(font
					(size 1 1)
					(thickness 0.15)
				)
				(justify mirror)
			)
		)
		(property "Author" "Antmicro"
			(at 0 0 180)
			(unlocked yes)
			(layer "B.Fab")
			(hide yes)
			(effects
				(font
					(size 1 1)
					(thickness 0.15)
				)
				(justify mirror)
			)
		)
		(property "Voltage" "50V"
			(at 0 0 180)
			(unlocked yes)
			(layer "B.Fab")
			(hide yes)
			(effects
				(font
					(size 1 1)
					(thickness 0.15)
				)
				(justify mirror)
			)
		)
		(property "Dielectric" "X5R"
			(at 0 0 180)
			(unlocked yes)
			(layer "B.Fab")
			(hide yes)
			(effects
				(font
					(size 1 1)
					(thickness 0.15)
				)
				(justify mirror)
			)
		)
		(sheetname "/Recovery USB/")
		(sheetfile "recovery_usb.kicad_sch")
		(attr smd)
		(fp_poly
			(pts
				(xy -0.925 0.47) (xy -0.925 -0.47) (xy 0.925 -0.47) (xy 0.925 0.47)
			)
			(stroke
				(width 0.05)
				(type default)
			)
			(fill no)
			(layer "B.CrtYd")
		)
		(fp_line
			(start -0.494 -0.248)
			(end -0.494 0.25)
			(stroke
				(width 0.15)
				(type solid)
			)
			(layer "B.Fab")
		)
		(fp_line
			(start -0.494 0.25)
			(end 0.504 0.25)
			(stroke
				(width 0.15)
				(type solid)
			)
			(layer "B.Fab")
		)
		(fp_line
			(start 0.504 -0.248)
			(end -0.494 -0.248)
			(stroke
				(width 0.15)
				(type solid)
			)
			(layer "B.Fab")
		)
		(fp_line
			(start 0.504 0.25)
			(end 0.504 -0.248)
			(stroke
				(width 0.15)
				(type solid)
			)
			(layer "B.Fab")
		)
		(fp_text user "${REFERENCE}"
			(at -0.939 -4.599 0)
			(layer "B.Fab")
			(effects
				(font
					(size 0.7 0.7)
					(thickness 0.15)
				)
				(justify right top mirror)
			)
		)
		(fp_text user "License: Apache-2.0"
			(at -0.939 -5.799 0)
			(layer "B.Fab")
			(effects
				(font
					(size 0.7 0.7)
					(thickness 0.15)
				)
				(justify right top mirror)
			)
		)
		(fp_text user "Author: Antmicro"
			(at -0.939 -3.399 0)
			(layer "B.Fab")
			(effects
				(font
					(size 0.7 0.7)
					(thickness 0.15)
				)
				(justify right top mirror)
			)
		)
		(pad "1" smd roundrect
			(at -0.48 0)
			(size 0.59 0.64)
			(layers "B.Cu" "B.Mask" "B.Paste")
			(roundrect_rratio 0.25)
			(net 5 "+5V")
			(pintype "passive")
		)
		(pad "2" smd roundrect
			(at 0.48 0)
			(size 0.59 0.64)
			(layers "B.Cu" "B.Mask" "B.Paste")
			(roundrect_rratio 0.25)
			(net 1 "GND")
			(pintype "passive")
		)
	)
	(footprint "antmicro-footprints:LED_0603_1608Metric_G"
		(layer "B.Cu")
		(at 225.98 56.26 180)
		(descr "LED SMD 0603 Green")
		(tags "LED SMD 0603 Green")
		(property "Reference" "D27"
			(at -3.52 -0.44 0)
			(layer "B.SilkS")
			(effects
				(font
					(size 0.7 0.7)
					(thickness 0.15)
				)
				(justify left bottom mirror)
			)
		)
		(property "Value" "LED_G_0603_LTST-C190GKT"
			(at -0.001 -1.599 0)
			(layer "B.Fab")
			(effects
				(font
					(size 0.7 0.7)
					(thickness 0.15)
				)
				(justify left bottom mirror)
			)
		)
		(property "Datasheet" "https://media.digikey.com/pdf/Data%20Sheets/Lite-On%20PDFs/LTST-C190GKT.pdf"
			(at 0 0 0)
			(layer "B.Fab")
			(hide yes)
			(effects
				(font
					(size 1.27 1.27)
					(thickness 0.15)
				)
				(justify mirror)
			)
		)
		(property "Description" "LED, Green, SMD, 0603, 20 mA, 2.1 V, 569 nm"
			(at 0 0 0)
			(layer "B.Fab")
			(hide yes)
			(effects
				(font
					(size 1.27 1.27)
					(thickness 0.15)
				)
				(justify mirror)
			)
		)
		(property "MPN" "LTST-C190GKT"
			(at 0 0 0)
			(unlocked yes)
			(layer "B.Fab")
			(hide yes)
			(effects
				(font
					(size 1 1)
					(thickness 0.15)
				)
				(justify mirror)
			)
		)
		(property "Manufacturer" "Lite-On"
			(at 0 0 0)
			(unlocked yes)
			(layer "B.Fab")
			(hide yes)
			(effects
				(font
					(size 1 1)
					(thickness 0.15)
				)
				(justify mirror)
			)
		)
		(property "Author" "Antmicro"
			(at 0 0 0)
			(unlocked yes)
			(layer "B.Fab")
			(hide yes)
			(effects
				(font
					(size 1 1)
					(thickness 0.15)
				)
				(justify mirror)
			)
		)
		(property "License" "Apache-2.0"
			(at 0 0 0)
			(unlocked yes)
			(layer "B.Fab")
			(hide yes)
			(effects
				(font
					(size 1 1)
					(thickness 0.15)
				)
				(justify mirror)
			)
		)
		(property "Color" "Green"
			(at 0 0 0)
			(unlocked yes)
			(layer "B.Fab")
			(hide yes)
			(effects
				(font
					(size 1 1)
					(thickness 0.15)
				)
				(justify mirror)
			)
		)
		(sheetname "/CSI/")
		(sheetfile "csi.kicad_sch")
		(attr smd)
		(fp_line
			(start 0.22 0.35)
			(end -0.22 0.35)
			(stroke
				(width 0.15)
				(type solid)
			)
			(layer "B.SilkS")
		)
		(fp_line
			(start 0.22 -0.35)
			(end -0.22 -0.35)
			(stroke
				(width 0.15)
				(type solid)
			)
			(layer "B.SilkS")
		)
		(fp_line
			(start 0.105328 -0.001008)
			(end 0.240001 -0.001)
			(stroke
				(width 0.1)
				(type solid)
			)
			(layer "B.SilkS")
		)
		(fp_line
			(start 0.105328 -0.201008)
			(end 0.105329 0.198992)
			(stroke
				(width 0.1)
				(type solid)
			)
			(layer "B.SilkS")
		)
		(fp_line
			(start 0.105328 -0.201008)
			(end -0.094672 -0.001008)
			(stroke
				(width 0.1)
				(type solid)
			)
			(layer "B.SilkS")
		)
		(fp_line
			(start -0.094672 -0.001008)
			(end 0.105329 0.198992)
			(stroke
				(width 0.1)
				(type solid)
			)
			(layer "B.SilkS")
		)
		(fp_line
			(start -0.094672 -0.001008)
			(end -0.24 -0.001008)
			(stroke
				(width 0.1)
				(type solid)
			)
			(layer "B.SilkS")
		)
		(fp_line
			(start -0.094672 -0.201008)
			(end -0.094672 0.198992)
			(stroke
				(width 0.1)
				(type solid)
			)
			(layer "B.SilkS")
		)
		(fp_line
			(start -1.18 0.319)
			(end -1.18 -0.321)
			(stroke
				(width 0.15)
				(type solid)
			)
			(layer "B.SilkS")
		)
		(fp_poly
			(pts
				(xy 1.25 -0.65) (xy 1.25 0.65) (xy -1.25 0.65) (xy -1.25 -0.65)
			)
			(stroke
				(width 0.05)
				(type solid)
			)
			(fill no)
			(layer "B.CrtYd")
		)
		(fp_line
			(start 0.599 0)
			(end 0.200999 0)
			(stroke
				(width 0.15)
				(type solid)
			)
			(layer "B.Fab")
		)
		(fp_line
			(start 0.201 0.202)
			(end -0.101 0)
			(stroke
				(width 0.15)
				(type solid)
			)
			(layer "B.Fab")
		)
		(fp_line
			(start 0.201 -0.2)
			(end 0.200999 0)
			(stroke
				(width 0.15)
				(type solid)
			)
			(layer "B.Fab")
		)
		(fp_line
			(start 0.200999 0)
			(end 0.201 0.202)
			(stroke
				(width 0.15)
				(type solid)
			)
			(layer "B.Fab")
		)
		(fp_line
			(start -0.101 0)
			(end 0.201 -0.2)
			(stroke
				(width 0.15)
				(type solid)
			)
			(layer "B.Fab")
		)
		(fp_line
			(start -0.199 0.202)
			(end -0.199 -0.1)
			(stroke
				(width 0.15)
				(type solid)
			)
			(layer "B.Fab")
		)
		(fp_line
			(start -0.199 0)
			(end -0.597 0)
			(stroke
				(width 0.15)
				(type solid)
			)
			(layer "B.Fab")
		)
		(fp_line
			(start -0.199 -0.2)
			(end -0.199 -0.1)
			(stroke
				(width 0.15)
				(type solid)
			)
			(layer "B.Fab")
		)
		(fp_poly
			(pts
				(xy 0.848 -0.4) (xy 0.848 0.401999) (xy -0.85 0.402) (xy -0.85 -0.4)
			)
			(stroke
				(width 0.15)
				(type solid)
			)
			(fill no)
			(layer "B.Fab")
		)
		(fp_text user "License: Apache-2.0"
			(at -1.4224 -3.599 0)
			(layer "B.Fab")
			(effects
				(font
					(size 0.7 0.7)
					(thickness 0.15)
				)
				(justify left bottom mirror)
			)
		)
		(fp_text user "${REFERENCE}"
			(at -1.4224 -5.999 0)
			(layer "B.Fab")
			(effects
				(font
					(size 0.7 0.7)
					(thickness 0.15)
				)
				(justify left bottom mirror)
			)
		)
		(fp_text user "Author: Antmicro"
			(at -1.4224 -4.799 0)
			(layer "B.Fab")
			(effects
				(font
					(size 0.7 0.7)
					(thickness 0.15)
				)
				(justify left bottom mirror)
			)
		)
		(pad "1" smd roundrect
			(at -0.7 0)
			(size 0.8 1)
			(layers "B.Cu" "B.Mask" "B.Paste")
			(roundrect_rratio 0.2)
			(net 1 "GND")
			(pinfunction "C")
			(pintype "passive")
		)
		(pad "2" smd roundrect
			(at 0.7 0)
			(size 0.8 1)
			(layers "B.Cu" "B.Mask" "B.Paste")
			(roundrect_rratio 0.2)
			(net 540 "Net-(D27-A)")
			(pinfunction "A")
			(pintype "passive")
		)
	)
	(footprint "antmicro-footprints:SOT-523"
		(layer "B.Cu")
		(at 173.9 60.078004 -90)
		(property "Reference" "Q13"
			(at -1.078004 1.3 90)
			(layer "B.SilkS")
			(effects
				(font
					(size 0.7 0.7)
					(thickness 0.15)
				)
				(justify left bottom mirror)
			)
		)
		(property "Value" "DMG1012T-7"
			(at 0.1 -1.824 90)
			(layer "B.Fab")
			(effects
				(font
					(size 0.7 0.7)
					(thickness 0.15)
				)
				(justify left bottom mirror)
			)
		)
		(property "Datasheet" "https://www.diodes.com/assets/Datasheets/ds31783.pdf"
			(at 0 0 90)
			(layer "B.Fab")
			(hide yes)
			(effects
				(font
					(size 1.27 1.27)
					(thickness 0.15)
				)
				(justify mirror)
			)
		)
		(property "Description" "Power MOSFET, N Channel, 20 V, 630 mA, 0.3 ohm, SOT-523, Surface Mount"
			(at 0 0 90)
			(layer "B.Fab")
			(hide yes)
			(effects
				(font
					(size 1.27 1.27)
					(thickness 0.15)
				)
				(justify mirror)
			)
		)
		(property "MPN" "DMG1012T-7"
			(at 0 0 90)
			(unlocked yes)
			(layer "B.Fab")
			(hide yes)
			(effects
				(font
					(size 1 1)
					(thickness 0.15)
				)
				(justify mirror)
			)
		)
		(property "Manufacturer" "Diodes Incorporated"
			(at 0 0 90)
			(unlocked yes)
			(layer "B.Fab")
			(hide yes)
			(effects
				(font
					(size 1 1)
					(thickness 0.15)
				)
				(justify mirror)
			)
		)
		(property "Author" "Antmicro"
			(at 0 0 90)
			(unlocked yes)
			(layer "B.Fab")
			(hide yes)
			(effects
				(font
					(size 1 1)
					(thickness 0.15)
				)
				(justify mirror)
			)
		)
		(property "License" "Apache-2.0"
			(at 0 0 90)
			(unlocked yes)
			(layer "B.Fab")
			(hide yes)
			(effects
				(font
					(size 1 1)
					(thickness 0.15)
				)
				(justify mirror)
			)
		)
		(sheetname "/Peripherals/")
		(sheetfile "peripherals.kicad_sch")
		(attr smd)
		(fp_line
			(start -0.725 0.551)
			(end -0.277 0.551)
			(stroke
				(width 0.15)
				(type solid)
			)
			(layer "B.SilkS")
		)
		(fp_line
			(start -0.277 0.551)
			(end -0.277 0.75)
			(stroke
				(width 0.15)
				(type solid)
			)
			(layer "B.SilkS")
		)
		(fp_line
			(start -0.927 0.351)
			(end -0.725 0.551)
			(stroke
				(width 0.15)
				(type solid)
			)
			(layer "B.SilkS")
		)
		(fp_line
			(start -0.927 0.051)
			(end -0.927 0.351)
			(stroke
				(width 0.15)
				(type solid)
			)
			(layer "B.SilkS")
		)
		(fp_circle
			(center -0.9652 -0.9652)
			(end -0.9152 -0.9652)
			(stroke
				(width 0.15)
				(type solid)
			)
			(fill yes)
			(layer "B.SilkS")
		)
		(fp_line
			(start -1.12 1.16)
			(end 1.1 1.16)
			(stroke
				(width 0.05)
				(type solid)
			)
			(layer "B.CrtYd")
		)
		(fp_line
			(start -1.12 1.16)
			(end -1.12 -1.15)
			(stroke
				(width 0.05)
				(type solid)
			)
			(layer "B.CrtYd")
		)
		(fp_line
			(start 1.1 1.16)
			(end 1.1 -1.15)
			(stroke
				(width 0.05)
				(type solid)
			)
			(layer "B.CrtYd")
		)
		(fp_line
			(start -1.12 -1.15)
			(end 1.1 -1.15)
			(stroke
				(width 0.05)
				(type solid)
			)
			(layer "B.CrtYd")
		)
		(fp_line
			(start -0.652 0.425)
			(end -0.802 0.276)
			(stroke
				(width 0.15)
				(type solid)
			)
			(layer "B.Fab")
		)
		(fp_line
			(start 0.8 0.425)
			(end -0.652 0.425)
			(stroke
				(width 0.15)
				(type solid)
			)
			(layer "B.Fab")
		)
		(fp_line
			(start 0.8 0.425)
			(end 0.8 -0.424)
			(stroke
				(width 0.15)
				(type solid)
			)
			(layer "B.Fab")
		)
		(fp_line
			(start -0.802 0.276)
			(end -0.802 -0.424)
			(stroke
				(width 0.15)
				(type solid)
			)
			(layer "B.Fab")
		)
		(fp_line
			(start 0.8 -0.424)
			(end -0.802 -0.424)
			(stroke
				(width 0.15)
				(type solid)
			)
			(layer "B.Fab")
		)
		(fp_circle
			(center -0.9652 -0.9652)
			(end -0.9144 -0.9652)
			(stroke
				(width 0.15)
				(type solid)
			)
			(fill no)
			(layer "B.Fab")
		)
		(fp_text user "License: Apache-2.0"
			(at -1.12 -5.024 90)
			(layer "B.Fab")
			(effects
				(font
					(size 0.7 0.7)
					(thickness 0.15)
				)
				(justify left bottom mirror)
			)
		)
		(fp_text user "Author: Antmicro"
			(at -1.12 -6.224 90)
			(layer "B.Fab")
			(effects
				(font
					(size 0.7 0.7)
					(thickness 0.15)
				)
				(justify left bottom mirror)
			)
		)
		(fp_text user "${REFERENCE}"
			(at -1.12 -3.824 90)
			(layer "B.Fab")
			(effects
				(font
					(size 0.7 0.7)
					(thickness 0.15)
				)
				(justify left bottom mirror)
			)
		)
		(pad "1" smd rect
			(at -0.5 -0.65 270)
			(size 0.4 0.51)
			(layers "B.Cu" "B.Mask" "B.Paste")
			(net 487 "/Expansion connector/GPIO.USER_LED0")
			(pinfunction "G")
			(pintype "input")
		)
		(pad "2" smd rect
			(at 0.498 -0.65 270)
			(size 0.4 0.51)
			(layers "B.Cu" "B.Mask" "B.Paste")
			(net 1 "GND")
			(pinfunction "S")
			(pintype "passive")
		)
		(pad "3" smd rect
			(at 0 0.652 270)
			(size 0.4 0.51)
			(layers "B.Cu" "B.Mask" "B.Paste")
			(net 37 "Net-(D35-C)")
			(pinfunction "D")
			(pintype "passive")
		)
	)
	(footprint "antmicro-footprints:SOD-523"
		(layer "B.Cu")
		(at 216.02 113.56 90)
		(property "Reference" "D58"
			(at -1.14 -1.52 90)
			(layer "B.SilkS")
			(effects
				(font
					(size 0.7 0.7)
					(thickness 0.15)
				)
				(justify right top mirror)
			)
		)
		(property "Value" "RB521S30T1G"
			(at 0 -1.499 90)
			(layer "B.Fab")
			(effects
				(font
					(size 0.7 0.7)
					(thickness 0.15)
				)
				(justify right top mirror)
			)
		)
		(property "Datasheet" "https://www.onsemi.com/pdf/datasheet/rb521s30t1-d.pdf"
			(at 0 0 90)
			(layer "B.Fab")
			(hide yes)
			(effects
				(font
					(size 1.27 1.27)
					(thickness 0.15)
				)
				(justify mirror)
			)
		)
		(property "Description" "Small Signal Schottky Diode, Single, 30 V, 200 mA, 500 mV, 1 A, 125 °C"
			(at 0 0 90)
			(layer "B.Fab")
			(hide yes)
			(effects
				(font
					(size 1.27 1.27)
					(thickness 0.15)
				)
				(justify mirror)
			)
		)
		(property "MPN" "RB521S30T1G"
			(at 0 0 270)
			(unlocked yes)
			(layer "B.Fab")
			(hide yes)
			(effects
				(font
					(size 1 1)
					(thickness 0.15)
				)
				(justify mirror)
			)
		)
		(property "Manufacturer" "ON Semiconductor"
			(at 0 0 270)
			(unlocked yes)
			(layer "B.Fab")
			(hide yes)
			(effects
				(font
					(size 1 1)
					(thickness 0.15)
				)
				(justify mirror)
			)
		)
		(property "Author" "Antmicro"
			(at 0 0 270)
			(unlocked yes)
			(layer "B.Fab")
			(hide yes)
			(effects
				(font
					(size 1 1)
					(thickness 0.15)
				)
				(justify mirror)
			)
		)
		(property "License" "Apache-2.0"
			(at 0 0 270)
			(unlocked yes)
			(layer "B.Fab")
			(hide yes)
			(effects
				(font
					(size 1 1)
					(thickness 0.15)
				)
				(justify mirror)
			)
		)
		(sheetname "/USB Hub/")
		(sheetfile "usb_hub.kicad_sch")
		(attr smd)
		(fp_line
			(start -0.35 0.5)
			(end -0.35 -0.5)
			(stroke
				(width 0.15)
				(type solid)
			)
			(layer "B.SilkS")
		)
		(fp_rect
			(start -1 0.6)
			(end 1 -0.6)
			(stroke
				(width 0.05)
				(type solid)
			)
			(fill no)
			(layer "B.CrtYd")
		)
		(fp_line
			(start -0.652 -0.423)
			(end 0.65 -0.423)
			(stroke
				(width 0.15)
				(type solid)
			)
			(layer "B.Fab")
		)
		(fp_line
			(start -0.652 -0.423)
			(end -0.652 0.425)
			(stroke
				(width 0.15)
				(type solid)
			)
			(layer "B.Fab")
		)
		(fp_line
			(start -0.35 0.4)
			(end -0.35 -0.4)
			(stroke
				(width 0.15)
				(type solid)
			)
			(layer "B.Fab")
		)
		(fp_line
			(start 0.65 0.425)
			(end 0.65 -0.423)
			(stroke
				(width 0.15)
				(type solid)
			)
			(layer "B.Fab")
		)
		(fp_line
			(start -0.652 0.425)
			(end 0.65 0.425)
			(stroke
				(width 0.15)
				(type solid)
			)
			(layer "B.Fab")
		)
		(fp_text user "Author: Antmicro"
			(at -1.276 -4.7 90)
			(layer "B.Fab")
			(effects
				(font
					(size 0.7 0.7)
					(thickness 0.15)
				)
				(justify right top mirror)
			)
		)
		(fp_text user "License: Apache-2.0"
			(at -1.276 -5.9 90)
			(layer "B.Fab")
			(effects
				(font
					(size 0.7 0.7)
					(thickness 0.15)
				)
				(justify right top mirror)
			)
		)
		(fp_text user "${REFERENCE}"
			(at -1.276 -3.499 90)
			(layer "B.Fab")
			(effects
				(font
					(size 0.7 0.7)
					(thickness 0.15)
				)
				(justify right top mirror)
			)
		)
		(pad "1" smd roundrect
			(at -0.701 0 90)
			(size 0.5 0.6)
			(layers "B.Cu" "B.Mask" "B.Paste")
			(roundrect_rratio 0.25)
			(net 1237 "Net-(D58-C)")
			(pinfunction "C")
			(pintype "passive")
		)
		(pad "2" smd roundrect
			(at 0.699 0 90)
			(size 0.5 0.6)
			(layers "B.Cu" "B.Mask" "B.Paste")
			(roundrect_rratio 0.25)
			(net 1236 "Net-(D58-A)")
			(pinfunction "A")
			(pintype "passive")
		)
	)
	(footprint "antmicro-footprints:Spacer_Drill3.7mm_H8mm_9774080151R"
		(locked yes)
		(layer "B.Cu")
		(at 222.430532 143.71 -90)
		(descr "Spacer M=3 h=8mm fi=5.1mm")
		(property "Reference" "H4"
			(at 0 3.2 90)
			(layer "B.SilkS")
			(effects
				(font
					(size 0.7 0.7)
					(thickness 0.15)
				)
				(justify left bottom mirror)
			)
		)
		(property "Value" "Spacer_Drill3.7mm_H8mm_9774080151R"
			(at 0 -4 90)
			(layer "B.Fab")
			(effects
				(font
					(size 0.7 0.7)
					(thickness 0.15)
				)
				(justify left bottom mirror)
			)
		)
		(property "Datasheet" "https://www.we-online.com/components/products/datasheet/9774080151R.pdf"
			(at 0 0 90)
			(layer "B.Fab")
			(hide yes)
			(effects
				(font
					(size 1.27 1.27)
					(thickness 0.15)
				)
				(justify mirror)
			)
		)
		(property "Description" "Spacer, SMT, Non Stop, Steel, Swage Round, 5.1 mm x 8 mm, M2.5 Thread, WA-SMSI Series"
			(at 0 0 90)
			(layer "B.Fab")
			(hide yes)
			(effects
				(font
					(size 1.27 1.27)
					(thickness 0.15)
				)
				(justify mirror)
			)
		)
		(property "Manufacturer" "Würth Elektronik"
			(at 0 0 270)
			(unlocked yes)
			(layer "B.Fab")
			(hide yes)
			(effects
				(font
					(size 1 1)
					(thickness 0.15)
				)
				(justify mirror)
			)
		)
		(property "MPN" "9774080151R"
			(at 0 0 270)
			(unlocked yes)
			(layer "B.Fab")
			(hide yes)
			(effects
				(font
					(size 1 1)
					(thickness 0.15)
				)
				(justify mirror)
			)
		)
		(property "Author" "Antmicro"
			(at 0 0 270)
			(unlocked yes)
			(layer "B.Fab")
			(hide yes)
			(effects
				(font
					(size 1 1)
					(thickness 0.15)
				)
				(justify mirror)
			)
		)
		(property "License" "Apache-2.0"
			(at 0 0 270)
			(unlocked yes)
			(layer "B.Fab")
			(hide yes)
			(effects
				(font
					(size 1 1)
					(thickness 0.15)
				)
				(justify mirror)
			)
		)
		(sheetname "/")
		(sheetfile "jetson-agx-thor-baseboard.kicad_sch")
		(solder_paste_margin_ratio -1)
		(attr smd)
		(fp_circle
			(center 0 0)
			(end 3.05 0)
			(stroke
				(width 0.05)
				(type solid)
			)
			(fill no)
			(layer "B.CrtYd")
		)
		(fp_circle
			(center 0 0)
			(end 2.6 0)
			(stroke
				(width 0.15)
				(type solid)
			)
			(fill no)
			(layer "B.Fab")
		)
		(fp_text user "${REFERENCE}"
			(at -9.6 -6.5 90)
			(layer "B.Fab")
			(effects
				(font
					(size 0.7 0.7)
					(thickness 0.15)
				)
				(justify left bottom mirror)
			)
		)
		(fp_text user "License: Apache-2.0"
			(at -9.6 -8.9 90)
			(layer "B.Fab")
			(effects
				(font
					(size 0.7 0.7)
					(thickness 0.15)
				)
				(justify left bottom mirror)
			)
		)
		(fp_text user "Author: Antmicro"
			(at -9.6 -7.7 90)
			(layer "B.Fab")
			(effects
				(font
					(size 0.7 0.7)
					(thickness 0.15)
				)
				(justify left bottom mirror)
			)
		)
		(pad "" smd custom
			(at -1.7 -1.7 180)
			(size 0.62 0.62)
			(layers "B.Paste")
			(thermal_bridge_angle 90)
			(options
				(clearance outline)
				(anchor circle)
			)
			(primitives
				(gr_arc
					(start 1.266786 0.24747)
					(mid 0.285453 -0.29439)
					(end -0.250195 -1.279127)
					(width 0.2)
				)
				(gr_arc
					(start 1.259603 0.339191)
					(mid 0.218448 -0.232561)
					(end -0.34334 -1.279127)
					(width 0.2)
				)
				(gr_arc
					(start 1.255279 0.431435)
					(mid 0.152481 -0.169693)
					(end -0.436309 -1.279127)
					(width 0.2)
				)
				(gr_arc
					(start 1.253811 0.524161)
					(mid 0.087542 -0.105784)
					(end -0.529126 -1.279127)
					(width 0.2)
				)
				(gr_arc
					(start 1.275473 0.621136)
					(mid 0.0309 -0.033527)
					(end -0.621807 -1.279127)
					(width 0.2)
				)
				(gr_arc
					(start 1.263664 0.711602)
					(mid -0.037759 0.026651)
					(end -0.71437 -1.279127)
					(width 0.2)
				)
				(gr_arc
					(start 1.253435 0.802342)
					(mid -0.105837 0.087395)
					(end -0.806826 -1.279127)
					(width 0.2)
				)
				(gr_arc
					(start 1.267475 0.897258)
					(mid -0.165236 0.156885)
					(end -0.899187 -1.279127)
					(width 0.2)
				)
				(gr_arc
					(start 1.270645 0.990112)
					(mid -0.228522 0.222449)
					(end -0.991463 -1.279127)
					(width 0.2)
				)
				(gr_arc
					(start 1.266278 1.081674)
					(mid -0.294507 0.285313)
					(end -1.083663 -1.279127)
					(width 0.2)
				)
				(gr_line
					(start 1.279127 0.250195)
					(end 1.279127 1.083663)
					(width 0.2)
				)
				(gr_line
					(start -0.250195 -1.279127)
					(end -1.083663 -1.279127)
					(width 0.2)
				)
			)
		)
		(pad "" smd custom
			(at -1.7 1.7 270)
			(size 0.62 0.62)
			(layers "B.Paste")
			(thermal_bridge_angle 90)
			(options
				(clearance outline)
				(anchor circle)
			)
			(primitives
				(gr_arc
					(start 1.266786 0.24747)
					(mid 0.285453 -0.29439)
					(end -0.250195 -1.279127)
					(width 0.2)
				)
				(gr_arc
					(start 1.259603 0.339191)
					(mid 0.218448 -0.232561)
					(end -0.34334 -1.279127)
					(width 0.2)
				)
				(gr_arc
					(start 1.255279 0.431435)
					(mid 0.152481 -0.169693)
					(end -0.436309 -1.279127)
					(width 0.2)
				)
				(gr_arc
					(start 1.253811 0.524161)
					(mid 0.087542 -0.105784)
					(end -0.529126 -1.279127)
					(width 0.2)
				)
				(gr_arc
					(start 1.275473 0.621136)
					(mid 0.0309 -0.033527)
					(end -0.621807 -1.279127)
					(width 0.2)
				)
				(gr_arc
					(start 1.263664 0.711602)
					(mid -0.037759 0.026651)
					(end -0.71437 -1.279127)
					(width 0.2)
				)
				(gr_arc
					(start 1.253435 0.802342)
					(mid -0.105837 0.087395)
					(end -0.806826 -1.279127)
					(width 0.2)
				)
				(gr_arc
					(start 1.267475 0.897258)
					(mid -0.165236 0.156885)
					(end -0.899187 -1.279127)
					(width 0.2)
				)
				(gr_arc
					(start 1.270645 0.990112)
					(mid -0.228522 0.222449)
					(end -0.991463 -1.279127)
					(width 0.2)
				)
				(gr_arc
					(start 1.266278 1.081674)
					(mid -0.294507 0.285313)
					(end -1.083663 -1.279127)
					(width 0.2)
				)
				(gr_line
					(start 1.279127 0.250195)
					(end 1.279127 1.083663)
					(width 0.2)
				)
				(gr_line
					(start -0.250195 -1.279127)
					(end -1.083663 -1.279127)
					(width 0.2)
				)
			)
		)
		(pad "" smd custom
			(at 1.7 -1.7 90)
			(size 0.62 0.62)
			(layers "B.Paste")
			(thermal_bridge_angle 90)
			(options
				(clearance outline)
				(anchor circle)
			)
			(primitives
				(gr_arc
					(start 1.266786 0.24747)
					(mid 0.285453 -0.29439)
					(end -0.250195 -1.279127)
					(width 0.2)
				)
				(gr_arc
					(start 1.259603 0.339191)
					(mid 0.218448 -0.232561)
					(end -0.34334 -1.279127)
					(width 0.2)
				)
				(gr_arc
					(start 1.255279 0.431435)
					(mid 0.152481 -0.169693)
					(end -0.436309 -1.279127)
					(width 0.2)
				)
				(gr_arc
					(start 1.253811 0.524161)
					(mid 0.087542 -0.105784)
					(end -0.529126 -1.279127)
					(width 0.2)
				)
				(gr_arc
					(start 1.275473 0.621136)
					(mid 0.0309 -0.033527)
					(end -0.621807 -1.279127)
					(width 0.2)
				)
				(gr_arc
					(start 1.263664 0.711602)
					(mid -0.037759 0.026651)
					(end -0.71437 -1.279127)
					(width 0.2)
				)
				(gr_arc
					(start 1.253435 0.802342)
					(mid -0.105837 0.087395)
					(end -0.806826 -1.279127)
					(width 0.2)
				)
				(gr_arc
					(start 1.267475 0.897258)
					(mid -0.165236 0.156885)
					(end -0.899187 -1.279127)
					(width 0.2)
				)
				(gr_arc
					(start 1.270645 0.990112)
					(mid -0.228522 0.222449)
					(end -0.991463 -1.279127)
					(width 0.2)
				)
				(gr_arc
					(start 1.266278 1.081674)
					(mid -0.294507 0.285313)
					(end -1.083663 -1.279127)
					(width 0.2)
				)
				(gr_line
					(start 1.279127 0.250195)
					(end 1.279127 1.083663)
					(width 0.2)
				)
				(gr_line
					(start -0.250195 -1.279127)
					(end -1.083663 -1.279127)
					(width 0.2)
				)
			)
		)
		(pad "" smd custom
			(at 1.7 1.7)
			(size 0.62 0.62)
			(layers "B.Paste")
			(thermal_bridge_angle 90)
			(options
				(clearance outline)
				(anchor circle)
			)
			(primitives
				(gr_arc
					(start 1.266786 0.24747)
					(mid 0.285453 -0.29439)
					(end -0.250195 -1.279127)
					(width 0.2)
				)
				(gr_arc
					(start 1.259603 0.339191)
					(mid 0.218448 -0.232561)
					(end -0.34334 -1.279127)
					(width 0.2)
				)
				(gr_arc
					(start 1.255279 0.431435)
					(mid 0.152481 -0.169693)
					(end -0.436309 -1.279127)
					(width 0.2)
				)
				(gr_arc
					(start 1.253811 0.524161)
					(mid 0.087542 -0.105784)
					(end -0.529126 -1.279127)
					(width 0.2)
				)
				(gr_arc
					(start 1.275473 0.621136)
					(mid 0.0309 -0.033527)
					(end -0.621807 -1.279127)
					(width 0.2)
				)
				(gr_arc
					(start 1.263664 0.711602)
					(mid -0.037759 0.026651)
					(end -0.71437 -1.279127)
					(width 0.2)
				)
				(gr_arc
					(start 1.253435 0.802342)
					(mid -0.105837 0.087395)
					(end -0.806826 -1.279127)
					(width 0.2)
				)
				(gr_arc
					(start 1.267475 0.897258)
					(mid -0.165236 0.156885)
					(end -0.899187 -1.279127)
					(width 0.2)
				)
				(gr_arc
					(start 1.270645 0.990112)
					(mid -0.228522 0.222449)
					(end -0.991463 -1.279127)
					(width 0.2)
				)
				(gr_arc
					(start 1.266278 1.081674)
					(mid -0.294507 0.285313)
					(end -1.083663 -1.279127)
					(width 0.2)
				)
				(gr_line
					(start 1.279127 0.250195)
					(end 1.279127 1.083663)
					(width 0.2)
				)
				(gr_line
					(start -0.250195 -1.279127)
					(end -1.083663 -1.279127)
					(width 0.2)
				)
			)
		)
		(pad "1" thru_hole circle
			(at 0 0 270)
			(size 6 6)
			(drill 3.7)
			(layers "*.Cu" "*.Mask")
			(remove_unused_layers no)
			(net 1 "GND")
			(pintype "passive")
		)
	)
	(footprint "antmicro-footprints:TP_SMD_0.75mm"
		(layer "B.Cu")
		(at 206.066532 147.62 -90)
		(property "Reference" "TP30"
			(at 0.48 0.740532 0)
			(layer "B.SilkS")
			(effects
				(font
					(size 0.7 0.7)
					(thickness 0.15)
				)
				(justify left bottom mirror)
			)
		)
		(property "Value" "TP_0.75mm_SMD"
			(at 0 -1.2 90)
			(layer "B.Fab")
			(effects
				(font
					(size 0.7 0.7)
					(thickness 0.15)
				)
				(justify left bottom mirror)
			)
		)
		(property "Description" "SMT test point"
			(at 0 0 90)
			(layer "B.Fab")
			(hide yes)
			(effects
				(font
					(size 1.27 1.27)
					(thickness 0.15)
				)
				(justify mirror)
			)
		)
		(property "MPN" ""
			(at 0 0 90)
			(unlocked yes)
			(layer "B.Fab")
			(hide yes)
			(effects
				(font
					(size 1 1)
					(thickness 0.15)
				)
				(justify mirror)
			)
		)
		(property "Manufacturer" ""
			(at 0 0 90)
			(unlocked yes)
			(layer "B.Fab")
			(hide yes)
			(effects
				(font
					(size 1 1)
					(thickness 0.15)
				)
				(justify mirror)
			)
		)
		(property "Author" "Antmicro"
			(at 0 0 90)
			(unlocked yes)
			(layer "B.Fab")
			(hide yes)
			(effects
				(font
					(size 1 1)
					(thickness 0.15)
				)
				(justify mirror)
			)
		)
		(property "License" "Apache-2.0"
			(at 0 0 90)
			(unlocked yes)
			(layer "B.Fab")
			(hide yes)
			(effects
				(font
					(size 1 1)
					(thickness 0.15)
				)
				(justify mirror)
			)
		)
		(sheetname "/SFP/")
		(sheetfile "sfp.kicad_sch")
		(attr exclude_from_pos_files exclude_from_bom)
		(fp_circle
			(center 0 0)
			(end 0.475 0)
			(stroke
				(width 0.05)
				(type default)
			)
			(fill no)
			(layer "B.CrtYd")
		)
		(fp_text user "Author: Antmicro"
			(at -0.4 -3.901 90)
			(layer "B.Fab")
			(effects
				(font
					(size 0.7 0.7)
					(thickness 0.15)
				)
				(justify left bottom mirror)
			)
		)
		(fp_text user "${REFERENCE}"
			(at -0.4 -2.7 90)
			(layer "B.Fab")
			(effects
				(font
					(size 0.7 0.7)
					(thickness 0.15)
				)
				(justify left bottom mirror)
			)
		)
		(fp_text user "License: Apache-2.0"
			(at -0.4 -5.101 90)
			(layer "B.Fab")
			(effects
				(font
					(size 0.7 0.7)
					(thickness 0.15)
				)
				(justify left bottom mirror)
			)
		)
		(pad "1" smd circle
			(at 0 0 270)
			(size 0.75 0.75)
			(layers "B.Cu" "B.Mask")
			(net 1371 "Net-(J12-TX_{FAULT})")
			(pinfunction "1")
			(pintype "passive")
		)
	)
	(footprint "antmicro-footprints:Fiducial_1mm_Mask3mm"
		(layer "B.Cu")
		(at 235.3 149.12 180)
		(descr "Circular Fiducial, 1.5mm bare copper, 3mm soldermask opening")
		(tags "fiducial")
		(property "Reference" "FD6"
			(at -0.95 1.66 0)
			(layer "B.SilkS")
			(effects
				(font
					(size 0.7 0.7)
					(thickness 0.15)
				)
				(justify left bottom mirror)
			)
		)
		(property "Value" "Fiducial_1mm_Mask3mm"
			(at 0 -2.603 0)
			(layer "B.Fab")
			(effects
				(font
					(size 0.7 0.7)
					(thickness 0.15)
				)
				(justify left bottom mirror)
			)
		)
		(property "Description" "Fiducial mask"
			(at 0 0 0)
			(layer "B.Fab")
			(hide yes)
			(effects
				(font
					(size 1.27 1.27)
					(thickness 0.15)
				)
				(justify mirror)
			)
		)
		(property "Author" "Antmicro"
			(at 0 0 0)
			(unlocked yes)
			(layer "B.Fab")
			(hide yes)
			(effects
				(font
					(size 1 1)
					(thickness 0.15)
				)
				(justify mirror)
			)
		)
		(property "License" "Apache-2.0"
			(at 0 0 0)
			(unlocked yes)
			(layer "B.Fab")
			(hide yes)
			(effects
				(font
					(size 1 1)
					(thickness 0.15)
				)
				(justify mirror)
			)
		)
		(sheetname "/")
		(sheetfile "jetson-agx-thor-baseboard.kicad_sch")
		(attr exclude_from_pos_files exclude_from_bom)
		(fp_circle
			(center 0 0)
			(end 1.5 0)
			(stroke
				(width 0.05)
				(type solid)
			)
			(fill no)
			(layer "B.CrtYd")
		)
		(fp_circle
			(center 0 0)
			(end 1.5 0)
			(stroke
				(width 0.15)
				(type solid)
			)
			(fill no)
			(layer "B.Fab")
		)
		(fp_text user "License: Apache-2.0"
			(at -1.25 -7.003 0)
			(layer "B.Fab")
			(effects
				(font
					(size 0.7 0.7)
					(thickness 0.15)
				)
				(justify left bottom mirror)
			)
		)
		(fp_text user "Author: Antmicro"
			(at -1.25 -5.803 0)
			(layer "B.Fab")
			(effects
				(font
					(size 0.7 0.7)
					(thickness 0.15)
				)
				(justify left bottom mirror)
			)
		)
		(fp_text user "${REFERENCE}"
			(at -1.25 -4.603 0)
			(layer "B.Fab")
			(effects
				(font
					(size 0.7 0.7)
					(thickness 0.15)
				)
				(justify left bottom mirror)
			)
		)
		(pad "" smd circle
			(at 0 0 180)
			(size 1 1)
			(layers "B.Cu" "B.Mask")
			(solder_mask_margin 1)
			(clearance 1)
		)
	)
	(footprint "antmicro-footprints:R_0402_1005Metric"
		(layer "B.Cu")
		(at 193.7 84.1)
		(descr "Resistor SMD 0402")
		(tags "resistor SMD 0402")
		(property "Reference" "R98"
			(at -1.225 -1.454 0)
			(layer "B.SilkS")
			(effects
				(font
					(size 0.7 0.7)
					(thickness 0.15)
				)
				(justify right top mirror)
			)
		)
		(property "Value" "R_10k_0402"
			(at -1.011843 -1.772046 0)
			(layer "B.Fab")
			(effects
				(font
					(size 0.7 0.7)
					(thickness 0.15)
				)
				(justify right top mirror)
			)
		)
		(property "Datasheet" "https://www.bourns.com/docs/product-datasheets/cr.pdf"
			(at 0 0 0)
			(layer "B.Fab")
			(hide yes)
			(effects
				(font
					(size 1.27 1.27)
					(thickness 0.15)
				)
				(justify mirror)
			)
		)
		(property "Description" "SMD Chip Resistor, 10 kohm, ± 1%, 62.5 mW, 0402 [1005 Metric], Thick Film, General Purpose"
			(at 0 0 0)
			(layer "B.Fab")
			(hide yes)
			(effects
				(font
					(size 1.27 1.27)
					(thickness 0.15)
				)
				(justify mirror)
			)
		)
		(property "MPN" "CR0402-FX-1002GLF"
			(at 0 0 180)
			(unlocked yes)
			(layer "B.Fab")
			(hide yes)
			(effects
				(font
					(size 1 1)
					(thickness 0.15)
				)
				(justify mirror)
			)
		)
		(property "Manufacturer" "Bourns"
			(at 0 0 180)
			(unlocked yes)
			(layer "B.Fab")
			(hide yes)
			(effects
				(font
					(size 1 1)
					(thickness 0.15)
				)
				(justify mirror)
			)
		)
		(property "License" "Apache-2.0"
			(at 0 0 180)
			(unlocked yes)
			(layer "B.Fab")
			(hide yes)
			(effects
				(font
					(size 1 1)
					(thickness 0.15)
				)
				(justify mirror)
			)
		)
		(property "Author" "Antmicro"
			(at 0 0 180)
			(unlocked yes)
			(layer "B.Fab")
			(hide yes)
			(effects
				(font
					(size 1 1)
					(thickness 0.15)
				)
				(justify mirror)
			)
		)
		(property "Val" "10k"
			(at 0 0 180)
			(unlocked yes)
			(layer "B.Fab")
			(hide yes)
			(effects
				(font
					(size 1 1)
					(thickness 0.15)
				)
				(justify mirror)
			)
		)
		(property "Tolerance" "1%"
			(at 0 0 180)
			(unlocked yes)
			(layer "B.Fab")
			(hide yes)
			(effects
				(font
					(size 1 1)
					(thickness 0.15)
				)
				(justify mirror)
			)
		)
		(sheetname "/USB Debug, PD/")
		(sheetfile "usb_debug_pd.kicad_sch")
		(attr smd)
		(fp_poly
			(pts
				(xy -0.925 0.47) (xy -0.925 -0.47) (xy 0.925 -0.47) (xy 0.925 0.47)
			)
			(stroke
				(width 0.05)
				(type default)
			)
			(fill no)
			(layer "B.CrtYd")
		)
		(fp_poly
			(pts
				(xy -0.5 0.25) (xy -0.5 -0.25) (xy 0.5 -0.25) (xy 0.5 0.25)
			)
			(stroke
				(width 0.15)
				(type solid)
			)
			(fill no)
			(layer "B.Fab")
		)
		(fp_text user "Author: Antmicro"
			(at -0.95 -4.169 0)
			(layer "B.Fab")
			(effects
				(font
					(size 0.7 0.7)
					(thickness 0.15)
				)
				(justify right top mirror)
			)
		)
		(fp_text user "${REFERENCE}"
			(at -0.95 -3.168 0)
			(layer "B.Fab")
			(effects
				(font
					(size 0.7 0.7)
					(thickness 0.15)
				)
				(justify right top mirror)
			)
		)
		(fp_text user "License: Apache-2.0"
			(at -0.949999 -5.169 0)
			(layer "B.Fab")
			(effects
				(font
					(size 0.7 0.7)
					(thickness 0.15)
				)
				(justify right top mirror)
			)
		)
		(pad "1" smd roundrect
			(at -0.48 0)
			(size 0.59 0.64)
			(layers "B.Cu" "B.Mask" "B.Paste")
			(roundrect_rratio 0.25)
			(net 936 "/USB Debug, PD/PDC_MISO")
			(pintype "passive")
		)
		(pad "2" smd roundrect
			(at 0.48 0)
			(size 0.59 0.64)
			(layers "B.Cu" "B.Mask" "B.Paste")
			(roundrect_rratio 0.25)
			(net 271 "FLASH_PWR")
			(pintype "passive")
		)
	)
	(footprint "antmicro-footprints:SOT-23-6"
		(layer "B.Cu")
		(at 179.25 86.75 90)
		(property "Reference" "U63"
			(at -0.45 -2.65 90)
			(layer "B.SilkS")
			(effects
				(font
					(size 0.7 0.7)
					(thickness 0.15)
				)
				(justify right top mirror)
			)
		)
		(property "Value" "LTC4412IS6"
			(at -1.75 -2.693 90)
			(layer "B.Fab")
			(effects
				(font
					(size 0.7 0.7)
					(thickness 0.15)
				)
				(justify right top mirror)
			)
		)
		(property "Datasheet" "https://www.analog.com/media/en/technical-documentation/data-sheets/4412fb.pdf"
			(at 0 0.057 90)
			(layer "B.Fab")
			(hide yes)
			(effects
				(font
					(size 1.27 1.27)
					(thickness 0.15)
				)
				(justify mirror)
			)
		)
		(property "Description" "Ideal diode controller"
			(at 0 0.057 90)
			(layer "B.Fab")
			(hide yes)
			(effects
				(font
					(size 1.27 1.27)
					(thickness 0.15)
				)
				(justify mirror)
			)
		)
		(property "MPN" "LTC4412IS6#TRMPBF"
			(at 0 0 270)
			(unlocked yes)
			(layer "B.Fab")
			(hide yes)
			(effects
				(font
					(size 1 1)
					(thickness 0.15)
				)
				(justify mirror)
			)
		)
		(property "Manufacturer" "Analog Devices"
			(at 0 0 270)
			(unlocked yes)
			(layer "B.Fab")
			(hide yes)
			(effects
				(font
					(size 1 1)
					(thickness 0.15)
				)
				(justify mirror)
			)
		)
		(property "Author" "Antmicro"
			(at 0 0 270)
			(unlocked yes)
			(layer "B.Fab")
			(hide yes)
			(effects
				(font
					(size 1 1)
					(thickness 0.15)
				)
				(justify mirror)
			)
		)
		(property "License" "Apache-2.0"
			(at 0 0 270)
			(unlocked yes)
			(layer "B.Fab")
			(hide yes)
			(effects
				(font
					(size 1 1)
					(thickness 0.15)
				)
				(justify mirror)
			)
		)
		(sheetname "/Power/")
		(sheetfile "power.kicad_sch")
		(attr smd)
		(fp_line
			(start 1.45 -0.643)
			(end 1.45 -0.343)
			(stroke
				(width 0.12)
				(type solid)
			)
			(layer "B.SilkS")
		)
		(fp_line
			(start 1.3 -0.643)
			(end 1.45 -0.643)
			(stroke
				(width 0.12)
				(type solid)
			)
			(layer "B.SilkS")
		)
		(fp_line
			(start -1.45 -0.643)
			(end -1.45 -0.343)
			(stroke
				(width 0.12)
				(type solid)
			)
			(layer "B.SilkS")
		)
		(fp_line
			(start 1.45 0.757)
			(end 1.45 0.457)
			(stroke
				(width 0.12)
				(type solid)
			)
			(layer "B.SilkS")
		)
		(fp_line
			(start 1.3 0.757)
			(end 1.45 0.757)
			(stroke
				(width 0.12)
				(type solid)
			)
			(layer "B.SilkS")
		)
		(fp_line
			(start -1.3 0.757)
			(end -1.45 0.757)
			(stroke
				(width 0.12)
				(type solid)
			)
			(layer "B.SilkS")
		)
		(fp_line
			(start -1.45 0.757)
			(end -1.45 0.457)
			(stroke
				(width 0.12)
				(type solid)
			)
			(layer "B.SilkS")
		)
		(fp_rect
			(start -1.55 1.85)
			(end 1.55 -1.75)
			(stroke
				(width 0.05)
				(type solid)
			)
			(fill no)
			(layer "B.CrtYd")
		)
		(fp_line
			(start 1.5 -0.643)
			(end -1.5 -0.643)
			(stroke
				(width 0.1)
				(type solid)
			)
			(layer "B.Fab")
		)
		(fp_line
			(start -1.5 -0.643)
			(end -1.5 0.757)
			(stroke
				(width 0.1)
				(type solid)
			)
			(layer "B.Fab")
		)
		(fp_line
			(start 1.5 0.757)
			(end 1.5 -0.643)
			(stroke
				(width 0.1)
				(type solid)
			)
			(layer "B.Fab")
		)
		(fp_line
			(start -1.5 0.757)
			(end 1.5 0.757)
			(stroke
				(width 0.1)
				(type solid)
			)
			(layer "B.Fab")
		)
		(fp_text user "."
			(at -1.05 -2.65 90)
			(layer "B.SilkS")
			(effects
				(font
					(size 1 1)
					(thickness 0.15)
				)
				(justify mirror)
			)
		)
		(fp_text user "Author: Antmicro"
			(at -1.829 -5.25 90)
			(layer "B.Fab")
			(effects
				(font
					(size 0.7 0.7)
					(thickness 0.15)
				)
				(justify right top mirror)
			)
		)
		(fp_text user "${REFERENCE}"
			(at -1.75 -4 90)
			(layer "B.Fab")
			(effects
				(font
					(size 0.7 0.7)
					(thickness 0.15)
				)
				(justify right top mirror)
			)
		)
		(fp_text user "License: Apache-2.0"
			(at -1.75 -6.5 90)
			(layer "B.Fab")
			(effects
				(font
					(size 0.7 0.7)
					(thickness 0.15)
				)
				(justify right top mirror)
			)
		)
		(pad "1" smd roundrect
			(at -0.954 -1.1 90)
			(size 0.55 1)
			(layers "B.Cu" "B.Mask" "B.Paste")
			(roundrect_rratio 0.15)
			(net 904 "+20V")
			(pinfunction "IN")
			(pintype "power_in")
		)
		(pad "2" smd roundrect
			(at -0.003 -1.1 90)
			(size 0.55 1)
			(layers "B.Cu" "B.Mask" "B.Paste")
			(roundrect_rratio 0.15)
			(net 1 "GND")
			(pinfunction "GND")
			(pintype "power_in")
		)
		(pad "3" smd roundrect
			(at 0.947 -1.1 90)
			(size 0.55 1)
			(layers "B.Cu" "B.Mask" "B.Paste")
			(roundrect_rratio 0.15)
			(net 1 "GND")
			(pinfunction "CTL")
			(pintype "input")
		)
		(pad "4" smd roundrect
			(at 0.947 1.214 90)
			(size 0.55 1)
			(layers "B.Cu" "B.Mask" "B.Paste")
			(roundrect_rratio 0.15)
			(net 1226 "unconnected-(U63-STAT-Pad4)")
			(pinfunction "STAT")
			(pintype "output+no_connect")
		)
		(pad "5" smd roundrect
			(at -0.003 1.214 90)
			(size 0.55 1)
			(layers "B.Cu" "B.Mask" "B.Paste")
			(roundrect_rratio 0.15)
			(net 1202 "Net-(Q24-G)")
			(pinfunction "GATE")
			(pintype "output")
		)
		(pad "6" smd roundrect
			(at -0.954 1.214 90)
			(size 0.55 1)
			(layers "B.Cu" "B.Mask" "B.Paste")
			(roundrect_rratio 0.15)
			(net 522 "/Power/USBPD1_HV")
			(pinfunction "SENSE")
			(pintype "input")
		)
	)
	(footprint "antmicro-footprints:C_0402_1005Metric"
		(layer "B.Cu")
		(at 145.1 75.85 -90)
		(descr "Capacitor SMD 0402")
		(tags "capacitor SMD 0402")
		(property "Reference" "C359"
			(at -0.95 -1.6 90)
			(layer "B.SilkS")
			(effects
				(font
					(size 0.7 0.7)
					(thickness 0.15)
				)
				(justify left bottom mirror)
			)
		)
		(property "Value" "C_1u_25V_0402"
			(at -1.022927 -2.155213 90)
			(layer "B.Fab")
			(effects
				(font
					(size 0.7 0.7)
					(thickness 0.15)
				)
				(justify left bottom mirror)
			)
		)
		(property "Datasheet" "https://www.murata.com/products/productdetail?partno=GRM155R61E105KE11%23"
			(at 0 0 90)
			(layer "B.Fab")
			(hide yes)
			(effects
				(font
					(size 1.27 1.27)
					(thickness 0.15)
				)
				(justify mirror)
			)
		)
		(property "Description" "SMD Multilayer Ceramic Capacitor, 1 µF, 25 V, 0402 [1005 Metric], ± 10%, X5R, GRM Series"
			(at 0 0 90)
			(layer "B.Fab")
			(hide yes)
			(effects
				(font
					(size 1.27 1.27)
					(thickness 0.15)
				)
				(justify mirror)
			)
		)
		(property "MPN" "GRM155R61E105KE11J"
			(at 0 0 90)
			(unlocked yes)
			(layer "B.Fab")
			(hide yes)
			(effects
				(font
					(size 1 1)
					(thickness 0.15)
				)
				(justify mirror)
			)
		)
		(property "Manufacturer" "Murata"
			(at 0 0 90)
			(unlocked yes)
			(layer "B.Fab")
			(hide yes)
			(effects
				(font
					(size 1 1)
					(thickness 0.15)
				)
				(justify mirror)
			)
		)
		(property "License" "Apache-2.0"
			(at 0 0 90)
			(unlocked yes)
			(layer "B.Fab")
			(hide yes)
			(effects
				(font
					(size 1 1)
					(thickness 0.15)
				)
				(justify mirror)
			)
		)
		(property "Author" "Antmicro"
			(at 0 0 90)
			(unlocked yes)
			(layer "B.Fab")
			(hide yes)
			(effects
				(font
					(size 1 1)
					(thickness 0.15)
				)
				(justify mirror)
			)
		)
		(property "Val" "1u"
			(at 0 0 90)
			(unlocked yes)
			(layer "B.Fab")
			(hide yes)
			(effects
				(font
					(size 1 1)
					(thickness 0.15)
				)
				(justify mirror)
			)
		)
		(property "Voltage" "25V"
			(at 0 0 90)
			(unlocked yes)
			(layer "B.Fab")
			(hide yes)
			(effects
				(font
					(size 1 1)
					(thickness 0.15)
				)
				(justify mirror)
			)
		)
		(property "Dielectric" "X5R"
			(at 0 0 90)
			(unlocked yes)
			(layer "B.Fab")
			(hide yes)
			(effects
				(font
					(size 1 1)
					(thickness 0.15)
				)
				(justify mirror)
			)
		)
		(sheetname "/SoM_Power/")
		(sheetfile "som_power.kicad_sch")
		(attr smd)
		(fp_poly
			(pts
				(xy -0.925 0.47) (xy 0.925 0.47) (xy 0.925 -0.47) (xy -0.925 -0.47)
			)
			(stroke
				(width 0.05)
				(type default)
			)
			(fill no)
			(layer "B.CrtYd")
		)
		(fp_line
			(start -0.494 0.25)
			(end 0.504 0.25)
			(stroke
				(width 0.15)
				(type solid)
			)
			(layer "B.Fab")
		)
		(fp_line
			(start 0.504 0.25)
			(end 0.504 -0.248)
			(stroke
				(width 0.15)
				(type solid)
			)
			(layer "B.Fab")
		)
		(fp_line
			(start -0.494 -0.248)
			(end -0.494 0.25)
			(stroke
				(width 0.15)
				(type solid)
			)
			(layer "B.Fab")
		)
		(fp_line
			(start 0.504 -0.248)
			(end -0.494 -0.248)
			(stroke
				(width 0.15)
				(type solid)
			)
			(layer "B.Fab")
		)
		(fp_text user "Author: Antmicro"
			(at -0.939 -3.399 90)
			(layer "B.Fab")
			(effects
				(font
					(size 0.7 0.7)
					(thickness 0.15)
				)
				(justify left bottom mirror)
			)
		)
		(fp_text user "${REFERENCE}"
			(at -0.939 -4.599 90)
			(layer "B.Fab")
			(effects
				(font
					(size 0.7 0.7)
					(thickness 0.15)
				)
				(justify left bottom mirror)
			)
		)
		(fp_text user "License: Apache-2.0"
			(at -0.939 -5.799 90)
			(layer "B.Fab")
			(effects
				(font
					(size 0.7 0.7)
					(thickness 0.15)
				)
				(justify left bottom mirror)
			)
		)
		(pad "1" smd roundrect
			(at -0.48 0 270)
			(size 0.59 0.64)
			(layers "B.Cu" "B.Mask" "B.Paste")
			(roundrect_rratio 0.25)
			(net 1 "GND")
			(pintype "passive")
		)
		(pad "2" smd roundrect
			(at 0.48 0 270)
			(size 0.59 0.64)
			(layers "B.Cu" "B.Mask" "B.Paste")
			(roundrect_rratio 0.25)
			(net 12 "SYS_VIN_HV")
			(pintype "passive")
		)
	)
	(footprint "antmicro-footprints:SOT-563"
		(layer "B.Cu")
		(at 223.08 121.67 90)
		(property "Reference" "Q27"
			(at -0.648302 1.21 90)
			(layer "B.SilkS")
			(effects
				(font
					(size 0.7 0.7)
					(thickness 0.15)
				)
				(justify right top mirror)
			)
		)
		(property "Value" "DMC2400UV-7"
			(at 0 -2 90)
			(layer "B.Fab")
			(effects
				(font
					(size 0.7 0.7)
					(thickness 0.15)
				)
				(justify right top mirror)
			)
		)
		(property "Datasheet" "https://www.mouser.com/datasheet/2/115/DIOD_S_A0010038249_1-2543538.pdf"
			(at 0 0 90)
			(layer "B.Fab")
			(hide yes)
			(effects
				(font
					(size 1.27 1.27)
					(thickness 0.15)
				)
				(justify mirror)
			)
		)
		(property "Description" "Dual MOSFET, Complementary N and P Channel, 20 V, 20 V, 1.03 A, 1.03 A, 0.3 ohm"
			(at 0 0 90)
			(layer "B.Fab")
			(hide yes)
			(effects
				(font
					(size 1.27 1.27)
					(thickness 0.15)
				)
				(justify mirror)
			)
		)
		(property "MPN" "DMC2400UV-7"
			(at 0 0 270)
			(unlocked yes)
			(layer "B.Fab")
			(hide yes)
			(effects
				(font
					(size 1 1)
					(thickness 0.15)
				)
				(justify mirror)
			)
		)
		(property "Manufacturer" "Diodes Incorporated"
			(at 0 0 270)
			(unlocked yes)
			(layer "B.Fab")
			(hide yes)
			(effects
				(font
					(size 1 1)
					(thickness 0.15)
				)
				(justify mirror)
			)
		)
		(property "Author" "Antmicro"
			(at 0 0 270)
			(unlocked yes)
			(layer "B.Fab")
			(hide yes)
			(effects
				(font
					(size 1 1)
					(thickness 0.15)
				)
				(justify mirror)
			)
		)
		(property "License" "Apache-2.0"
			(at 0 0 270)
			(unlocked yes)
			(layer "B.Fab")
			(hide yes)
			(effects
				(font
					(size 1 1)
					(thickness 0.15)
				)
				(justify mirror)
			)
		)
		(sheetname "/USB Hub/")
		(sheetfile "usb_hub.kicad_sch")
		(attr smd)
		(fp_line
			(start 0.776 -0.972)
			(end 0.526 -0.972)
			(stroke
				(width 0.15)
				(type solid)
			)
			(layer "B.SilkS")
		)
		(fp_line
			(start -0.778 -0.949)
			(end -0.424 -0.949)
			(stroke
				(width 0.15)
				(type solid)
			)
			(layer "B.SilkS")
		)
		(fp_line
			(start 0.776 -0.776)
			(end 0.776 -0.972)
			(stroke
				(width 0.15)
				(type solid)
			)
			(layer "B.SilkS")
		)
		(fp_line
			(start -0.778 -0.776)
			(end -0.778 -0.949)
			(stroke
				(width 0.15)
				(type solid)
			)
			(layer "B.SilkS")
		)
		(fp_line
			(start 0.776 0.974)
			(end 0.776 0.778)
			(stroke
				(width 0.15)
				(type solid)
			)
			(layer "B.SilkS")
		)
		(fp_line
			(start 0.776 0.974)
			(end 0.526 0.974)
			(stroke
				(width 0.15)
				(type solid)
			)
			(layer "B.SilkS")
		)
		(fp_line
			(start -0.499 0.974)
			(end -0.724 0.778)
			(stroke
				(width 0.15)
				(type solid)
			)
			(layer "B.SilkS")
		)
		(fp_circle
			(center -0.903 0.999)
			(end -0.952 0.95)
			(stroke
				(width 0.15)
				(type solid)
			)
			(fill yes)
			(layer "B.SilkS")
		)
		(fp_rect
			(start 1.19 1.12)
			(end -1.2 -1.1)
			(stroke
				(width 0.05)
				(type solid)
			)
			(fill no)
			(layer "B.CrtYd")
		)
		(fp_line
			(start 0.651 -0.847)
			(end -0.653 -0.847)
			(stroke
				(width 0.15)
				(type solid)
			)
			(layer "B.Fab")
		)
		(fp_line
			(start -0.653 0.678)
			(end -0.653 -0.847)
			(stroke
				(width 0.15)
				(type solid)
			)
			(layer "B.Fab")
		)
		(fp_line
			(start 0.651 0.849)
			(end 0.651 -0.847)
			(stroke
				(width 0.15)
				(type solid)
			)
			(layer "B.Fab")
		)
		(fp_line
			(start -0.453 0.849)
			(end -0.653 0.678)
			(stroke
				(width 0.15)
				(type solid)
			)
			(layer "B.Fab")
		)
		(fp_line
			(start -0.453 0.849)
			(end 0.651 0.849)
			(stroke
				(width 0.15)
				(type solid)
			)
			(layer "B.Fab")
		)
		(fp_text user "Author: Antmicro"
			(at -1.299 -6.124 90)
			(layer "B.Fab")
			(effects
				(font
					(size 0.7 0.7)
					(thickness 0.15)
				)
				(justify right top mirror)
			)
		)
		(fp_text user "${REFERENCE}"
			(at -1.299 -7.323 90)
			(layer "B.Fab")
			(effects
				(font
					(size 0.7 0.7)
					(thickness 0.15)
				)
				(justify right top mirror)
			)
		)
		(fp_text user "License: Apache-2.0"
			(at -1.299 -4.924 90)
			(layer "B.Fab")
			(effects
				(font
					(size 0.7 0.7)
					(thickness 0.15)
				)
				(justify right top mirror)
			)
		)
		(pad "1" smd roundrect
			(at -0.749 0.499 180)
			(size 0.3 0.6)
			(layers "B.Cu" "B.Mask" "B.Paste")
			(roundrect_rratio 0.25)
			(net 1 "GND")
			(pinfunction "S1")
			(pintype "passive")
		)
		(pad "2" smd roundrect
			(at -0.749 -0.001 180)
			(size 0.3 0.6)
			(layers "B.Cu" "B.Mask" "B.Paste")
			(roundrect_rratio 0.25)
			(net 1084 "/USB Hub/DP1_VCONN1")
			(pinfunction "G1")
			(pintype "input")
		)
		(pad "3" smd roundrect
			(at -0.749 -0.497 180)
			(size 0.3 0.6)
			(layers "B.Cu" "B.Mask" "B.Paste")
			(roundrect_rratio 0.25)
			(net 1239 "Net-(D59-A)")
			(pinfunction "D2")
			(pintype "passive")
		)
		(pad "4" smd roundrect
			(at 0.747 -0.497 180)
			(size 0.3 0.6)
			(layers "B.Cu" "B.Mask" "B.Paste")
			(roundrect_rratio 0.25)
			(net 5 "+5V")
			(pinfunction "S2")
			(pintype "passive")
		)
		(pad "5" smd roundrect
			(at 0.747 -0.001 180)
			(size 0.3 0.6)
			(layers "B.Cu" "B.Mask" "B.Paste")
			(roundrect_rratio 0.25)
			(net 1332 "Net-(Q27-D1)")
			(pinfunction "G2")
			(pintype "input")
		)
		(pad "6" smd roundrect
			(at 0.747 0.499 180)
			(size 0.3 0.6)
			(layers "B.Cu" "B.Mask" "B.Paste")
			(roundrect_rratio 0.25)
			(net 1332 "Net-(Q27-D1)")
			(pinfunction "D1")
			(pintype "passive")
		)
	)
	(footprint "antmicro-footprints:C_0402_1005Metric"
		(layer "B.Cu")
		(at 207 65 180)
		(descr "Capacitor SMD 0402")
		(tags "capacitor SMD 0402")
		(property "Reference" "C158"
			(at 0.989001 -0.374 0)
			(layer "B.SilkS")
			(effects
				(font
					(size 0.7 0.7)
					(thickness 0.15)
				)
				(justify left bottom mirror)
			)
		)
		(property "Value" "C_100n_0402"
			(at -1.022927 -2.155213 0)
			(layer "B.Fab")
			(effects
				(font
					(size 0.7 0.7)
					(thickness 0.15)
				)
				(justify left bottom mirror)
			)
		)
		(property "Datasheet" "https://www.murata.com/products/productdetail?partno=GRM155R61H104KE14%23"
			(at 0 0 0)
			(layer "B.Fab")
			(hide yes)
			(effects
				(font
					(size 1.27 1.27)
					(thickness 0.15)
				)
				(justify mirror)
			)
		)
		(property "Description" "SMD Multilayer Ceramic Capacitor, 0.1 µF, 50 V, 0402 [1005 Metric], ± 10%, X5R, GRM Series"
			(at 0 0 0)
			(layer "B.Fab")
			(hide yes)
			(effects
				(font
					(size 1.27 1.27)
					(thickness 0.15)
				)
				(justify mirror)
			)
		)
		(property "Manufacturer" "Murata"
			(at 0 0 0)
			(unlocked yes)
			(layer "B.Fab")
			(hide yes)
			(effects
				(font
					(size 1 1)
					(thickness 0.15)
				)
				(justify mirror)
			)
		)
		(property "MPN" "GRM155R61H104KE14D"
			(at 0 0 0)
			(unlocked yes)
			(layer "B.Fab")
			(hide yes)
			(effects
				(font
					(size 1 1)
					(thickness 0.15)
				)
				(justify mirror)
			)
		)
		(property "Val" "100n"
			(at 0 0 0)
			(unlocked yes)
			(layer "B.Fab")
			(hide yes)
			(effects
				(font
					(size 1 1)
					(thickness 0.15)
				)
				(justify mirror)
			)
		)
		(property "License" "Apache-2.0"
			(at 0 0 0)
			(unlocked yes)
			(layer "B.Fab")
			(hide yes)
			(effects
				(font
					(size 1 1)
					(thickness 0.15)
				)
				(justify mirror)
			)
		)
		(property "Author" "Antmicro"
			(at 0 0 0)
			(unlocked yes)
			(layer "B.Fab")
			(hide yes)
			(effects
				(font
					(size 1 1)
					(thickness 0.15)
				)
				(justify mirror)
			)
		)
		(property "Voltage" "50V"
			(at 0 0 0)
			(unlocked yes)
			(layer "B.Fab")
			(hide yes)
			(effects
				(font
					(size 1 1)
					(thickness 0.15)
				)
				(justify mirror)
			)
		)
		(property "Dielectric" "X5R"
			(at 0 0 0)
			(unlocked yes)
			(layer "B.Fab")
			(hide yes)
			(effects
				(font
					(size 1 1)
					(thickness 0.15)
				)
				(justify mirror)
			)
		)
		(sheetname "/CSI/")
		(sheetfile "csi.kicad_sch")
		(attr smd)
		(fp_poly
			(pts
				(xy -0.925 0.47) (xy -0.925 -0.47) (xy 0.925 -0.47) (xy 0.925 0.47)
			)
			(stroke
				(width 0.05)
				(type default)
			)
			(fill no)
			(layer "B.CrtYd")
		)
		(fp_line
			(start 0.504 0.25)
			(end 0.504 -0.248)
			(stroke
				(width 0.15)
				(type solid)
			)
			(layer "B.Fab")
		)
		(fp_line
			(start 0.504 -0.248)
			(end -0.494 -0.248)
			(stroke
				(width 0.15)
				(type solid)
			)
			(layer "B.Fab")
		)
		(fp_line
			(start -0.494 0.25)
			(end 0.504 0.25)
			(stroke
				(width 0.15)
				(type solid)
			)
			(layer "B.Fab")
		)
		(fp_line
			(start -0.494 -0.248)
			(end -0.494 0.25)
			(stroke
				(width 0.15)
				(type solid)
			)
			(layer "B.Fab")
		)
		(fp_text user "Author: Antmicro"
			(at -0.939 -3.399 0)
			(layer "B.Fab")
			(effects
				(font
					(size 0.7 0.7)
					(thickness 0.15)
				)
				(justify left bottom mirror)
			)
		)
		(fp_text user "${REFERENCE}"
			(at -0.939 -4.599 0)
			(layer "B.Fab")
			(effects
				(font
					(size 0.7 0.7)
					(thickness 0.15)
				)
				(justify left bottom mirror)
			)
		)
		(fp_text user "License: Apache-2.0"
			(at -0.939 -5.799 0)
			(layer "B.Fab")
			(effects
				(font
					(size 0.7 0.7)
					(thickness 0.15)
				)
				(justify left bottom mirror)
			)
		)
		(pad "1" smd roundrect
			(at -0.48 0 180)
			(size 0.59 0.64)
			(layers "B.Cu" "B.Mask" "B.Paste")
			(roundrect_rratio 0.25)
			(net 5 "+5V")
			(pintype "passive")
		)
		(pad "2" smd roundrect
			(at 0.48 0 180)
			(size 0.59 0.64)
			(layers "B.Cu" "B.Mask" "B.Paste")
			(roundrect_rratio 0.25)
			(net 1 "GND")
			(pintype "passive")
		)
	)
	(footprint "antmicro-footprints:TP_SMD_0.75mm"
		(layer "B.Cu")
		(at 86.6 59.4 180)
		(property "Reference" "TP121"
			(at -3.85 -0.46 0)
			(layer "B.SilkS")
			(effects
				(font
					(size 0.7 0.7)
					(thickness 0.15)
				)
				(justify left bottom mirror)
			)
		)
		(property "Value" "TP_0.75mm_SMD"
			(at 0 -1.2 0)
			(layer "B.Fab")
			(effects
				(font
					(size 0.7 0.7)
					(thickness 0.15)
				)
				(justify left bottom mirror)
			)
		)
		(property "Description" "SMT test point"
			(at 0 0 0)
			(layer "B.Fab")
			(hide yes)
			(effects
				(font
					(size 1.27 1.27)
					(thickness 0.15)
				)
				(justify mirror)
			)
		)
		(property "MPN" ""
			(at 0 0 0)
			(unlocked yes)
			(layer "B.Fab")
			(hide yes)
			(effects
				(font
					(size 1 1)
					(thickness 0.15)
				)
				(justify mirror)
			)
		)
		(property "Manufacturer" ""
			(at 0 0 0)
			(unlocked yes)
			(layer "B.Fab")
			(hide yes)
			(effects
				(font
					(size 1 1)
					(thickness 0.15)
				)
				(justify mirror)
			)
		)
		(property "Author" "Antmicro"
			(at 0 0 0)
			(unlocked yes)
			(layer "B.Fab")
			(hide yes)
			(effects
				(font
					(size 1 1)
					(thickness 0.15)
				)
				(justify mirror)
			)
		)
		(property "License" "Apache-2.0"
			(at 0 0 0)
			(unlocked yes)
			(layer "B.Fab")
			(hide yes)
			(effects
				(font
					(size 1 1)
					(thickness 0.15)
				)
				(justify mirror)
			)
		)
		(sheetname "/SoM_Power/")
		(sheetfile "som_power.kicad_sch")
		(attr exclude_from_pos_files exclude_from_bom)
		(fp_circle
			(center 0 0)
			(end 0.475 0)
			(stroke
				(width 0.05)
				(type default)
			)
			(fill no)
			(layer "B.CrtYd")
		)
		(fp_text user "License: Apache-2.0"
			(at -0.4 -5.101 0)
			(layer "B.Fab")
			(effects
				(font
					(size 0.7 0.7)
					(thickness 0.15)
				)
				(justify left bottom mirror)
			)
		)
		(fp_text user "${REFERENCE}"
			(at -0.4 -2.7 0)
			(layer "B.Fab")
			(effects
				(font
					(size 0.7 0.7)
					(thickness 0.15)
				)
				(justify left bottom mirror)
			)
		)
		(fp_text user "Author: Antmicro"
			(at -0.4 -3.901 0)
			(layer "B.Fab")
			(effects
				(font
					(size 0.7 0.7)
					(thickness 0.15)
				)
				(justify left bottom mirror)
			)
		)
		(pad "1" smd circle
			(at 0 0 180)
			(size 0.75 0.75)
			(layers "B.Cu" "B.Mask")
			(net 85 "/SoM_Power/~{SOM_POWER_BTN}")
			(pinfunction "1")
			(pintype "passive")
		)
	)
	(footprint "antmicro-footprints:R_0402_1005Metric"
		(layer "B.Cu")
		(at 62.1 70.4 90)
		(descr "Resistor SMD 0402")
		(tags "resistor SMD 0402")
		(property "Reference" "R181"
			(at -2.2 3.7 90)
			(layer "B.SilkS")
			(effects
				(font
					(size 0.7 0.7)
					(thickness 0.15)
				)
				(justify right top mirror)
			)
		)
		(property "Value" "R_0R_0402"
			(at -1.011843 -1.772047 90)
			(layer "B.Fab")
			(effects
				(font
					(size 0.7 0.7)
					(thickness 0.15)
				)
				(justify right top mirror)
			)
		)
		(property "Datasheet" "https://industrial.panasonic.com/cdbs/www-data/pdf/RDA0000/AOA0000C301.pdf"
			(at 0 0 90)
			(layer "B.Fab")
			(hide yes)
			(effects
				(font
					(size 1.27 1.27)
					(thickness 0.15)
				)
				(justify mirror)
			)
		)
		(property "Description" "SMD Chip Resistor, Jumper, 0 ohm, 100 mW, 0402 [1005 Metric], Thick Film, General Purpose"
			(at 0 0 90)
			(layer "B.Fab")
			(hide yes)
			(effects
				(font
					(size 1.27 1.27)
					(thickness 0.15)
				)
				(justify mirror)
			)
		)
		(property "MPN" "ERJ2GE0R00X"
			(at 0 0 270)
			(unlocked yes)
			(layer "B.Fab")
			(hide yes)
			(effects
				(font
					(size 1 1)
					(thickness 0.15)
				)
				(justify mirror)
			)
		)
		(property "Manufacturer" "Panasonic"
			(at 0 0 270)
			(unlocked yes)
			(layer "B.Fab")
			(hide yes)
			(effects
				(font
					(size 1 1)
					(thickness 0.15)
				)
				(justify mirror)
			)
		)
		(property "License" "Apache-2.0"
			(at 0 0 270)
			(unlocked yes)
			(layer "B.Fab")
			(hide yes)
			(effects
				(font
					(size 1 1)
					(thickness 0.15)
				)
				(justify mirror)
			)
		)
		(property "Author" "Antmicro"
			(at 0 0 270)
			(unlocked yes)
			(layer "B.Fab")
			(hide yes)
			(effects
				(font
					(size 1 1)
					(thickness 0.15)
				)
				(justify mirror)
			)
		)
		(property "Val" "0R"
			(at 0 0 270)
			(unlocked yes)
			(layer "B.Fab")
			(hide yes)
			(effects
				(font
					(size 1 1)
					(thickness 0.15)
				)
				(justify mirror)
			)
		)
		(property "Tolerance" "~"
			(at 0 0 270)
			(unlocked yes)
			(layer "B.Fab")
			(hide yes)
			(effects
				(font
					(size 1 1)
					(thickness 0.15)
				)
				(justify mirror)
			)
		)
		(property "Current" "1A"
			(at 0 0 270)
			(unlocked yes)
			(layer "B.Fab")
			(hide yes)
			(effects
				(font
					(size 1 1)
					(thickness 0.15)
				)
				(justify mirror)
			)
		)
		(sheetname "/CSI/")
		(sheetfile "csi.kicad_sch")
		(attr smd)
		(fp_rect
			(start -0.925 0.47)
			(end 0.925 -0.47)
			(stroke
				(width 0.05)
				(type default)
			)
			(fill no)
			(layer "B.CrtYd")
		)
		(fp_rect
			(start -0.5 0.25)
			(end 0.5 -0.25)
			(stroke
				(width 0.15)
				(type solid)
			)
			(fill no)
			(layer "B.Fab")
		)
		(fp_text user "Author: Antmicro"
			(at -0.95 -4.169 90)
			(layer "B.Fab")
			(effects
				(font
					(size 0.7 0.7)
					(thickness 0.15)
				)
				(justify right top mirror)
			)
		)
		(fp_text user "${REFERENCE}"
			(at -0.95 -3.168 90)
			(layer "B.Fab")
			(effects
				(font
					(size 0.7 0.7)
					(thickness 0.15)
				)
				(justify right top mirror)
			)
		)
		(fp_text user "License: Apache-2.0"
			(at -0.95 -5.169 90)
			(layer "B.Fab")
			(effects
				(font
					(size 0.7 0.7)
					(thickness 0.15)
				)
				(justify right top mirror)
			)
		)
		(pad "1" smd roundrect
			(at -0.48 0 90)
			(size 0.59 0.64)
			(layers "B.Cu" "B.Mask" "B.Paste")
			(roundrect_rratio 0.25)
			(net 1374 "Net-(J11-Pad39)")
			(pintype "passive")
		)
		(pad "2" smd roundrect
			(at 0.48 0 90)
			(size 0.59 0.64)
			(layers "B.Cu" "B.Mask" "B.Paste")
			(roundrect_rratio 0.25)
			(net 987 "/CSI/SDA_CAM0")
			(pintype "passive")
		)
	)
	(footprint "antmicro-footprints:QFN-2L_1.6x1x0.55mm"
		(layer "B.Cu")
		(at 235.106 74.6)
		(property "Reference" "D23"
			(at 3.594 0.4 0)
			(layer "B.SilkS")
			(effects
				(font
					(size 0.7 0.7)
					(thickness 0.15)
				)
				(justify left bottom mirror)
			)
		)
		(property "Value" "ESDA25P35-1U1M"
			(at 0 -1.7 180)
			(layer "B.Fab")
			(effects
				(font
					(size 0.7 0.7)
					(thickness 0.15)
				)
				(justify left bottom mirror)
			)
		)
		(property "Datasheet" "https://www.st.com/resource/en/datasheet/esda25p35-1u1m.pdf"
			(at 0 0 180)
			(layer "B.Fab")
			(hide yes)
			(effects
				(font
					(size 1.27 1.27)
					(thickness 0.15)
				)
				(justify mirror)
			)
		)
		(property "Description" "Unidirectional TVS, 30 kV, QFN-2L, 22 V, 195 pF"
			(at 0 0 180)
			(layer "B.Fab")
			(hide yes)
			(effects
				(font
					(size 1.27 1.27)
					(thickness 0.15)
				)
				(justify mirror)
			)
		)
		(property "Manufacturer" "STMicroelectronics"
			(at 0 0 0)
			(unlocked yes)
			(layer "B.Fab")
			(hide yes)
			(effects
				(font
					(size 1 1)
					(thickness 0.15)
				)
				(justify mirror)
			)
		)
		(property "MPN" "ESDA25P35-1U1M"
			(at 0 0 0)
			(unlocked yes)
			(layer "B.Fab")
			(hide yes)
			(effects
				(font
					(size 1 1)
					(thickness 0.15)
				)
				(justify mirror)
			)
		)
		(property "Author" "Antmicro"
			(at 0 0 0)
			(unlocked yes)
			(layer "B.Fab")
			(hide yes)
			(effects
				(font
					(size 1 1)
					(thickness 0.15)
				)
				(justify mirror)
			)
		)
		(property "License" "Apache-2.0"
			(at 0 0 0)
			(unlocked yes)
			(layer "B.Fab")
			(hide yes)
			(effects
				(font
					(size 1 1)
					(thickness 0.15)
				)
				(justify mirror)
			)
		)
		(sheetname "/USB Debug, PD/")
		(sheetfile "usb_debug_pd.kicad_sch")
		(attr smd)
		(fp_line
			(start -1.2 0.4)
			(end -1.2 -0.4)
			(stroke
				(width 0.15)
				(type solid)
			)
			(layer "B.SilkS")
		)
		(fp_line
			(start 0.23 -0.45)
			(end -0.23 -0.45)
			(stroke
				(width 0.15)
				(type solid)
			)
			(layer "B.SilkS")
		)
		(fp_line
			(start 0.23 0.45)
			(end -0.23 0.45)
			(stroke
				(width 0.15)
				(type solid)
			)
			(layer "B.SilkS")
		)
		(fp_rect
			(start 1.25 -0.65)
			(end -1.25 0.65)
			(stroke
				(width 0.05)
				(type solid)
			)
			(fill no)
			(layer "B.CrtYd")
		)
		(fp_line
			(start -0.199 -0.2)
			(end -0.199 -0.1)
			(stroke
				(width 0.15)
				(type solid)
			)
			(layer "B.Fab")
		)
		(fp_line
			(start -0.199 0)
			(end -0.597 0)
			(stroke
				(width 0.15)
				(type solid)
			)
			(layer "B.Fab")
		)
		(fp_line
			(start -0.199 0.202)
			(end -0.199 -0.1)
			(stroke
				(width 0.15)
				(type solid)
			)
			(layer "B.Fab")
		)
		(fp_line
			(start -0.101 0)
			(end 0.201 -0.2)
			(stroke
				(width 0.15)
				(type solid)
			)
			(layer "B.Fab")
		)
		(fp_line
			(start 0.201 -0.2)
			(end 0.201 0)
			(stroke
				(width 0.15)
				(type solid)
			)
			(layer "B.Fab")
		)
		(fp_line
			(start 0.201 0)
			(end 0.201 0.202)
			(stroke
				(width 0.15)
				(type solid)
			)
			(layer "B.Fab")
		)
		(fp_line
			(start 0.201 0.202)
			(end -0.101 0)
			(stroke
				(width 0.15)
				(type solid)
			)
			(layer "B.Fab")
		)
		(fp_line
			(start 0.599 0)
			(end 0.201 0)
			(stroke
				(width 0.15)
				(type solid)
			)
			(layer "B.Fab")
		)
		(fp_rect
			(start 0.848 -0.4)
			(end -0.85 0.402)
			(stroke
				(width 0.15)
				(type solid)
			)
			(fill no)
			(layer "B.Fab")
		)
		(fp_text user "License: Apache-2.0"
			(at -1.31 -5.769 180)
			(layer "B.Fab")
			(effects
				(font
					(size 0.7 0.7)
					(thickness 0.15)
				)
				(justify left bottom mirror)
			)
		)
		(fp_text user "Author: Antmicro"
			(at -1.31 -4.769 180)
			(layer "B.Fab")
			(effects
				(font
					(size 0.7 0.7)
					(thickness 0.15)
				)
				(justify left bottom mirror)
			)
		)
		(fp_text user "${REFERENCE}"
			(at -1.31 -3.769 180)
			(layer "B.Fab")
			(effects
				(font
					(size 0.7 0.7)
					(thickness 0.15)
				)
				(justify left bottom mirror)
			)
		)
		(pad "1" smd roundrect
			(at -0.7 0 180)
			(size 0.8 1)
			(layers "B.Cu" "B.Mask" "B.Paste")
			(roundrect_rratio 0.2)
			(net 176 "/USB Debug, PD/USBC0_VBUS")
			(pinfunction "C")
			(pintype "passive")
		)
		(pad "2" smd roundrect
			(at 0.7 0 180)
			(size 0.8 1)
			(layers "B.Cu" "B.Mask" "B.Paste")
			(roundrect_rratio 0.2)
			(net 1 "GND")
			(pinfunction "A")
			(pintype "passive")
		)
	)
	(footprint "antmicro-footprints:C_0402_1005Metric"
		(layer "B.Cu")
		(at 100.5 57.5 90)
		(descr "Capacitor SMD 0402")
		(tags "capacitor SMD 0402")
		(property "Reference" "C225"
			(at -1.6 0.45 90)
			(layer "B.SilkS")
			(effects
				(font
					(size 0.7 0.7)
					(thickness 0.15)
				)
				(justify right top mirror)
			)
		)
		(property "Value" "C_100n_0402"
			(at -1.022927 -2.155213 90)
			(layer "B.Fab")
			(effects
				(font
					(size 0.7 0.7)
					(thickness 0.15)
				)
				(justify right top mirror)
			)
		)
		(property "Datasheet" "https://www.murata.com/products/productdetail?partno=GRM155R61H104KE14%23"
			(at 0 0 90)
			(layer "B.Fab")
			(hide yes)
			(effects
				(font
					(size 1.27 1.27)
					(thickness 0.15)
				)
				(justify mirror)
			)
		)
		(property "Description" "SMD Multilayer Ceramic Capacitor, 0.1 µF, 50 V, 0402 [1005 Metric], ± 10%, X5R, GRM Series"
			(at 0 0 90)
			(layer "B.Fab")
			(hide yes)
			(effects
				(font
					(size 1.27 1.27)
					(thickness 0.15)
				)
				(justify mirror)
			)
		)
		(property "MPN" "GRM155R61H104KE14D"
			(at 0 0 270)
			(unlocked yes)
			(layer "B.Fab")
			(hide yes)
			(effects
				(font
					(size 1 1)
					(thickness 0.15)
				)
				(justify mirror)
			)
		)
		(property "Manufacturer" "Murata"
			(at 0 0 270)
			(unlocked yes)
			(layer "B.Fab")
			(hide yes)
			(effects
				(font
					(size 1 1)
					(thickness 0.15)
				)
				(justify mirror)
			)
		)
		(property "License" "Apache-2.0"
			(at 0 0 270)
			(unlocked yes)
			(layer "B.Fab")
			(hide yes)
			(effects
				(font
					(size 1 1)
					(thickness 0.15)
				)
				(justify mirror)
			)
		)
		(property "Author" "Antmicro"
			(at 0 0 270)
			(unlocked yes)
			(layer "B.Fab")
			(hide yes)
			(effects
				(font
					(size 1 1)
					(thickness 0.15)
				)
				(justify mirror)
			)
		)
		(property "Val" "100n"
			(at 0 0 270)
			(unlocked yes)
			(layer "B.Fab")
			(hide yes)
			(effects
				(font
					(size 1 1)
					(thickness 0.15)
				)
				(justify mirror)
			)
		)
		(property "Voltage" "50V"
			(at 0 0 270)
			(unlocked yes)
			(layer "B.Fab")
			(hide yes)
			(effects
				(font
					(size 1 1)
					(thickness 0.15)
				)
				(justify mirror)
			)
		)
		(property "Dielectric" "X5R"
			(at 0 0 270)
			(unlocked yes)
			(layer "B.Fab")
			(hide yes)
			(effects
				(font
					(size 1 1)
					(thickness 0.15)
				)
				(justify mirror)
			)
		)
		(property "Public" "False"
			(at 0 0 270)
			(unlocked yes)
			(layer "B.Fab")
			(hide yes)
			(effects
				(font
					(size 1 1)
					(thickness 0.15)
				)
				(justify mirror)
			)
		)
		(sheetname "/SoM_Power/")
		(sheetfile "som_power.kicad_sch")
		(attr smd)
		(fp_poly
			(pts
				(xy -0.925 0.47) (xy 0.925 0.47) (xy 0.925 -0.47) (xy -0.925 -0.47)
			)
			(stroke
				(width 0.05)
				(type default)
			)
			(fill no)
			(layer "B.CrtYd")
		)
		(fp_line
			(start 0.504 -0.248)
			(end -0.494 -0.248)
			(stroke
				(width 0.15)
				(type solid)
			)
			(layer "B.Fab")
		)
		(fp_line
			(start -0.494 -0.248)
			(end -0.494 0.25)
			(stroke
				(width 0.15)
				(type solid)
			)
			(layer "B.Fab")
		)
		(fp_line
			(start 0.504 0.25)
			(end 0.504 -0.248)
			(stroke
				(width 0.15)
				(type solid)
			)
			(layer "B.Fab")
		)
		(fp_line
			(start -0.494 0.25)
			(end 0.504 0.25)
			(stroke
				(width 0.15)
				(type solid)
			)
			(layer "B.Fab")
		)
		(fp_text user "Author: Antmicro"
			(at -0.939 -3.399 90)
			(layer "B.Fab")
			(effects
				(font
					(size 0.7 0.7)
					(thickness 0.15)
				)
				(justify right top mirror)
			)
		)
		(fp_text user "${REFERENCE}"
			(at -0.939 -4.599 90)
			(layer "B.Fab")
			(effects
				(font
					(size 0.7 0.7)
					(thickness 0.15)
				)
				(justify right top mirror)
			)
		)
		(fp_text user "License: Apache-2.0"
			(at -0.939 -5.799 90)
			(layer "B.Fab")
			(effects
				(font
					(size 0.7 0.7)
					(thickness 0.15)
				)
				(justify right top mirror)
			)
		)
		(pad "1" smd roundrect
			(at -0.48 0 90)
			(size 0.59 0.64)
			(layers "B.Cu" "B.Mask" "B.Paste")
			(roundrect_rratio 0.25)
			(net 1 "GND")
			(pintype "passive")
		)
		(pad "2" smd roundrect
			(at 0.48 0 90)
			(size 0.59 0.64)
			(layers "B.Cu" "B.Mask" "B.Paste")
			(roundrect_rratio 0.25)
			(net 4 "+3V3_AON")
			(pintype "passive")
		)
	)
	(footprint "antmicro-footprints:TP_SMD_0.75mm"
		(layer "B.Cu")
		(at 147.75 144.75 -90)
		(property "Reference" "TP78"
			(at -3.35 -0.45 90)
			(layer "B.SilkS")
			(effects
				(font
					(size 0.7 0.7)
					(thickness 0.15)
				)
				(justify left bottom mirror)
			)
		)
		(property "Value" "TP_0.75mm_SMD"
			(at 0 -1.2 90)
			(layer "B.Fab")
			(effects
				(font
					(size 0.7 0.7)
					(thickness 0.15)
				)
				(justify left bottom mirror)
			)
		)
		(property "Description" "SMT test point"
			(at 0 0 90)
			(layer "B.Fab")
			(hide yes)
			(effects
				(font
					(size 1.27 1.27)
					(thickness 0.15)
				)
				(justify mirror)
			)
		)
		(property "MPN" ""
			(at 0 0 90)
			(unlocked yes)
			(layer "B.Fab")
			(hide yes)
			(effects
				(font
					(size 1 1)
					(thickness 0.15)
				)
				(justify mirror)
			)
		)
		(property "Manufacturer" ""
			(at 0 0 90)
			(unlocked yes)
			(layer "B.Fab")
			(hide yes)
			(effects
				(font
					(size 1 1)
					(thickness 0.15)
				)
				(justify mirror)
			)
		)
		(property "Author" "Antmicro"
			(at 0 0 90)
			(unlocked yes)
			(layer "B.Fab")
			(hide yes)
			(effects
				(font
					(size 1 1)
					(thickness 0.15)
				)
				(justify mirror)
			)
		)
		(property "License" "Apache-2.0"
			(at 0 0 90)
			(unlocked yes)
			(layer "B.Fab")
			(hide yes)
			(effects
				(font
					(size 1 1)
					(thickness 0.15)
				)
				(justify mirror)
			)
		)
		(sheetname "/SoM_Power/")
		(sheetfile "som_power.kicad_sch")
		(attr exclude_from_pos_files exclude_from_bom)
		(fp_circle
			(center 0 0)
			(end 0.475 0)
			(stroke
				(width 0.05)
				(type default)
			)
			(fill no)
			(layer "B.CrtYd")
		)
		(fp_text user "License: Apache-2.0"
			(at -0.4 -5.101 90)
			(layer "B.Fab")
			(effects
				(font
					(size 0.7 0.7)
					(thickness 0.15)
				)
				(justify left bottom mirror)
			)
		)
		(fp_text user "Author: Antmicro"
			(at -0.4 -3.901 90)
			(layer "B.Fab")
			(effects
				(font
					(size 0.7 0.7)
					(thickness 0.15)
				)
				(justify left bottom mirror)
			)
		)
		(fp_text user "${REFERENCE}"
			(at -0.4 -2.7 90)
			(layer "B.Fab")
			(effects
				(font
					(size 0.7 0.7)
					(thickness 0.15)
				)
				(justify left bottom mirror)
			)
		)
		(pad "1" smd circle
			(at 0 0 270)
			(size 0.75 0.75)
			(layers "B.Cu" "B.Mask")
			(net 32 "Net-(D1-C)")
			(pinfunction "1")
			(pintype "passive")
		)
	)
	(footprint "antmicro-footprints:SOT-23-5"
		(layer "B.Cu")
		(at 97.75 57 180)
		(property "Reference" "U72"
			(at -4.25 1 0)
			(layer "B.SilkS")
			(effects
				(font
					(size 0.7 0.7)
					(thickness 0.15)
				)
				(justify left bottom mirror)
			)
		)
		(property "Value" "TPS3840PL30DBVR"
			(at 0.002 -2.799 0)
			(layer "B.Fab")
			(effects
				(font
					(size 0.7 0.7)
					(thickness 0.15)
				)
				(justify left bottom mirror)
			)
		)
		(property "Datasheet" "https://www.ti.com/lit/ds/symlink/tps3840.pdf?HQS=dis-mous-null-mousermode-dsf-pf-null-wwe&DCM=yes&ref_url=https%3A%2F%2Fwww.mouser.com%2F&distId=26"
			(at 0 0 0)
			(layer "B.Fab")
			(hide yes)
			(effects
				(font
					(size 1.27 1.27)
					(thickness 0.15)
				)
				(justify mirror)
			)
		)
		(property "Description" "Voltage supervisor"
			(at 0 0 0)
			(layer "B.Fab")
			(hide yes)
			(effects
				(font
					(size 1.27 1.27)
					(thickness 0.15)
				)
				(justify mirror)
			)
		)
		(property "Manufacturer" "Texas Instruments"
			(at 0 0 0)
			(unlocked yes)
			(layer "B.Fab")
			(hide yes)
			(effects
				(font
					(size 1 1)
					(thickness 0.15)
				)
				(justify mirror)
			)
		)
		(property "MPN" "TPS3840PL30DBVR"
			(at 0 0 0)
			(unlocked yes)
			(layer "B.Fab")
			(hide yes)
			(effects
				(font
					(size 1 1)
					(thickness 0.15)
				)
				(justify mirror)
			)
		)
		(property "Author" "Antmicro"
			(at 0 0 0)
			(unlocked yes)
			(layer "B.Fab")
			(hide yes)
			(effects
				(font
					(size 1 1)
					(thickness 0.15)
				)
				(justify mirror)
			)
		)
		(property "License" "Apache-2.0"
			(at 0 0 0)
			(unlocked yes)
			(layer "B.Fab")
			(hide yes)
			(effects
				(font
					(size 1 1)
					(thickness 0.15)
				)
				(justify mirror)
			)
		)
		(property ki_fp_filters "DBV0005A_N DBV0005A_M DBV0005A_L")
		(sheetname "/SoM_Power/")
		(sheetfile "som_power.kicad_sch")
		(attr smd)
		(fp_line
			(start 0.8 1.6)
			(end 0.5 1.6)
			(stroke
				(width 0.15)
				(type solid)
			)
			(layer "B.SilkS")
		)
		(fp_line
			(start 0.8 1.3)
			(end 0.8 1.6)
			(stroke
				(width 0.15)
				(type solid)
			)
			(layer "B.SilkS")
		)
		(fp_line
			(start 0.8 -0.55)
			(end 0.8 0.55)
			(stroke
				(width 0.15)
				(type solid)
			)
			(layer "B.SilkS")
		)
		(fp_line
			(start 0.8 -1.3)
			(end 0.8 -1.599)
			(stroke
				(width 0.15)
				(type solid)
			)
			(layer "B.SilkS")
		)
		(fp_line
			(start 0.8 -1.599)
			(end 0.549 -1.599)
			(stroke
				(width 0.15)
				(type solid)
			)
			(layer "B.SilkS")
		)
		(fp_line
			(start -0.55 -1.6)
			(end -0.85 -1.6)
			(stroke
				(width 0.15)
				(type solid)
			)
			(layer "B.SilkS")
		)
		(fp_line
			(start -0.8 1.6)
			(end -0.5 1.6)
			(stroke
				(width 0.15)
				(type solid)
			)
			(layer "B.SilkS")
		)
		(fp_line
			(start -0.8 1.6)
			(end -0.8 1.3)
			(stroke
				(width 0.15)
				(type solid)
			)
			(layer "B.SilkS")
		)
		(fp_line
			(start -0.85 -1.6)
			(end -0.85 -1.301)
			(stroke
				(width 0.15)
				(type solid)
			)
			(layer "B.SilkS")
		)
		(fp_circle
			(center -1.25 1.5)
			(end -1.2 1.5)
			(stroke
				(width 0.15)
				(type solid)
			)
			(fill yes)
			(layer "B.SilkS")
		)
		(fp_poly
			(pts
				(xy 1.9 1.76) (xy 1.9 -1.75) (xy -1.9 -1.75) (xy -1.9 1.76)
			)
			(stroke
				(width 0.05)
				(type solid)
			)
			(fill no)
			(layer "B.CrtYd")
		)
		(fp_line
			(start -0.398 1.525999)
			(end -0.874 1.05)
			(stroke
				(width 0.15)
				(type solid)
			)
			(layer "B.Fab")
		)
		(fp_poly
			(pts
				(xy 0.874 -1.523) (xy 0.874 1.525) (xy -0.873 1.525) (xy -0.873 -1.523)
			)
			(stroke
				(width 0.15)
				(type solid)
			)
			(fill no)
			(layer "B.Fab")
		)
		(fp_text user "${REFERENCE}"
			(at -1.898 -4.299 0)
			(layer "B.Fab")
			(effects
				(font
					(size 0.7 0.7)
					(thickness 0.15)
				)
				(justify left bottom mirror)
			)
		)
		(fp_text user "License: Apache-2.0"
			(at -1.898 -6.7 0)
			(layer "B.Fab")
			(effects
				(font
					(size 0.7 0.7)
					(thickness 0.15)
				)
				(justify left bottom mirror)
			)
		)
		(fp_text user "Author: Antmicro"
			(at -1.898 -5.499 0)
			(layer "B.Fab")
			(effects
				(font
					(size 0.7 0.7)
					(thickness 0.15)
				)
				(justify left bottom mirror)
			)
		)
		(pad "1" smd rect
			(at -1.351 0.951 270)
			(size 0.55 1)
			(layers "B.Cu" "B.Mask" "B.Paste")
			(net 892 "Net-(Q22-G)")
			(pinfunction "~{RESET}")
			(pintype "output")
		)
		(pad "2" smd rect
			(at -1.351 0 270)
			(size 0.55 1)
			(layers "B.Cu" "B.Mask" "B.Paste")
			(net 4 "+3V3_AON")
			(pinfunction "VDD")
			(pintype "power_in")
		)
		(pad "3" smd rect
			(at -1.351 -0.949 270)
			(size 0.55 1)
			(layers "B.Cu" "B.Mask" "B.Paste")
			(net 1 "GND")
			(pinfunction "GND")
			(pintype "power_in")
		)
		(pad "4" smd rect
			(at 1.35 -0.949 270)
			(size 0.55 1)
			(layers "B.Cu" "B.Mask" "B.Paste")
			(net 1037 "Net-(U72-~{MR})")
			(pinfunction "~{MR}")
			(pintype "input")
		)
		(pad "5" smd rect
			(at 1.35 0.951 270)
			(size 0.55 1)
			(layers "B.Cu" "B.Mask" "B.Paste")
			(net 521 "Net-(U72-CT)")
			(pinfunction "CT")
			(pintype "passive")
		)
	)
	(footprint "antmicro-footprints:Oscillator_SMD_Abracon_AK3LPHEF1_3.2x2.5x1mm"
		(layer "B.Cu")
		(at 103.75 59.25 -90)
		(property "Reference" "Y5"
			(at -1.3 -3.030532 90)
			(layer "B.SilkS")
			(effects
				(font
					(size 0.7 0.7)
					(thickness 0.15)
				)
				(justify left bottom mirror)
			)
		)
		(property "Value" "Oscillator_156.25MHz_AK3LPHEF1"
			(at 0 -3 90)
			(unlocked yes)
			(layer "B.Fab")
			(effects
				(font
					(size 0.7 0.7)
					(thickness 0.15)
				)
				(justify left bottom mirror)
			)
		)
		(property "Datasheet" "https://eu.mouser.com/datasheet/2/3/AK3LP-3318362.pdf"
			(at 0 0 90)
			(layer "B.Fab")
			(hide yes)
			(effects
				(font
					(size 1.27 1.27)
					(thickness 0.15)
				)
				(justify mirror)
			)
		)
		(property "Description" "156.25 MHz XO (Standard) HCSL Oscillator 3.3V Enable/Disable 6-SMD, +/-25ppm"
			(at 0 0 90)
			(layer "B.Fab")
			(hide yes)
			(effects
				(font
					(size 1.27 1.27)
					(thickness 0.15)
				)
				(justify mirror)
			)
		)
		(property "MPN" "AK3LPHEF1-156.2500T"
			(at 0 0 90)
			(unlocked yes)
			(layer "B.Fab")
			(hide yes)
			(effects
				(font
					(size 1 1)
					(thickness 0.15)
				)
				(justify mirror)
			)
		)
		(property "Manufacturer" "Abracon"
			(at 0 0 90)
			(unlocked yes)
			(layer "B.Fab")
			(hide yes)
			(effects
				(font
					(size 1 1)
					(thickness 0.15)
				)
				(justify mirror)
			)
		)
		(property "Val" "156.25MHz"
			(at 0 0 90)
			(unlocked yes)
			(layer "B.Fab")
			(hide yes)
			(effects
				(font
					(size 1 1)
					(thickness 0.15)
				)
				(justify mirror)
			)
		)
		(property "Author" "Antmicro"
			(at 0 0 90)
			(unlocked yes)
			(layer "B.Fab")
			(hide yes)
			(effects
				(font
					(size 1 1)
					(thickness 0.15)
				)
				(justify mirror)
			)
		)
		(property "License" "Apache-2.0"
			(at 0 0 90)
			(unlocked yes)
			(layer "B.Fab")
			(hide yes)
			(effects
				(font
					(size 1 1)
					(thickness 0.15)
				)
				(justify mirror)
			)
		)
		(sheetname "/SoM_IO2/")
		(sheetfile "som_io2.kicad_sch")
		(attr smd)
		(fp_line
			(start 1.25 1.8)
			(end -1.25 1.8)
			(stroke
				(width 0.15)
				(type solid)
			)
			(layer "B.SilkS")
		)
		(fp_line
			(start 1.25 -1.899999)
			(end -1.25 -1.899999)
			(stroke
				(width 0.15)
				(type solid)
			)
			(layer "B.SilkS")
		)
		(fp_circle
			(center -1.525 1.825)
			(end -1.525 1.775)
			(stroke
				(width 0.15)
				(type solid)
			)
			(fill yes)
			(layer "B.SilkS")
		)
		(fp_poly
			(pts
				(xy 1.6 1.9) (xy 1.6 -2) (xy -1.6 -2) (xy -1.6 1.9)
			)
			(stroke
				(width 0.05)
				(type solid)
			)
			(fill no)
			(layer "B.CrtYd")
		)
		(fp_text user "${REFERENCE}"
			(at -2.29 -5.11 90)
			(unlocked yes)
			(layer "B.Fab")
			(effects
				(font
					(size 0.7 0.7)
					(thickness 0.15)
				)
				(justify left bottom mirror)
			)
		)
		(fp_text user "Author: Antmicro"
			(at -2.29 -6.31 90)
			(layer "B.Fab")
			(effects
				(font
					(size 0.7 0.7)
					(thickness 0.15)
				)
				(justify left bottom mirror)
			)
		)
		(fp_text user "License: Apache-2.0"
			(at -2.29 -3.91 90)
			(layer "B.Fab")
			(effects
				(font
					(size 0.7 0.7)
					(thickness 0.15)
				)
				(justify left bottom mirror)
			)
		)
		(pad "1" smd rect
			(at -0.925 1.24)
			(size 0.92 1.05)
			(layers "B.Cu" "B.Mask" "B.Paste")
			(net 1101 "Net-(Y5-EN)")
			(pinfunction "EN")
			(pintype "input")
			(solder_mask_margin 0.05)
		)
		(pad "2" smd rect
			(at -0.925 -0.05)
			(size 0.8 1.05)
			(layers "B.Cu" "B.Mask" "B.Paste")
			(net 1180 "unconnected-(Y5-NC-Pad2)")
			(pinfunction "NC")
			(pintype "no_connect")
			(solder_mask_margin 0.05)
		)
		(pad "3" smd rect
			(at -0.925 -1.34)
			(size 0.92 1.05)
			(layers "B.Cu" "B.Mask" "B.Paste")
			(net 1 "GND")
			(pinfunction "GND")
			(pintype "power_in")
			(solder_mask_margin 0.05)
		)
		(pad "4" smd rect
			(at 0.925 -1.34)
			(size 0.92 1.05)
			(layers "B.Cu" "B.Mask" "B.Paste")
			(net 894 "/SoM_IO2/SFI_CLK+")
			(pinfunction "OUT+")
			(pintype "output")
			(solder_mask_margin 0.05)
		)
		(pad "5" smd rect
			(at 0.925 -0.05)
			(size 0.8 1.05)
			(layers "B.Cu" "B.Mask" "B.Paste")
			(net 895 "/SoM_IO2/SFI_CLK-")
			(pinfunction "OUT-")
			(pintype "output")
			(solder_mask_margin 0.05)
		)
		(pad "6" smd rect
			(at 0.925 1.24)
			(size 0.92 1.05)
			(layers "B.Cu" "B.Mask" "B.Paste")
			(net 2 "+3V3")
			(pinfunction "VCC")
			(pintype "power_in")
			(solder_mask_margin 0.05)
		)
	)
	(footprint "antmicro-footprints:R_0402_1005Metric"
		(layer "B.Cu")
		(at 162.84 59.81 90)
		(descr "Resistor SMD 0402")
		(tags "resistor SMD 0402")
		(property "Reference" "R72"
			(at 3.11 -0.34 90)
			(layer "B.SilkS")
			(effects
				(font
					(size 0.7 0.7)
					(thickness 0.15)
				)
				(justify right top mirror)
			)
		)
		(property "Value" "R_10k_0402"
			(at -1.011843 -1.772047 90)
			(layer "B.Fab")
			(effects
				(font
					(size 0.7 0.7)
					(thickness 0.15)
				)
				(justify right top mirror)
			)
		)
		(property "Datasheet" "https://www.bourns.com/docs/product-datasheets/cr.pdf"
			(at 0 0 90)
			(layer "B.Fab")
			(hide yes)
			(effects
				(font
					(size 1.27 1.27)
					(thickness 0.15)
				)
				(justify mirror)
			)
		)
		(property "Description" "SMD Chip Resistor, 10 kohm, ± 1%, 62.5 mW, 0402 [1005 Metric], Thick Film, General Purpose"
			(at 0 0 90)
			(layer "B.Fab")
			(hide yes)
			(effects
				(font
					(size 1.27 1.27)
					(thickness 0.15)
				)
				(justify mirror)
			)
		)
		(property "MPN" "CR0402-FX-1002GLF"
			(at 0 0 270)
			(unlocked yes)
			(layer "B.Fab")
			(hide yes)
			(effects
				(font
					(size 1 1)
					(thickness 0.15)
				)
				(justify mirror)
			)
		)
		(property "Manufacturer" "Bourns"
			(at 0 0 270)
			(unlocked yes)
			(layer "B.Fab")
			(hide yes)
			(effects
				(font
					(size 1 1)
					(thickness 0.15)
				)
				(justify mirror)
			)
		)
		(property "License" "Apache-2.0"
			(at 0 0 270)
			(unlocked yes)
			(layer "B.Fab")
			(hide yes)
			(effects
				(font
					(size 1 1)
					(thickness 0.15)
				)
				(justify mirror)
			)
		)
		(property "Author" "Antmicro"
			(at 0 0 270)
			(unlocked yes)
			(layer "B.Fab")
			(hide yes)
			(effects
				(font
					(size 1 1)
					(thickness 0.15)
				)
				(justify mirror)
			)
		)
		(property "Val" "10k"
			(at 0 0 270)
			(unlocked yes)
			(layer "B.Fab")
			(hide yes)
			(effects
				(font
					(size 1 1)
					(thickness 0.15)
				)
				(justify mirror)
			)
		)
		(property "Tolerance" "1%"
			(at 0 0 270)
			(unlocked yes)
			(layer "B.Fab")
			(hide yes)
			(effects
				(font
					(size 1 1)
					(thickness 0.15)
				)
				(justify mirror)
			)
		)
		(sheetname "/Power/")
		(sheetfile "power.kicad_sch")
		(attr smd)
		(fp_rect
			(start -0.925 0.47)
			(end 0.925 -0.47)
			(stroke
				(width 0.05)
				(type default)
			)
			(fill no)
			(layer "B.CrtYd")
		)
		(fp_rect
			(start -0.5 0.25)
			(end 0.5 -0.25)
			(stroke
				(width 0.15)
				(type solid)
			)
			(fill no)
			(layer "B.Fab")
		)
		(fp_text user "Author: Antmicro"
			(at -0.95 -4.169 90)
			(layer "B.Fab")
			(effects
				(font
					(size 0.7 0.7)
					(thickness 0.15)
				)
				(justify right top mirror)
			)
		)
		(fp_text user "License: Apache-2.0"
			(at -0.95 -5.169 90)
			(layer "B.Fab")
			(effects
				(font
					(size 0.7 0.7)
					(thickness 0.15)
				)
				(justify right top mirror)
			)
		)
		(fp_text user "${REFERENCE}"
			(at -0.95 -3.168 90)
			(layer "B.Fab")
			(effects
				(font
					(size 0.7 0.7)
					(thickness 0.15)
				)
				(justify right top mirror)
			)
		)
		(pad "1" smd roundrect
			(at -0.48 0 90)
			(size 0.59 0.64)
			(layers "B.Cu" "B.Mask" "B.Paste")
			(roundrect_rratio 0.25)
			(net 1 "GND")
			(pintype "passive")
		)
		(pad "2" smd roundrect
			(at 0.48 0 90)
			(size 0.59 0.64)
			(layers "B.Cu" "B.Mask" "B.Paste")
			(roundrect_rratio 0.25)
			(net 282 "+1V15")
			(pintype "passive")
		)
	)
	(footprint "antmicro-footprints:R_0402_1005Metric"
		(layer "B.Cu")
		(at 208.716532 142)
		(descr "Resistor SMD 0402")
		(tags "resistor SMD 0402")
		(property "Reference" "R192"
			(at 0.98 -0.31 0)
			(layer "B.SilkS")
			(effects
				(font
					(size 0.7 0.7)
					(thickness 0.15)
				)
				(justify right top mirror)
			)
		)
		(property "Value" "R_1k_0402"
			(at -1.011843 -1.772047 0)
			(layer "B.Fab")
			(effects
				(font
					(size 0.7 0.7)
					(thickness 0.15)
				)
				(justify right top mirror)
			)
		)
		(property "Datasheet" "https://www.bourns.com/docs/product-datasheets/cr.pdf"
			(at 0 0 0)
			(layer "B.Fab")
			(hide yes)
			(effects
				(font
					(size 1.27 1.27)
					(thickness 0.15)
				)
				(justify mirror)
			)
		)
		(property "Description" "SMD Chip Resistor, 1 kohm, ± 1%, 63 mW, 0402 [1005 Metric], Thick Film, General Purpose"
			(at 0 0 0)
			(layer "B.Fab")
			(hide yes)
			(effects
				(font
					(size 1.27 1.27)
					(thickness 0.15)
				)
				(justify mirror)
			)
		)
		(property "MPN" "CR0402-FX-1001GLF"
			(at 0 0 180)
			(unlocked yes)
			(layer "B.Fab")
			(hide yes)
			(effects
				(font
					(size 1 1)
					(thickness 0.15)
				)
				(justify mirror)
			)
		)
		(property "Manufacturer" "Bourns"
			(at 0 0 180)
			(unlocked yes)
			(layer "B.Fab")
			(hide yes)
			(effects
				(font
					(size 1 1)
					(thickness 0.15)
				)
				(justify mirror)
			)
		)
		(property "License" "Apache-2.0"
			(at 0 0 180)
			(unlocked yes)
			(layer "B.Fab")
			(hide yes)
			(effects
				(font
					(size 1 1)
					(thickness 0.15)
				)
				(justify mirror)
			)
		)
		(property "Author" "Antmicro"
			(at 0 0 180)
			(unlocked yes)
			(layer "B.Fab")
			(hide yes)
			(effects
				(font
					(size 1 1)
					(thickness 0.15)
				)
				(justify mirror)
			)
		)
		(property "Val" "1k"
			(at 0 0 180)
			(unlocked yes)
			(layer "B.Fab")
			(hide yes)
			(effects
				(font
					(size 1 1)
					(thickness 0.15)
				)
				(justify mirror)
			)
		)
		(property "Tolerance" "1%"
			(at 0 0 180)
			(unlocked yes)
			(layer "B.Fab")
			(hide yes)
			(effects
				(font
					(size 1 1)
					(thickness 0.15)
				)
				(justify mirror)
			)
		)
		(sheetname "/SFP/")
		(sheetfile "sfp.kicad_sch")
		(attr smd)
		(fp_rect
			(start -0.925 0.47)
			(end 0.925 -0.47)
			(stroke
				(width 0.05)
				(type default)
			)
			(fill no)
			(layer "B.CrtYd")
		)
		(fp_rect
			(start -0.5 0.25)
			(end 0.5 -0.25)
			(stroke
				(width 0.15)
				(type solid)
			)
			(fill no)
			(layer "B.Fab")
		)
		(fp_text user "Author: Antmicro"
			(at -0.95 -4.169 0)
			(layer "B.Fab")
			(effects
				(font
					(size 0.7 0.7)
					(thickness 0.15)
				)
				(justify right top mirror)
			)
		)
		(fp_text user "License: Apache-2.0"
			(at -0.95 -5.169 0)
			(layer "B.Fab")
			(effects
				(font
					(size 0.7 0.7)
					(thickness 0.15)
				)
				(justify right top mirror)
			)
		)
		(fp_text user "${REFERENCE}"
			(at -0.95 -3.168 0)
			(layer "B.Fab")
			(effects
				(font
					(size 0.7 0.7)
					(thickness 0.15)
				)
				(justify right top mirror)
			)
		)
		(pad "1" smd roundrect
			(at -0.48 0)
			(size 0.59 0.64)
			(layers "B.Cu" "B.Mask" "B.Paste")
			(roundrect_rratio 0.25)
			(net 1370 "Net-(J12-RX_{LOS})")
			(pintype "passive")
		)
		(pad "2" smd roundrect
			(at 0.48 0)
			(size 0.59 0.64)
			(layers "B.Cu" "B.Mask" "B.Paste")
			(roundrect_rratio 0.25)
			(net 2 "+3V3")
			(pintype "passive")
		)
	)
	(footprint "antmicro-footprints:TP_SMD_0.75mm"
		(layer "B.Cu")
		(at 89.15 61.5 180)
		(property "Reference" "TP119"
			(at 0.38 -0.45 0)
			(layer "B.SilkS")
			(effects
				(font
					(size 0.7 0.7)
					(thickness 0.15)
				)
				(justify left bottom mirror)
			)
		)
		(property "Value" "TP_0.75mm_SMD"
			(at 0 -1.2 0)
			(layer "B.Fab")
			(effects
				(font
					(size 0.7 0.7)
					(thickness 0.15)
				)
				(justify left bottom mirror)
			)
		)
		(property "Description" "SMT test point"
			(at 0 0 0)
			(layer "B.Fab")
			(hide yes)
			(effects
				(font
					(size 1.27 1.27)
					(thickness 0.15)
				)
				(justify mirror)
			)
		)
		(property "MPN" ""
			(at 0 0 0)
			(unlocked yes)
			(layer "B.Fab")
			(hide yes)
			(effects
				(font
					(size 1 1)
					(thickness 0.15)
				)
				(justify mirror)
			)
		)
		(property "Manufacturer" ""
			(at 0 0 0)
			(unlocked yes)
			(layer "B.Fab")
			(hide yes)
			(effects
				(font
					(size 1 1)
					(thickness 0.15)
				)
				(justify mirror)
			)
		)
		(property "Author" "Antmicro"
			(at 0 0 0)
			(unlocked yes)
			(layer "B.Fab")
			(hide yes)
			(effects
				(font
					(size 1 1)
					(thickness 0.15)
				)
				(justify mirror)
			)
		)
		(property "License" "Apache-2.0"
			(at 0 0 0)
			(unlocked yes)
			(layer "B.Fab")
			(hide yes)
			(effects
				(font
					(size 1 1)
					(thickness 0.15)
				)
				(justify mirror)
			)
		)
		(sheetname "/SoM_Power/")
		(sheetfile "som_power.kicad_sch")
		(attr exclude_from_pos_files exclude_from_bom)
		(fp_circle
			(center 0 0)
			(end 0.475 0)
			(stroke
				(width 0.05)
				(type default)
			)
			(fill no)
			(layer "B.CrtYd")
		)
		(fp_text user "Author: Antmicro"
			(at -0.4 -3.901 0)
			(layer "B.Fab")
			(effects
				(font
					(size 0.7 0.7)
					(thickness 0.15)
				)
				(justify left bottom mirror)
			)
		)
		(fp_text user "${REFERENCE}"
			(at -0.4 -2.7 0)
			(layer "B.Fab")
			(effects
				(font
					(size 0.7 0.7)
					(thickness 0.15)
				)
				(justify left bottom mirror)
			)
		)
		(fp_text user "License: Apache-2.0"
			(at -0.4 -5.101 0)
			(layer "B.Fab")
			(effects
				(font
					(size 0.7 0.7)
					(thickness 0.15)
				)
				(justify left bottom mirror)
			)
		)
		(pad "1" smd circle
			(at 0 0 180)
			(size 0.75 0.75)
			(layers "B.Cu" "B.Mask")
			(net 1027 "Net-(U70-~{CLR})")
			(pinfunction "1")
			(pintype "passive")
		)
	)
	(footprint "antmicro-footprints:R_0402_1005Metric"
		(layer "B.Cu")
		(at 215.538 75.970532 -90)
		(descr "Resistor SMD 0402")
		(tags "resistor SMD 0402")
		(property "Reference" "R286"
			(at -1.570532 -1.462 90)
			(layer "B.SilkS")
			(effects
				(font
					(size 0.7 0.7)
					(thickness 0.15)
				)
				(justify left bottom mirror)
			)
		)
		(property "Value" "R_10M_0402"
			(at -1.011843 -1.772047 90)
			(layer "B.Fab")
			(effects
				(font
					(size 0.7 0.7)
					(thickness 0.15)
				)
				(justify left bottom mirror)
			)
		)
		(property "Datasheet" "https://www.bourns.com/docs/product-datasheets/cr.pdf"
			(at 0 0 90)
			(layer "B.Fab")
			(hide yes)
			(effects
				(font
					(size 1.27 1.27)
					(thickness 0.15)
				)
				(justify mirror)
			)
		)
		(property "Description" "SMD Chip Resistor"
			(at 0 0 90)
			(layer "B.Fab")
			(hide yes)
			(effects
				(font
					(size 1.27 1.27)
					(thickness 0.15)
				)
				(justify mirror)
			)
		)
		(property "MPN" "CR0402-FX-1005GLF"
			(at 0 0 90)
			(unlocked yes)
			(layer "B.Fab")
			(hide yes)
			(effects
				(font
					(size 1 1)
					(thickness 0.15)
				)
				(justify mirror)
			)
		)
		(property "Manufacturer" "Bourns"
			(at 0 0 90)
			(unlocked yes)
			(layer "B.Fab")
			(hide yes)
			(effects
				(font
					(size 1 1)
					(thickness 0.15)
				)
				(justify mirror)
			)
		)
		(property "License" "Apache-2.0"
			(at 0 0 90)
			(unlocked yes)
			(layer "B.Fab")
			(hide yes)
			(effects
				(font
					(size 1 1)
					(thickness 0.15)
				)
				(justify mirror)
			)
		)
		(property "Author" "Antmicro"
			(at 0 0 90)
			(unlocked yes)
			(layer "B.Fab")
			(hide yes)
			(effects
				(font
					(size 1 1)
					(thickness 0.15)
				)
				(justify mirror)
			)
		)
		(property "Val" "10M"
			(at 0 0 90)
			(unlocked yes)
			(layer "B.Fab")
			(hide yes)
			(effects
				(font
					(size 1 1)
					(thickness 0.15)
				)
				(justify mirror)
			)
		)
		(property "Tolerance" "1%"
			(at 0 0 90)
			(unlocked yes)
			(layer "B.Fab")
			(hide yes)
			(effects
				(font
					(size 1 1)
					(thickness 0.15)
				)
				(justify mirror)
			)
		)
		(sheetname "/USB Debug, PD/")
		(sheetfile "usb_debug_pd.kicad_sch")
		(attr smd exclude_from_pos_files exclude_from_bom dnp)
		(fp_rect
			(start -0.925 0.47)
			(end 0.925 -0.47)
			(stroke
				(width 0.05)
				(type default)
			)
			(fill no)
			(layer "B.CrtYd")
		)
		(fp_rect
			(start -0.5 0.25)
			(end 0.5 -0.25)
			(stroke
				(width 0.15)
				(type solid)
			)
			(fill no)
			(layer "B.Fab")
		)
		(fp_text user "${REFERENCE}"
			(at -0.95 -3.168 90)
			(layer "B.Fab")
			(effects
				(font
					(size 0.7 0.7)
					(thickness 0.15)
				)
				(justify left bottom mirror)
			)
		)
		(fp_text user "Author: Antmicro"
			(at -0.95 -4.169 90)
			(layer "B.Fab")
			(effects
				(font
					(size 0.7 0.7)
					(thickness 0.15)
				)
				(justify left bottom mirror)
			)
		)
		(fp_text user "License: Apache-2.0"
			(at -0.95 -5.169 90)
			(layer "B.Fab")
			(effects
				(font
					(size 0.7 0.7)
					(thickness 0.15)
				)
				(justify left bottom mirror)
			)
		)
		(pad "1" smd roundrect
			(at -0.48 0 270)
			(size 0.59 0.64)
			(layers "B.Cu" "B.Mask" "B.Paste")
			(roundrect_rratio 0.25)
			(net 1 "GND")
			(pintype "passive")
		)
		(pad "2" smd roundrect
			(at 0.48 0 270)
			(size 0.59 0.64)
			(layers "B.Cu" "B.Mask" "B.Paste")
			(roundrect_rratio 0.25)
			(net 104 "/M.2/~{PEWAKE}")
			(pintype "passive")
		)
	)
	(footprint "antmicro-footprints:TP_SMD_0.75mm"
		(layer "B.Cu")
		(at 87.8 67.6 -90)
		(property "Reference" "TP104"
			(at 0.6 -0.4 90)
			(layer "B.SilkS")
			(effects
				(font
					(size 0.7 0.7)
					(thickness 0.15)
				)
				(justify left bottom mirror)
			)
		)
		(property "Value" "TP_0.75mm_SMD"
			(at 0 -1.2 90)
			(layer "B.Fab")
			(effects
				(font
					(size 0.7 0.7)
					(thickness 0.15)
				)
				(justify left bottom mirror)
			)
		)
		(property "Description" "SMT test point"
			(at 0 0 90)
			(layer "B.Fab")
			(hide yes)
			(effects
				(font
					(size 1.27 1.27)
					(thickness 0.15)
				)
				(justify mirror)
			)
		)
		(property "MPN" ""
			(at 0 0 90)
			(unlocked yes)
			(layer "B.Fab")
			(hide yes)
			(effects
				(font
					(size 1 1)
					(thickness 0.15)
				)
				(justify mirror)
			)
		)
		(property "Manufacturer" ""
			(at 0 0 90)
			(unlocked yes)
			(layer "B.Fab")
			(hide yes)
			(effects
				(font
					(size 1 1)
					(thickness 0.15)
				)
				(justify mirror)
			)
		)
		(property "Author" "Antmicro"
			(at 0 0 90)
			(unlocked yes)
			(layer "B.Fab")
			(hide yes)
			(effects
				(font
					(size 1 1)
					(thickness 0.15)
				)
				(justify mirror)
			)
		)
		(property "License" "Apache-2.0"
			(at 0 0 90)
			(unlocked yes)
			(layer "B.Fab")
			(hide yes)
			(effects
				(font
					(size 1 1)
					(thickness 0.15)
				)
				(justify mirror)
			)
		)
		(sheetname "/SoM_IO/")
		(sheetfile "som_io.kicad_sch")
		(attr exclude_from_pos_files exclude_from_bom)
		(fp_circle
			(center 0 0)
			(end 0.475 0)
			(stroke
				(width 0.05)
				(type default)
			)
			(fill no)
			(layer "B.CrtYd")
		)
		(fp_text user "${REFERENCE}"
			(at -0.4 -2.7 90)
			(layer "B.Fab")
			(effects
				(font
					(size 0.7 0.7)
					(thickness 0.15)
				)
				(justify left bottom mirror)
			)
		)
		(fp_text user "License: Apache-2.0"
			(at -0.4 -5.101 90)
			(layer "B.Fab")
			(effects
				(font
					(size 0.7 0.7)
					(thickness 0.15)
				)
				(justify left bottom mirror)
			)
		)
		(fp_text user "Author: Antmicro"
			(at -0.4 -3.901 90)
			(layer "B.Fab")
			(effects
				(font
					(size 0.7 0.7)
					(thickness 0.15)
				)
				(justify left bottom mirror)
			)
		)
		(pad "1" smd circle
			(at 0 0 270)
			(size 0.75 0.75)
			(layers "B.Cu" "B.Mask")
			(net 96 "/SoM_IO/I2C1_SDA_1V8")
			(pinfunction "1")
			(pintype "passive")
		)
	)
	(footprint "antmicro-footprints:C_0402_1005Metric"
		(layer "B.Cu")
		(at 218.62 59.98 180)
		(descr "Capacitor SMD 0402")
		(tags "capacitor SMD 0402")
		(property "Reference" "C161"
			(at 3.72 0.31 0)
			(layer "B.SilkS")
			(effects
				(font
					(size 0.7 0.7)
					(thickness 0.15)
				)
				(justify right top mirror)
			)
		)
		(property "Value" "C_1u_0402"
			(at -1.022927 -2.155213 0)
			(layer "B.Fab")
			(effects
				(font
					(size 0.7 0.7)
					(thickness 0.15)
				)
				(justify left bottom mirror)
			)
		)
		(property "Datasheet" "https://product.tdk.com/en/search/capacitor/ceramic/mlcc/info?part_no=C1005X6S1A105K050BC"
			(at 0 0 0)
			(layer "B.Fab")
			(hide yes)
			(effects
				(font
					(size 1.27 1.27)
					(thickness 0.15)
				)
				(justify mirror)
			)
		)
		(property "Description" "SMD Multilayer Ceramic Capacitor, 1 µF, 10 V, 0402 [1005 Metric], ± 10%, X6S, C"
			(at 0 0 0)
			(layer "B.Fab")
			(hide yes)
			(effects
				(font
					(size 1.27 1.27)
					(thickness 0.15)
				)
				(justify mirror)
			)
		)
		(property "Manufacturer" "TDK"
			(at 0 0 0)
			(unlocked yes)
			(layer "B.Fab")
			(hide yes)
			(effects
				(font
					(size 1 1)
					(thickness 0.15)
				)
				(justify mirror)
			)
		)
		(property "MPN" "C1005X6S1A105K050BC"
			(at 0 0 0)
			(unlocked yes)
			(layer "B.Fab")
			(hide yes)
			(effects
				(font
					(size 1 1)
					(thickness 0.15)
				)
				(justify mirror)
			)
		)
		(property "Val" "1u"
			(at 0 0 0)
			(unlocked yes)
			(layer "B.Fab")
			(hide yes)
			(effects
				(font
					(size 1 1)
					(thickness 0.15)
				)
				(justify mirror)
			)
		)
		(property "License" "Apache-2.0"
			(at 0 0 0)
			(unlocked yes)
			(layer "B.Fab")
			(hide yes)
			(effects
				(font
					(size 1 1)
					(thickness 0.15)
				)
				(justify mirror)
			)
		)
		(property "Author" "Antmicro"
			(at 0 0 0)
			(unlocked yes)
			(layer "B.Fab")
			(hide yes)
			(effects
				(font
					(size 1 1)
					(thickness 0.15)
				)
				(justify mirror)
			)
		)
		(property "Voltage" ""
			(at 0 0 0)
			(unlocked yes)
			(layer "B.Fab")
			(hide yes)
			(effects
				(font
					(size 1 1)
					(thickness 0.15)
				)
				(justify mirror)
			)
		)
		(property "Dielectric" ""
			(at 0 0 0)
			(unlocked yes)
			(layer "B.Fab")
			(hide yes)
			(effects
				(font
					(size 1 1)
					(thickness 0.15)
				)
				(justify mirror)
			)
		)
		(sheetname "/CSI/")
		(sheetfile "csi.kicad_sch")
		(attr smd)
		(fp_rect
			(start -0.925 0.47)
			(end 0.925 -0.47)
			(stroke
				(width 0.05)
				(type default)
			)
			(fill no)
			(layer "B.CrtYd")
		)
		(fp_line
			(start 0.504 0.25)
			(end 0.504 -0.248)
			(stroke
				(width 0.15)
				(type solid)
			)
			(layer "B.Fab")
		)
		(fp_line
			(start 0.504 -0.248)
			(end -0.494 -0.248)
			(stroke
				(width 0.15)
				(type solid)
			)
			(layer "B.Fab")
		)
		(fp_line
			(start -0.494 0.25)
			(end 0.504 0.25)
			(stroke
				(width 0.15)
				(type solid)
			)
			(layer "B.Fab")
		)
		(fp_line
			(start -0.494 -0.248)
			(end -0.494 0.25)
			(stroke
				(width 0.15)
				(type solid)
			)
			(layer "B.Fab")
		)
		(fp_text user "${REFERENCE}"
			(at -0.939 -4.599 0)
			(layer "B.Fab")
			(effects
				(font
					(size 0.7 0.7)
					(thickness 0.15)
				)
				(justify left bottom mirror)
			)
		)
		(fp_text user "Author: Antmicro"
			(at -0.939 -3.399 0)
			(layer "B.Fab")
			(effects
				(font
					(size 0.7 0.7)
					(thickness 0.15)
				)
				(justify left bottom mirror)
			)
		)
		(fp_text user "License: Apache-2.0"
			(at -0.939 -5.799 0)
			(layer "B.Fab")
			(effects
				(font
					(size 0.7 0.7)
					(thickness 0.15)
				)
				(justify left bottom mirror)
			)
		)
		(pad "1" smd roundrect
			(at -0.48 0 180)
			(size 0.59 0.64)
			(layers "B.Cu" "B.Mask" "B.Paste")
			(roundrect_rratio 0.25)
			(net 1 "GND")
			(pintype "passive")
		)
		(pad "2" smd roundrect
			(at 0.48 0 180)
			(size 0.59 0.64)
			(layers "B.Cu" "B.Mask" "B.Paste")
			(roundrect_rratio 0.25)
			(net 9 "/CSI/CSIB_5V")
			(pintype "passive")
		)
	)
	(footprint "antmicro-footprints:R_0402_1005Metric"
		(layer "B.Cu")
		(at 63.97 63.58 90)
		(descr "Resistor SMD 0402")
		(tags "resistor SMD 0402")
		(property "Reference" "R158"
			(at 0.78 -0.4 90)
			(layer "B.SilkS")
			(effects
				(font
					(size 0.7 0.7)
					(thickness 0.15)
				)
				(justify right top mirror)
			)
		)
		(property "Value" "R_0R_0402"
			(at -1.011843 -1.772046 90)
			(layer "B.Fab")
			(effects
				(font
					(size 0.7 0.7)
					(thickness 0.15)
				)
				(justify right top mirror)
			)
		)
		(property "Datasheet" "https://industrial.panasonic.com/cdbs/www-data/pdf/RDA0000/AOA0000C301.pdf"
			(at 0 0 90)
			(layer "B.Fab")
			(hide yes)
			(effects
				(font
					(size 1.27 1.27)
					(thickness 0.15)
				)
				(justify mirror)
			)
		)
		(property "Description" "SMD Chip Resistor, Jumper, 0 ohm, 100 mW, 0402 [1005 Metric], Thick Film, General Purpose"
			(at 0 0 90)
			(layer "B.Fab")
			(hide yes)
			(effects
				(font
					(size 1.27 1.27)
					(thickness 0.15)
				)
				(justify mirror)
			)
		)
		(property "Manufacturer" "Panasonic"
			(at 0 0 270)
			(unlocked yes)
			(layer "B.Fab")
			(hide yes)
			(effects
				(font
					(size 1 1)
					(thickness 0.15)
				)
				(justify mirror)
			)
		)
		(property "MPN" "ERJ2GE0R00X"
			(at 0 0 270)
			(unlocked yes)
			(layer "B.Fab")
			(hide yes)
			(effects
				(font
					(size 1 1)
					(thickness 0.15)
				)
				(justify mirror)
			)
		)
		(property "Val" "0R"
			(at 0 0 270)
			(unlocked yes)
			(layer "B.Fab")
			(hide yes)
			(effects
				(font
					(size 1 1)
					(thickness 0.15)
				)
				(justify mirror)
			)
		)
		(property "License" "Apache-2.0"
			(at 0 0 270)
			(unlocked yes)
			(layer "B.Fab")
			(hide yes)
			(effects
				(font
					(size 1 1)
					(thickness 0.15)
				)
				(justify mirror)
			)
		)
		(property "Author" "Antmicro"
			(at 0 0 270)
			(unlocked yes)
			(layer "B.Fab")
			(hide yes)
			(effects
				(font
					(size 1 1)
					(thickness 0.15)
				)
				(justify mirror)
			)
		)
		(property "Tolerance" "~"
			(at 0 0 270)
			(unlocked yes)
			(layer "B.Fab")
			(hide yes)
			(effects
				(font
					(size 1 1)
					(thickness 0.15)
				)
				(justify mirror)
			)
		)
		(property "Current" "1A"
			(at 0 0 270)
			(unlocked yes)
			(layer "B.Fab")
			(hide yes)
			(effects
				(font
					(size 1 1)
					(thickness 0.15)
				)
				(justify mirror)
			)
		)
		(sheetname "/CSI/")
		(sheetfile "csi.kicad_sch")
		(attr smd)
		(fp_poly
			(pts
				(xy -0.925 0.47) (xy -0.925 -0.47) (xy 0.925 -0.47) (xy 0.925 0.47)
			)
			(stroke
				(width 0.05)
				(type default)
			)
			(fill no)
			(layer "B.CrtYd")
		)
		(fp_poly
			(pts
				(xy -0.5 0.25) (xy -0.5 -0.25) (xy 0.5 -0.25) (xy 0.5 0.25)
			)
			(stroke
				(width 0.15)
				(type solid)
			)
			(fill no)
			(layer "B.Fab")
		)
		(fp_text user "Author: Antmicro"
			(at -0.95 -4.169 90)
			(layer "B.Fab")
			(effects
				(font
					(size 0.7 0.7)
					(thickness 0.15)
				)
				(justify right top mirror)
			)
		)
		(fp_text user "License: Apache-2.0"
			(at -0.949999 -5.169 90)
			(layer "B.Fab")
			(effects
				(font
					(size 0.7 0.7)
					(thickness 0.15)
				)
				(justify right top mirror)
			)
		)
		(fp_text user "${REFERENCE}"
			(at -0.95 -3.168 90)
			(layer "B.Fab")
			(effects
				(font
					(size 0.7 0.7)
					(thickness 0.15)
				)
				(justify right top mirror)
			)
		)
		(pad "1" smd roundrect
			(at -0.48 0 90)
			(size 0.59 0.64)
			(layers "B.Cu" "B.Mask" "B.Paste")
			(roundrect_rratio 0.25)
			(net 979 "/CSI/CSIA_I2C_VCC")
			(pintype "passive")
		)
		(pad "2" smd roundrect
			(at 0.48 0 90)
			(size 0.59 0.64)
			(layers "B.Cu" "B.Mask" "B.Paste")
			(roundrect_rratio 0.25)
			(net 2 "+3V3")
			(pintype "passive")
		)
	)
	(footprint "antmicro-footprints:R_0402_1005Metric"
		(layer "B.Cu")
		(at 157.15 66.51 180)
		(descr "Resistor SMD 0402")
		(tags "resistor SMD 0402")
		(property "Reference" "R293"
			(at -1.05 -4.22 0)
			(layer "B.SilkS")
			(effects
				(font
					(size 0.7 0.7)
					(thickness 0.15)
				)
				(justify left bottom mirror)
			)
		)
		(property "Value" "R_0R_0402"
			(at -1.011843 -1.772047 0)
			(layer "B.Fab")
			(effects
				(font
					(size 0.7 0.7)
					(thickness 0.15)
				)
				(justify left bottom mirror)
			)
		)
		(property "Datasheet" "https://industrial.panasonic.com/cdbs/www-data/pdf/RDA0000/AOA0000C301.pdf"
			(at 0 0 0)
			(layer "B.Fab")
			(hide yes)
			(effects
				(font
					(size 1.27 1.27)
					(thickness 0.15)
				)
				(justify mirror)
			)
		)
		(property "Description" "SMD Chip Resistor, Jumper, 0 ohm, 100 mW, 0402 [1005 Metric], Thick Film, General Purpose"
			(at 0 0 0)
			(layer "B.Fab")
			(hide yes)
			(effects
				(font
					(size 1.27 1.27)
					(thickness 0.15)
				)
				(justify mirror)
			)
		)
		(property "MPN" "ERJ2GE0R00X"
			(at 0 0 0)
			(unlocked yes)
			(layer "B.Fab")
			(hide yes)
			(effects
				(font
					(size 1 1)
					(thickness 0.15)
				)
				(justify mirror)
			)
		)
		(property "Manufacturer" "Panasonic"
			(at 0 0 0)
			(unlocked yes)
			(layer "B.Fab")
			(hide yes)
			(effects
				(font
					(size 1 1)
					(thickness 0.15)
				)
				(justify mirror)
			)
		)
		(property "License" "Apache-2.0"
			(at 0 0 0)
			(unlocked yes)
			(layer "B.Fab")
			(hide yes)
			(effects
				(font
					(size 1 1)
					(thickness 0.15)
				)
				(justify mirror)
			)
		)
		(property "Author" "Antmicro"
			(at 0 0 0)
			(unlocked yes)
			(layer "B.Fab")
			(hide yes)
			(effects
				(font
					(size 1 1)
					(thickness 0.15)
				)
				(justify mirror)
			)
		)
		(property "Val" "0R"
			(at 0 0 0)
			(unlocked yes)
			(layer "B.Fab")
			(hide yes)
			(effects
				(font
					(size 1 1)
					(thickness 0.15)
				)
				(justify mirror)
			)
		)
		(property "Tolerance" "~"
			(at 0 0 0)
			(unlocked yes)
			(layer "B.Fab")
			(hide yes)
			(effects
				(font
					(size 1 1)
					(thickness 0.15)
				)
				(justify mirror)
			)
		)
		(property "Current" "1A"
			(at 0 0 0)
			(unlocked yes)
			(layer "B.Fab")
			(hide yes)
			(effects
				(font
					(size 1 1)
					(thickness 0.15)
				)
				(justify mirror)
			)
		)
		(sheetname "/SoM_IO2/")
		(sheetfile "som_io2.kicad_sch")
		(attr smd exclude_from_pos_files exclude_from_bom dnp)
		(fp_rect
			(start -0.925 0.47)
			(end 0.925 -0.47)
			(stroke
				(width 0.05)
				(type default)
			)
			(fill no)
			(layer "B.CrtYd")
		)
		(fp_rect
			(start -0.5 0.25)
			(end 0.5 -0.25)
			(stroke
				(width 0.15)
				(type solid)
			)
			(fill no)
			(layer "B.Fab")
		)
		(fp_text user "${REFERENCE}"
			(at -0.95 -3.168 0)
			(layer "B.Fab")
			(effects
				(font
					(size 0.7 0.7)
					(thickness 0.15)
				)
				(justify left bottom mirror)
			)
		)
		(fp_text user "License: Apache-2.0"
			(at -0.95 -5.169 0)
			(layer "B.Fab")
			(effects
				(font
					(size 0.7 0.7)
					(thickness 0.15)
				)
				(justify left bottom mirror)
			)
		)
		(fp_text user "Author: Antmicro"
			(at -0.95 -4.169 0)
			(layer "B.Fab")
			(effects
				(font
					(size 0.7 0.7)
					(thickness 0.15)
				)
				(justify left bottom mirror)
			)
		)
		(pad "1" smd roundrect
			(at -0.48 0 180)
			(size 0.59 0.64)
			(layers "B.Cu" "B.Mask" "B.Paste")
			(roundrect_rratio 0.25)
			(net 1029 "Net-(U59-B2Y)")
			(pintype "passive")
		)
		(pad "2" smd roundrect
			(at 0.48 0 180)
			(size 0.59 0.64)
			(layers "B.Cu" "B.Mask" "B.Paste")
			(roundrect_rratio 0.25)
			(net 715 "/SoM_IO2/JTAG_TDI")
			(pintype "passive")
		)
	)
	(footprint "antmicro-footprints:SOT-523"
		(layer "B.Cu")
		(at 97.75 60.25 -90)
		(property "Reference" "Q22"
			(at -1 1.25 90)
			(layer "B.SilkS")
			(effects
				(font
					(size 0.7 0.7)
					(thickness 0.15)
				)
				(justify left bottom mirror)
			)
		)
		(property "Value" "DMG1012T-7"
			(at 0.1 -1.824 90)
			(layer "B.Fab")
			(effects
				(font
					(size 0.7 0.7)
					(thickness 0.15)
				)
				(justify left bottom mirror)
			)
		)
		(property "Datasheet" "https://www.diodes.com/assets/Datasheets/ds31783.pdf"
			(at 0 0 90)
			(layer "B.Fab")
			(hide yes)
			(effects
				(font
					(size 1.27 1.27)
					(thickness 0.15)
				)
				(justify mirror)
			)
		)
		(property "Description" "Power MOSFET, N Channel, 20 V, 630 mA, 0.3 ohm, SOT-523, Surface Mount"
			(at 0 0 90)
			(layer "B.Fab")
			(hide yes)
			(effects
				(font
					(size 1.27 1.27)
					(thickness 0.15)
				)
				(justify mirror)
			)
		)
		(property "MPN" "DMG1012T-7"
			(at 0 0 270)
			(unlocked yes)
			(layer "B.Fab")
			(hide yes)
			(effects
				(font
					(size 1 1)
					(thickness 0.15)
				)
				(justify mirror)
			)
		)
		(property "Manufacturer" "Diodes Incorporated"
			(at 0 0 270)
			(unlocked yes)
			(layer "B.Fab")
			(hide yes)
			(effects
				(font
					(size 1 1)
					(thickness 0.15)
				)
				(justify mirror)
			)
		)
		(property "Author" "Antmicro"
			(at 0 0 270)
			(unlocked yes)
			(layer "B.Fab")
			(hide yes)
			(effects
				(font
					(size 1 1)
					(thickness 0.15)
				)
				(justify mirror)
			)
		)
		(property "License" "Apache-2.0"
			(at 0 0 270)
			(unlocked yes)
			(layer "B.Fab")
			(hide yes)
			(effects
				(font
					(size 1 1)
					(thickness 0.15)
				)
				(justify mirror)
			)
		)
		(sheetname "/SoM_Power/")
		(sheetfile "som_power.kicad_sch")
		(attr smd)
		(fp_line
			(start -0.725 0.551)
			(end -0.277 0.551)
			(stroke
				(width 0.15)
				(type solid)
			)
			(layer "B.SilkS")
		)
		(fp_line
			(start -0.277 0.551)
			(end -0.277 0.75)
			(stroke
				(width 0.15)
				(type solid)
			)
			(layer "B.SilkS")
		)
		(fp_line
			(start -0.927 0.351)
			(end -0.725 0.551)
			(stroke
				(width 0.15)
				(type solid)
			)
			(layer "B.SilkS")
		)
		(fp_line
			(start -0.927 0.051)
			(end -0.927 0.351)
			(stroke
				(width 0.15)
				(type solid)
			)
			(layer "B.SilkS")
		)
		(fp_circle
			(center -0.9652 -0.9652)
			(end -0.9152 -0.9652)
			(stroke
				(width 0.15)
				(type solid)
			)
			(fill yes)
			(layer "B.SilkS")
		)
		(fp_line
			(start -1.12 1.16)
			(end 1.1 1.16)
			(stroke
				(width 0.05)
				(type solid)
			)
			(layer "B.CrtYd")
		)
		(fp_line
			(start -1.12 1.16)
			(end -1.12 -1.15)
			(stroke
				(width 0.05)
				(type solid)
			)
			(layer "B.CrtYd")
		)
		(fp_line
			(start 1.1 1.16)
			(end 1.1 -1.15)
			(stroke
				(width 0.05)
				(type solid)
			)
			(layer "B.CrtYd")
		)
		(fp_line
			(start -1.12 -1.15)
			(end 1.1 -1.15)
			(stroke
				(width 0.05)
				(type solid)
			)
			(layer "B.CrtYd")
		)
		(fp_line
			(start -0.652 0.425)
			(end -0.802 0.276)
			(stroke
				(width 0.15)
				(type solid)
			)
			(layer "B.Fab")
		)
		(fp_line
			(start 0.8 0.425)
			(end -0.652 0.425)
			(stroke
				(width 0.15)
				(type solid)
			)
			(layer "B.Fab")
		)
		(fp_line
			(start 0.8 0.425)
			(end 0.8 -0.424)
			(stroke
				(width 0.15)
				(type solid)
			)
			(layer "B.Fab")
		)
		(fp_line
			(start -0.802 0.276)
			(end -0.802 -0.424)
			(stroke
				(width 0.15)
				(type solid)
			)
			(layer "B.Fab")
		)
		(fp_line
			(start 0.8 -0.424)
			(end -0.802 -0.424)
			(stroke
				(width 0.15)
				(type solid)
			)
			(layer "B.Fab")
		)
		(fp_circle
			(center -0.9652 -0.9652)
			(end -0.9144 -0.9652)
			(stroke
				(width 0.15)
				(type solid)
			)
			(fill no)
			(layer "B.Fab")
		)
		(fp_text user "Author: Antmicro"
			(at -1.12 -6.224 90)
			(layer "B.Fab")
			(effects
				(font
					(size 0.7 0.7)
					(thickness 0.15)
				)
				(justify left bottom mirror)
			)
		)
		(fp_text user "License: Apache-2.0"
			(at -1.12 -5.024 90)
			(layer "B.Fab")
			(effects
				(font
					(size 0.7 0.7)
					(thickness 0.15)
				)
				(justify left bottom mirror)
			)
		)
		(fp_text user "${REFERENCE}"
			(at -1.12 -3.824 90)
			(layer "B.Fab")
			(effects
				(font
					(size 0.7 0.7)
					(thickness 0.15)
				)
				(justify left bottom mirror)
			)
		)
		(pad "1" smd rect
			(at -0.5 -0.65 270)
			(size 0.4 0.51)
			(layers "B.Cu" "B.Mask" "B.Paste")
			(net 892 "Net-(Q22-G)")
			(pinfunction "G")
			(pintype "input")
		)
		(pad "2" smd rect
			(at 0.498 -0.65 270)
			(size 0.4 0.51)
			(layers "B.Cu" "B.Mask" "B.Paste")
			(net 1 "GND")
			(pinfunction "S")
			(pintype "passive")
		)
		(pad "3" smd rect
			(at 0 0.652 270)
			(size 0.4 0.51)
			(layers "B.Cu" "B.Mask" "B.Paste")
			(net 524 "Net-(Q22-D)")
			(pinfunction "D")
			(pintype "passive")
		)
	)
	(footprint "antmicro-footprints:R_0402_1005Metric"
		(layer "B.Cu")
		(at 205.4 101.8 180)
		(descr "Resistor SMD 0402")
		(tags "resistor SMD 0402")
		(property "Reference" "R253"
			(at -1.6 0.6 0)
			(layer "B.SilkS")
			(effects
				(font
					(size 0.7 0.7)
					(thickness 0.15)
				)
				(justify left bottom mirror)
			)
		)
		(property "Value" "R_0R_0402"
			(at -1.011843 -1.772046 0)
			(layer "B.Fab")
			(effects
				(font
					(size 0.7 0.7)
					(thickness 0.15)
				)
				(justify left bottom mirror)
			)
		)
		(property "Datasheet" "https://industrial.panasonic.com/cdbs/www-data/pdf/RDA0000/AOA0000C301.pdf"
			(at 0 0 0)
			(layer "B.Fab")
			(hide yes)
			(effects
				(font
					(size 1.27 1.27)
					(thickness 0.15)
				)
				(justify mirror)
			)
		)
		(property "Description" "SMD Chip Resistor, Jumper, 0 ohm, 100 mW, 0402 [1005 Metric], Thick Film, General Purpose"
			(at 0 0 0)
			(layer "B.Fab")
			(hide yes)
			(effects
				(font
					(size 1.27 1.27)
					(thickness 0.15)
				)
				(justify mirror)
			)
		)
		(property "Manufacturer" "Panasonic"
			(at 0 0 0)
			(unlocked yes)
			(layer "B.Fab")
			(hide yes)
			(effects
				(font
					(size 1 1)
					(thickness 0.15)
				)
				(justify mirror)
			)
		)
		(property "MPN" "ERJ2GE0R00X"
			(at 0 0 0)
			(unlocked yes)
			(layer "B.Fab")
			(hide yes)
			(effects
				(font
					(size 1 1)
					(thickness 0.15)
				)
				(justify mirror)
			)
		)
		(property "Val" "0R"
			(at 0 0 0)
			(unlocked yes)
			(layer "B.Fab")
			(hide yes)
			(effects
				(font
					(size 1 1)
					(thickness 0.15)
				)
				(justify mirror)
			)
		)
		(property "License" "Apache-2.0"
			(at 0 0 0)
			(unlocked yes)
			(layer "B.Fab")
			(hide yes)
			(effects
				(font
					(size 1 1)
					(thickness 0.15)
				)
				(justify mirror)
			)
		)
		(property "Author" "Antmicro"
			(at 0 0 0)
			(unlocked yes)
			(layer "B.Fab")
			(hide yes)
			(effects
				(font
					(size 1 1)
					(thickness 0.15)
				)
				(justify mirror)
			)
		)
		(property "Tolerance" "~"
			(at 0 0 0)
			(unlocked yes)
			(layer "B.Fab")
			(hide yes)
			(effects
				(font
					(size 1 1)
					(thickness 0.15)
				)
				(justify mirror)
			)
		)
		(property "Current" "1A"
			(at 0 0 0)
			(unlocked yes)
			(layer "B.Fab")
			(hide yes)
			(effects
				(font
					(size 1 1)
					(thickness 0.15)
				)
				(justify mirror)
			)
		)
		(sheetname "/Recovery USB/")
		(sheetfile "recovery_usb.kicad_sch")
		(attr smd exclude_from_pos_files exclude_from_bom dnp)
		(fp_poly
			(pts
				(xy -0.925 0.47) (xy 0.925 0.47) (xy 0.925 -0.47) (xy -0.925 -0.47)
			)
			(stroke
				(width 0.05)
				(type default)
			)
			(fill no)
			(layer "B.CrtYd")
		)
		(fp_poly
			(pts
				(xy -0.5 0.25) (xy 0.5 0.25) (xy 0.5 -0.25) (xy -0.5 -0.25)
			)
			(stroke
				(width 0.15)
				(type solid)
			)
			(fill no)
			(layer "B.Fab")
		)
		(fp_text user "License: Apache-2.0"
			(at -0.949999 -5.169 0)
			(layer "B.Fab")
			(effects
				(font
					(size 0.7 0.7)
					(thickness 0.15)
				)
				(justify left bottom mirror)
			)
		)
		(fp_text user "${REFERENCE}"
			(at -0.95 -3.168 0)
			(layer "B.Fab")
			(effects
				(font
					(size 0.7 0.7)
					(thickness 0.15)
				)
				(justify left bottom mirror)
			)
		)
		(fp_text user "Author: Antmicro"
			(at -0.95 -4.169 0)
			(layer "B.Fab")
			(effects
				(font
					(size 0.7 0.7)
					(thickness 0.15)
				)
				(justify left bottom mirror)
			)
		)
		(pad "1" smd roundrect
			(at -0.48 0 180)
			(size 0.59 0.64)
			(layers "B.Cu" "B.Mask" "B.Paste")
			(roundrect_rratio 0.25)
			(net 1 "GND")
			(pintype "passive")
		)
		(pad "2" smd roundrect
			(at 0.48 0 180)
			(size 0.59 0.64)
			(layers "B.Cu" "B.Mask" "B.Paste")
			(roundrect_rratio 0.25)
			(net 1011 "/Recovery USB/USBC2_ADDR")
			(pintype "passive")
		)
	)
	(footprint "antmicro-footprints:SOIC-8_3.9x4.9x1.75mm_P1.27mm"
		(layer "B.Cu")
		(at 121 146.999 -90)
		(property "Reference" "U54"
			(at 0 2.85 90)
			(layer "B.SilkS")
			(effects
				(font
					(size 0.7 0.7)
					(thickness 0.15)
				)
				(justify left bottom mirror)
			)
		)
		(property "Value" "AT24CS01_SOIC8"
			(at 0 -3.65 90)
			(layer "B.Fab")
			(effects
				(font
					(size 0.7 0.7)
					(thickness 0.15)
				)
				(justify left bottom mirror)
			)
		)
		(property "Datasheet" "https://ww1.microchip.com/downloads/aemDocuments/documents/MPD/ProductDocuments/DataSheets/20006330A.pdf"
			(at 0 0 90)
			(layer "B.Fab")
			(hide yes)
			(effects
				(font
					(size 1.27 1.27)
					(thickness 0.15)
				)
				(justify mirror)
			)
		)
		(property "Description" "EEPROM, 1 Kbit, 128 x 8bit, Serial I2C (2-Wire), 1 MHz, SOIC-8"
			(at 0 0 90)
			(layer "B.Fab")
			(hide yes)
			(effects
				(font
					(size 1.27 1.27)
					(thickness 0.15)
				)
				(justify mirror)
			)
		)
		(property "Manufacturer" "Microchip Technology"
			(at 0 0 270)
			(unlocked yes)
			(layer "B.Fab")
			(hide yes)
			(effects
				(font
					(size 1 1)
					(thickness 0.15)
				)
				(justify mirror)
			)
		)
		(property "MPN" "AT24CS01-SSHM-B"
			(at 0 0 270)
			(unlocked yes)
			(layer "B.Fab")
			(hide yes)
			(effects
				(font
					(size 1 1)
					(thickness 0.15)
				)
				(justify mirror)
			)
		)
		(property "Author" "Antmicro"
			(at 0 0 270)
			(unlocked yes)
			(layer "B.Fab")
			(hide yes)
			(effects
				(font
					(size 1 1)
					(thickness 0.15)
				)
				(justify mirror)
			)
		)
		(property "License" "Apache-2.0"
			(at 0 0 270)
			(unlocked yes)
			(layer "B.Fab")
			(hide yes)
			(effects
				(font
					(size 1 1)
					(thickness 0.15)
				)
				(justify mirror)
			)
		)
		(sheetname "/Peripherals/")
		(sheetfile "peripherals.kicad_sch")
		(attr smd)
		(fp_line
			(start -1.95 2.452)
			(end 1.95 2.45)
			(stroke
				(width 0.15)
				(type solid)
			)
			(layer "B.SilkS")
		)
		(fp_line
			(start -1.95 -2.45)
			(end 1.95 -2.45)
			(stroke
				(width 0.15)
				(type solid)
			)
			(layer "B.SilkS")
		)
		(fp_circle
			(center -2.4 2.45)
			(end -2.35 2.4)
			(stroke
				(width 0.15)
				(type solid)
			)
			(fill yes)
			(layer "B.SilkS")
		)
		(fp_rect
			(start -3.625 2.7)
			(end 3.625 -2.7)
			(stroke
				(width 0.05)
				(type solid)
			)
			(fill no)
			(layer "B.CrtYd")
		)
		(fp_line
			(start -0.683 2.452)
			(end 1.949 2.452)
			(stroke
				(width 0.15)
				(type solid)
			)
			(layer "B.Fab")
		)
		(fp_line
			(start 1.949 2.452)
			(end 1.949 -2.45)
			(stroke
				(width 0.15)
				(type solid)
			)
			(layer "B.Fab")
		)
		(fp_line
			(start -1.95 1.18)
			(end -0.683 2.452)
			(stroke
				(width 0.15)
				(type solid)
			)
			(layer "B.Fab")
		)
		(fp_line
			(start -1.95 -2.45)
			(end -1.95 1.18)
			(stroke
				(width 0.15)
				(type solid)
			)
			(layer "B.Fab")
		)
		(fp_line
			(start 1.949 -2.45)
			(end -1.95 -2.45)
			(stroke
				(width 0.15)
				(type solid)
			)
			(layer "B.Fab")
		)
		(fp_text user "License: Apache-2.0"
			(at -3.476 -5.099 90)
			(layer "B.Fab")
			(effects
				(font
					(size 0.7 0.7)
					(thickness 0.15)
				)
				(justify left bottom mirror)
			)
		)
		(fp_text user "Author: Antmicro"
			(at -3.476 -6.099 90)
			(layer "B.Fab")
			(effects
				(font
					(size 0.7 0.7)
					(thickness 0.15)
				)
				(justify left bottom mirror)
			)
		)
		(fp_text user "${REFERENCE}"
			(at -3.476 -7.099 90)
			(layer "B.Fab")
			(effects
				(font
					(size 0.7 0.7)
					(thickness 0.15)
				)
				(justify left bottom mirror)
			)
		)
		(pad "1" smd roundrect
			(at -2.714 1.905 180)
			(size 0.65 1.525)
			(layers "B.Cu" "B.Mask" "B.Paste")
			(roundrect_rratio 0.25)
			(net 1 "GND")
			(pinfunction "A0")
			(pintype "input")
		)
		(pad "2" smd roundrect
			(at -2.714 0.635 180)
			(size 0.65 1.525)
			(layers "B.Cu" "B.Mask" "B.Paste")
			(roundrect_rratio 0.25)
			(net 1 "GND")
			(pinfunction "A1")
			(pintype "input")
		)
		(pad "3" smd roundrect
			(at -2.714 -0.632 180)
			(size 0.65 1.525)
			(layers "B.Cu" "B.Mask" "B.Paste")
			(roundrect_rratio 0.25)
			(net 1 "GND")
			(pinfunction "A2")
			(pintype "input")
		)
		(pad "4" smd roundrect
			(at -2.714 -1.902 180)
			(size 0.65 1.525)
			(layers "B.Cu" "B.Mask" "B.Paste")
			(roundrect_rratio 0.25)
			(net 1 "GND")
			(pinfunction "GND")
			(pintype "power_in")
		)
		(pad "5" smd roundrect
			(at 2.712 -1.902 180)
			(size 0.65 1.525)
			(layers "B.Cu" "B.Mask" "B.Paste")
			(roundrect_rratio 0.25)
			(net 853 "/I2C_{SYS}.SCL")
			(pinfunction "SDA")
			(pintype "bidirectional")
		)
		(pad "6" smd roundrect
			(at 2.712 -0.632 180)
			(size 0.65 1.525)
			(layers "B.Cu" "B.Mask" "B.Paste")
			(roundrect_rratio 0.25)
			(net 850 "/I2C_{SYS}.SDA")
			(pinfunction "SCL")
			(pintype "input")
		)
		(pad "7" smd roundrect
			(at 2.712 0.635 180)
			(size 0.65 1.525)
			(layers "B.Cu" "B.Mask" "B.Paste")
			(roundrect_rratio 0.25)
			(net 1 "GND")
			(pinfunction "WP")
			(pintype "input")
		)
		(pad "8" smd roundrect
			(at 2.712 1.905 180)
			(size 0.65 1.525)
			(layers "B.Cu" "B.Mask" "B.Paste")
			(roundrect_rratio 0.25)
			(net 4 "+3V3_AON")
			(pinfunction "VCC")
			(pintype "power_in")
		)
	)
	(footprint "antmicro-footprints:R_0402_1005Metric"
		(layer "B.Cu")
		(at 212.8 89.8)
		(descr "Resistor SMD 0402")
		(tags "resistor SMD 0402")
		(property "Reference" "R135"
			(at -3.9 -0.3 0)
			(layer "B.SilkS")
			(effects
				(font
					(size 0.7 0.7)
					(thickness 0.15)
				)
				(justify right top mirror)
			)
		)
		(property "Value" "R_1k_0402"
			(at -1.011843 -1.772046 0)
			(layer "B.Fab")
			(effects
				(font
					(size 0.7 0.7)
					(thickness 0.15)
				)
				(justify right top mirror)
			)
		)
		(property "Datasheet" "https://www.bourns.com/docs/product-datasheets/cr.pdf"
			(at 0 0 0)
			(layer "B.Fab")
			(hide yes)
			(effects
				(font
					(size 1.27 1.27)
					(thickness 0.15)
				)
				(justify mirror)
			)
		)
		(property "Description" "SMD Chip Resistor, 1 kohm, ± 1%, 63 mW, 0402 [1005 Metric], Thick Film, General Purpose"
			(at 0 0 0)
			(layer "B.Fab")
			(hide yes)
			(effects
				(font
					(size 1.27 1.27)
					(thickness 0.15)
				)
				(justify mirror)
			)
		)
		(property "Manufacturer" "Bourns"
			(at 0 0 180)
			(unlocked yes)
			(layer "B.Fab")
			(hide yes)
			(effects
				(font
					(size 1 1)
					(thickness 0.15)
				)
				(justify mirror)
			)
		)
		(property "MPN" "CR0402-FX-1001GLF"
			(at 0 0 180)
			(unlocked yes)
			(layer "B.Fab")
			(hide yes)
			(effects
				(font
					(size 1 1)
					(thickness 0.15)
				)
				(justify mirror)
			)
		)
		(property "Val" "1k"
			(at 0 0 180)
			(unlocked yes)
			(layer "B.Fab")
			(hide yes)
			(effects
				(font
					(size 1 1)
					(thickness 0.15)
				)
				(justify mirror)
			)
		)
		(property "License" "Apache-2.0"
			(at 0 0 180)
			(unlocked yes)
			(layer "B.Fab")
			(hide yes)
			(effects
				(font
					(size 1 1)
					(thickness 0.15)
				)
				(justify mirror)
			)
		)
		(property "Author" "Antmicro"
			(at 0 0 180)
			(unlocked yes)
			(layer "B.Fab")
			(hide yes)
			(effects
				(font
					(size 1 1)
					(thickness 0.15)
				)
				(justify mirror)
			)
		)
		(property "Tolerance" "1%"
			(at 0 0 180)
			(unlocked yes)
			(layer "B.Fab")
			(hide yes)
			(effects
				(font
					(size 1 1)
					(thickness 0.15)
				)
				(justify mirror)
			)
		)
		(sheetname "/USB DP Alt mode/")
		(sheetfile "usb_dp.kicad_sch")
		(attr smd exclude_from_pos_files exclude_from_bom dnp)
		(fp_poly
			(pts
				(xy -0.925 0.47) (xy 0.925 0.47) (xy 0.925 -0.47) (xy -0.925 -0.47)
			)
			(stroke
				(width 0.05)
				(type default)
			)
			(fill no)
			(layer "B.CrtYd")
		)
		(fp_poly
			(pts
				(xy -0.5 0.25) (xy 0.5 0.25) (xy 0.5 -0.25) (xy -0.5 -0.25)
			)
			(stroke
				(width 0.15)
				(type solid)
			)
			(fill no)
			(layer "B.Fab")
		)
		(fp_text user "License: Apache-2.0"
			(at -0.949999 -5.169 0)
			(layer "B.Fab")
			(effects
				(font
					(size 0.7 0.7)
					(thickness 0.15)
				)
				(justify right top mirror)
			)
		)
		(fp_text user "${REFERENCE}"
			(at -0.95 -3.168 0)
			(layer "B.Fab")
			(effects
				(font
					(size 0.7 0.7)
					(thickness 0.15)
				)
				(justify right top mirror)
			)
		)
		(fp_text user "Author: Antmicro"
			(at -0.95 -4.169 0)
			(layer "B.Fab")
			(effects
				(font
					(size 0.7 0.7)
					(thickness 0.15)
				)
				(justify right top mirror)
			)
		)
		(pad "1" smd roundrect
			(at -0.48 0)
			(size 0.59 0.64)
			(layers "B.Cu" "B.Mask" "B.Paste")
			(roundrect_rratio 0.25)
			(net 966 "/USB DP Alt mode/USBC1_DPEQ0")
			(pintype "passive")
		)
		(pad "2" smd roundrect
			(at 0.48 0)
			(size 0.59 0.64)
			(layers "B.Cu" "B.Mask" "B.Paste")
			(roundrect_rratio 0.25)
			(net 1 "GND")
			(pintype "passive")
		)
	)
	(footprint "antmicro-footprints:C_0402_1005Metric"
		(layer "B.Cu")
		(at 205.3 130.5 -90)
		(descr "Capacitor SMD 0402")
		(tags "capacitor SMD 0402")
		(property "Reference" "C85"
			(at 0.9 -0.5 90)
			(layer "B.SilkS")
			(effects
				(font
					(size 0.7 0.7)
					(thickness 0.15)
				)
				(justify left bottom mirror)
			)
		)
		(property "Value" "C_100n_0402"
			(at -1.022927 -2.155213 90)
			(layer "B.Fab")
			(effects
				(font
					(size 0.7 0.7)
					(thickness 0.15)
				)
				(justify left bottom mirror)
			)
		)
		(property "Datasheet" "https://www.murata.com/products/productdetail?partno=GRM155R61H104KE14%23"
			(at 0 0 90)
			(layer "B.Fab")
			(hide yes)
			(effects
				(font
					(size 1.27 1.27)
					(thickness 0.15)
				)
				(justify mirror)
			)
		)
		(property "Description" "SMD Multilayer Ceramic Capacitor, 0.1 µF, 50 V, 0402 [1005 Metric], ± 10%, X5R, GRM Series"
			(at 0 0 90)
			(layer "B.Fab")
			(hide yes)
			(effects
				(font
					(size 1.27 1.27)
					(thickness 0.15)
				)
				(justify mirror)
			)
		)
		(property "MPN" "GRM155R61H104KE14D"
			(at 0 0 90)
			(unlocked yes)
			(layer "B.Fab")
			(hide yes)
			(effects
				(font
					(size 1 1)
					(thickness 0.15)
				)
				(justify mirror)
			)
		)
		(property "Val" "100n"
			(at 0 0 90)
			(unlocked yes)
			(layer "B.Fab")
			(hide yes)
			(effects
				(font
					(size 1 1)
					(thickness 0.15)
				)
				(justify mirror)
			)
		)
		(property "Voltage" "50V"
			(at 0 0 90)
			(unlocked yes)
			(layer "B.Fab")
			(hide yes)
			(effects
				(font
					(size 1 1)
					(thickness 0.15)
				)
				(justify mirror)
			)
		)
		(property "Dielectric" "X5R"
			(at 0 0 90)
			(unlocked yes)
			(layer "B.Fab")
			(hide yes)
			(effects
				(font
					(size 1 1)
					(thickness 0.15)
				)
				(justify mirror)
			)
		)
		(property "Manufacturer" "Murata"
			(at 0 0 90)
			(unlocked yes)
			(layer "B.Fab")
			(hide yes)
			(effects
				(font
					(size 1 1)
					(thickness 0.15)
				)
				(justify mirror)
			)
		)
		(property "License" "Apache-2.0"
			(at 0 0 90)
			(unlocked yes)
			(layer "B.Fab")
			(hide yes)
			(effects
				(font
					(size 1 1)
					(thickness 0.15)
				)
				(justify mirror)
			)
		)
		(property "Author" "Antmicro"
			(at 0 0 90)
			(unlocked yes)
			(layer "B.Fab")
			(hide yes)
			(effects
				(font
					(size 1 1)
					(thickness 0.15)
				)
				(justify mirror)
			)
		)
		(sheetname "/USB Hub/")
		(sheetfile "usb_hub.kicad_sch")
		(attr smd)
		(fp_poly
			(pts
				(xy -0.925 0.47) (xy 0.925 0.47) (xy 0.925 -0.47) (xy -0.925 -0.47)
			)
			(stroke
				(width 0.05)
				(type default)
			)
			(fill no)
			(layer "B.CrtYd")
		)
		(fp_line
			(start -0.494 0.25)
			(end 0.504 0.25)
			(stroke
				(width 0.15)
				(type solid)
			)
			(layer "B.Fab")
		)
		(fp_line
			(start 0.504 0.25)
			(end 0.504 -0.248)
			(stroke
				(width 0.15)
				(type solid)
			)
			(layer "B.Fab")
		)
		(fp_line
			(start -0.494 -0.248)
			(end -0.494 0.25)
			(stroke
				(width 0.15)
				(type solid)
			)
			(layer "B.Fab")
		)
		(fp_line
			(start 0.504 -0.248)
			(end -0.494 -0.248)
			(stroke
				(width 0.15)
				(type solid)
			)
			(layer "B.Fab")
		)
		(fp_text user "Author: Antmicro"
			(at -0.939 -3.399 90)
			(layer "B.Fab")
			(effects
				(font
					(size 0.7 0.7)
					(thickness 0.15)
				)
				(justify left bottom mirror)
			)
		)
		(fp_text user "${REFERENCE}"
			(at -0.939 -4.599 90)
			(layer "B.Fab")
			(effects
				(font
					(size 0.7 0.7)
					(thickness 0.15)
				)
				(justify left bottom mirror)
			)
		)
		(fp_text user "License: Apache-2.0"
			(at -0.939 -5.799 90)
			(layer "B.Fab")
			(effects
				(font
					(size 0.7 0.7)
					(thickness 0.15)
				)
				(justify left bottom mirror)
			)
		)
		(pad "1" smd roundrect
			(at -0.48 0 270)
			(size 0.59 0.64)
			(layers "B.Cu" "B.Mask" "B.Paste")
			(roundrect_rratio 0.25)
			(net 1 "GND")
			(pintype "passive")
		)
		(pad "2" smd roundrect
			(at 0.48 0 270)
			(size 0.59 0.64)
			(layers "B.Cu" "B.Mask" "B.Paste")
			(roundrect_rratio 0.25)
			(net 2 "+3V3")
			(pintype "passive")
		)
	)
	(footprint "antmicro-footprints:R_0402_1005Metric"
		(layer "B.Cu")
		(at 216 87.185 180)
		(descr "Resistor SMD 0402")
		(tags "resistor SMD 0402")
		(property "Reference" "R139"
			(at -7.6 -2.415 0)
			(layer "B.SilkS")
			(effects
				(font
					(size 0.7 0.7)
					(thickness 0.15)
				)
				(justify left bottom mirror)
			)
		)
		(property "Value" "R_1k_0402"
			(at -1.011843 -1.772047 0)
			(layer "B.Fab")
			(effects
				(font
					(size 0.7 0.7)
					(thickness 0.15)
				)
				(justify left bottom mirror)
			)
		)
		(property "Datasheet" "https://www.bourns.com/docs/product-datasheets/cr.pdf"
			(at 0 0 0)
			(layer "B.Fab")
			(hide yes)
			(effects
				(font
					(size 1.27 1.27)
					(thickness 0.15)
				)
				(justify mirror)
			)
		)
		(property "Description" "SMD Chip Resistor, 1 kohm, ± 1%, 63 mW, 0402 [1005 Metric], Thick Film, General Purpose"
			(at 0 0 0)
			(layer "B.Fab")
			(hide yes)
			(effects
				(font
					(size 1.27 1.27)
					(thickness 0.15)
				)
				(justify mirror)
			)
		)
		(property "Manufacturer" "Bourns"
			(at 0 0 0)
			(unlocked yes)
			(layer "B.Fab")
			(hide yes)
			(effects
				(font
					(size 1 1)
					(thickness 0.15)
				)
				(justify mirror)
			)
		)
		(property "MPN" "CR0402-FX-1001GLF"
			(at 0 0 0)
			(unlocked yes)
			(layer "B.Fab")
			(hide yes)
			(effects
				(font
					(size 1 1)
					(thickness 0.15)
				)
				(justify mirror)
			)
		)
		(property "Val" "1k"
			(at 0 0 0)
			(unlocked yes)
			(layer "B.Fab")
			(hide yes)
			(effects
				(font
					(size 1 1)
					(thickness 0.15)
				)
				(justify mirror)
			)
		)
		(property "License" "Apache-2.0"
			(at 0 0 0)
			(unlocked yes)
			(layer "B.Fab")
			(hide yes)
			(effects
				(font
					(size 1 1)
					(thickness 0.15)
				)
				(justify mirror)
			)
		)
		(property "Author" "Antmicro"
			(at 0 0 0)
			(unlocked yes)
			(layer "B.Fab")
			(hide yes)
			(effects
				(font
					(size 1 1)
					(thickness 0.15)
				)
				(justify mirror)
			)
		)
		(property "Tolerance" "1%"
			(at 0 0 0)
			(unlocked yes)
			(layer "B.Fab")
			(hide yes)
			(effects
				(font
					(size 1 1)
					(thickness 0.15)
				)
				(justify mirror)
			)
		)
		(sheetname "/USB DP Alt mode/")
		(sheetfile "usb_dp.kicad_sch")
		(attr smd exclude_from_pos_files exclude_from_bom dnp)
		(fp_rect
			(start -0.925 0.47)
			(end 0.925 -0.47)
			(stroke
				(width 0.05)
				(type default)
			)
			(fill no)
			(layer "B.CrtYd")
		)
		(fp_rect
			(start -0.5 0.25)
			(end 0.5 -0.25)
			(stroke
				(width 0.15)
				(type solid)
			)
			(fill no)
			(layer "B.Fab")
		)
		(fp_text user "${REFERENCE}"
			(at -0.95 -3.168 0)
			(layer "B.Fab")
			(effects
				(font
					(size 0.7 0.7)
					(thickness 0.15)
				)
				(justify left bottom mirror)
			)
		)
		(fp_text user "License: Apache-2.0"
			(at -0.95 -5.169 0)
			(layer "B.Fab")
			(effects
				(font
					(size 0.7 0.7)
					(thickness 0.15)
				)
				(justify left bottom mirror)
			)
		)
		(fp_text user "Author: Antmicro"
			(at -0.95 -4.169 0)
			(layer "B.Fab")
			(effects
				(font
					(size 0.7 0.7)
					(thickness 0.15)
				)
				(justify left bottom mirror)
			)
		)
		(pad "1" smd roundrect
			(at -0.48 0 180)
			(size 0.59 0.64)
			(layers "B.Cu" "B.Mask" "B.Paste")
			(roundrect_rratio 0.25)
			(net 968 "/USB DP Alt mode/USBC1_EQ0")
			(pintype "passive")
		)
		(pad "2" smd roundrect
			(at 0.48 0 180)
			(size 0.59 0.64)
			(layers "B.Cu" "B.Mask" "B.Paste")
			(roundrect_rratio 0.25)
			(net 1 "GND")
			(pintype "passive")
		)
	)
	(footprint "antmicro-footprints:R_0402_1005Metric"
		(layer "B.Cu")
		(at 235.8 95.6 180)
		(descr "Resistor SMD 0402")
		(tags "resistor SMD 0402")
		(property "Reference" "R146"
			(at -3.845 -1.254999 0)
			(layer "B.SilkS")
			(effects
				(font
					(size 0.7 0.7)
					(thickness 0.15)
				)
				(justify left bottom mirror)
			)
		)
		(property "Value" "R_2k2_0402"
			(at -1.011843 -1.772046 0)
			(layer "B.Fab")
			(effects
				(font
					(size 0.7 0.7)
					(thickness 0.15)
				)
				(justify left bottom mirror)
			)
		)
		(property "Datasheet" "https://www.bourns.com/docs/product-datasheets/cr.pdf"
			(at 0 0 0)
			(layer "B.Fab")
			(hide yes)
			(effects
				(font
					(size 1.27 1.27)
					(thickness 0.15)
				)
				(justify mirror)
			)
		)
		(property "Description" "SMD Chip Resistor, 2.2 kohm, ± 1%, 62.5 mW, 0402 [1005 Metric], Thick Film, General Purpose"
			(at 0 0 0)
			(layer "B.Fab")
			(hide yes)
			(effects
				(font
					(size 1.27 1.27)
					(thickness 0.15)
				)
				(justify mirror)
			)
		)
		(property "Manufacturer" "Bourns"
			(at 0 0 0)
			(unlocked yes)
			(layer "B.Fab")
			(hide yes)
			(effects
				(font
					(size 1 1)
					(thickness 0.15)
				)
				(justify mirror)
			)
		)
		(property "MPN" "CR0402-FX-2201GLF"
			(at 0 0 0)
			(unlocked yes)
			(layer "B.Fab")
			(hide yes)
			(effects
				(font
					(size 1 1)
					(thickness 0.15)
				)
				(justify mirror)
			)
		)
		(property "Val" "2k2"
			(at 0 0 0)
			(unlocked yes)
			(layer "B.Fab")
			(hide yes)
			(effects
				(font
					(size 1 1)
					(thickness 0.15)
				)
				(justify mirror)
			)
		)
		(property "License" "Apache-2.0"
			(at 0 0 0)
			(unlocked yes)
			(layer "B.Fab")
			(hide yes)
			(effects
				(font
					(size 1 1)
					(thickness 0.15)
				)
				(justify mirror)
			)
		)
		(property "Author" "Antmicro"
			(at 0 0 0)
			(unlocked yes)
			(layer "B.Fab")
			(hide yes)
			(effects
				(font
					(size 1 1)
					(thickness 0.15)
				)
				(justify mirror)
			)
		)
		(property "Tolerance" "1%"
			(at 0 0 0)
			(unlocked yes)
			(layer "B.Fab")
			(hide yes)
			(effects
				(font
					(size 1 1)
					(thickness 0.15)
				)
				(justify mirror)
			)
		)
		(sheetname "/USB DP Alt mode/")
		(sheetfile "usb_dp.kicad_sch")
		(attr smd)
		(fp_poly
			(pts
				(xy -0.925 0.47) (xy -0.925 -0.47) (xy 0.925 -0.47) (xy 0.925 0.47)
			)
			(stroke
				(width 0.05)
				(type default)
			)
			(fill no)
			(layer "B.CrtYd")
		)
		(fp_poly
			(pts
				(xy -0.5 0.25) (xy -0.5 -0.25) (xy 0.5 -0.25) (xy 0.5 0.25)
			)
			(stroke
				(width 0.15)
				(type solid)
			)
			(fill no)
			(layer "B.Fab")
		)
		(fp_text user "${REFERENCE}"
			(at -0.95 -3.168 0)
			(layer "B.Fab")
			(effects
				(font
					(size 0.7 0.7)
					(thickness 0.15)
				)
				(justify left bottom mirror)
			)
		)
		(fp_text user "License: Apache-2.0"
			(at -0.949999 -5.169 0)
			(layer "B.Fab")
			(effects
				(font
					(size 0.7 0.7)
					(thickness 0.15)
				)
				(justify left bottom mirror)
			)
		)
		(fp_text user "Author: Antmicro"
			(at -0.95 -4.169 0)
			(layer "B.Fab")
			(effects
				(font
					(size 0.7 0.7)
					(thickness 0.15)
				)
				(justify left bottom mirror)
			)
		)
		(pad "1" smd roundrect
			(at -0.48 0 180)
			(size 0.59 0.64)
			(layers "B.Cu" "B.Mask" "B.Paste")
			(roundrect_rratio 0.25)
			(net 1 "GND")
			(pintype "passive")
		)
		(pad "2" smd roundrect
			(at 0.48 0 180)
			(size 0.59 0.64)
			(layers "B.Cu" "B.Mask" "B.Paste")
			(roundrect_rratio 0.25)
			(net 972 "Net-(U35-ISET)")
			(pintype "passive")
		)
	)
	(footprint "antmicro-footprints:TP_SMD_0.75mm"
		(layer "B.Cu")
		(at 134.8 72.6 -90)
		(property "Reference" "TP107"
			(at 0.4 -3.9 0)
			(layer "B.SilkS")
			(effects
				(font
					(size 0.7 0.7)
					(thickness 0.15)
				)
				(justify left bottom mirror)
			)
		)
		(property "Value" "TP_0.75mm_SMD"
			(at 0 -1.2 90)
			(layer "B.Fab")
			(effects
				(font
					(size 0.7 0.7)
					(thickness 0.15)
				)
				(justify left bottom mirror)
			)
		)
		(property "Description" "SMT test point"
			(at 0 0 90)
			(layer "B.Fab")
			(hide yes)
			(effects
				(font
					(size 1.27 1.27)
					(thickness 0.15)
				)
				(justify mirror)
			)
		)
		(property "MPN" ""
			(at 0 0 90)
			(unlocked yes)
			(layer "B.Fab")
			(hide yes)
			(effects
				(font
					(size 1 1)
					(thickness 0.15)
				)
				(justify mirror)
			)
		)
		(property "Manufacturer" ""
			(at 0 0 90)
			(unlocked yes)
			(layer "B.Fab")
			(hide yes)
			(effects
				(font
					(size 1 1)
					(thickness 0.15)
				)
				(justify mirror)
			)
		)
		(property "Author" "Antmicro"
			(at 0 0 90)
			(unlocked yes)
			(layer "B.Fab")
			(hide yes)
			(effects
				(font
					(size 1 1)
					(thickness 0.15)
				)
				(justify mirror)
			)
		)
		(property "License" "Apache-2.0"
			(at 0 0 90)
			(unlocked yes)
			(layer "B.Fab")
			(hide yes)
			(effects
				(font
					(size 1 1)
					(thickness 0.15)
				)
				(justify mirror)
			)
		)
		(sheetname "/SoM_IO/")
		(sheetfile "som_io.kicad_sch")
		(attr exclude_from_pos_files exclude_from_bom)
		(fp_circle
			(center 0 0)
			(end 0.475 0)
			(stroke
				(width 0.05)
				(type default)
			)
			(fill no)
			(layer "B.CrtYd")
		)
		(fp_text user "Author: Antmicro"
			(at -0.4 -3.901 90)
			(layer "B.Fab")
			(effects
				(font
					(size 0.7 0.7)
					(thickness 0.15)
				)
				(justify left bottom mirror)
			)
		)
		(fp_text user "License: Apache-2.0"
			(at -0.4 -5.101 90)
			(layer "B.Fab")
			(effects
				(font
					(size 0.7 0.7)
					(thickness 0.15)
				)
				(justify left bottom mirror)
			)
		)
		(fp_text user "${REFERENCE}"
			(at -0.4 -2.7 90)
			(layer "B.Fab")
			(effects
				(font
					(size 0.7 0.7)
					(thickness 0.15)
				)
				(justify left bottom mirror)
			)
		)
		(pad "1" smd circle
			(at 0 0 270)
			(size 0.75 0.75)
			(layers "B.Cu" "B.Mask")
			(net 138 "/SoM_IO/UART1.TX")
			(pinfunction "1")
			(pintype "passive")
		)
	)
	(footprint "antmicro-footprints:Conn_FFC_WE_68715014x22"
		(locked yes)
		(layer "B.Cu")
		(at 205.908 56.24)
		(property "Reference" "J10"
			(at -15.181 2.976 0)
			(layer "B.SilkS")
			(effects
				(font
					(size 0.7 0.7)
					(thickness 0.15)
				)
				(justify right top mirror)
			)
		)
		(property "Value" "Conn_FFC_WE_68715014522"
			(at 0 -4.5 0)
			(layer "B.Fab")
			(effects
				(font
					(size 0.7 0.7)
					(thickness 0.15)
				)
				(justify right top mirror)
			)
		)
		(property "Datasheet" "https://www.we-online.com/components/products/datasheet/68715014522.pdf"
			(at 0 0 0)
			(layer "B.Fab")
			(hide yes)
			(effects
				(font
					(size 1.27 1.27)
					(thickness 0.15)
				)
				(justify mirror)
			)
		)
		(property "Description" "FFC connector"
			(at 0 0 0)
			(layer "B.Fab")
			(hide yes)
			(effects
				(font
					(size 1.27 1.27)
					(thickness 0.15)
				)
				(justify mirror)
			)
		)
		(property "MPN" "68715014522"
			(at 0 0 180)
			(unlocked yes)
			(layer "B.Fab")
			(hide yes)
			(effects
				(font
					(size 1 1)
					(thickness 0.15)
				)
				(justify mirror)
			)
		)
		(property "Manufacturer" "Würth Elektronik"
			(at 0 0 180)
			(unlocked yes)
			(layer "B.Fab")
			(hide yes)
			(effects
				(font
					(size 1 1)
					(thickness 0.15)
				)
				(justify mirror)
			)
		)
		(property "Author" "Antmicro"
			(at 0 0 180)
			(unlocked yes)
			(layer "B.Fab")
			(hide yes)
			(effects
				(font
					(size 1 1)
					(thickness 0.15)
				)
				(justify mirror)
			)
		)
		(property "License" "Apache-2.0"
			(at 0 0 180)
			(unlocked yes)
			(layer "B.Fab")
			(hide yes)
			(effects
				(font
					(size 1 1)
					(thickness 0.15)
				)
				(justify mirror)
			)
		)
		(sheetname "/CSI/")
		(sheetfile "csi.kicad_sch")
		(attr smd)
		(fp_line
			(start -15.85 -2.7)
			(end -15.85 2.15)
			(stroke
				(width 0.15)
				(type solid)
			)
			(layer "B.SilkS")
		)
		(fp_line
			(start -15.85 2.15)
			(end -12.5 2.15)
			(stroke
				(width 0.15)
				(type solid)
			)
			(layer "B.SilkS")
		)
		(fp_line
			(start -12.5 2.15)
			(end -12.5 2.976)
			(stroke
				(width 0.15)
				(type solid)
			)
			(layer "B.SilkS")
		)
		(fp_line
			(start -12.5 2.976)
			(end 12.499 2.976)
			(stroke
				(width 0.15)
				(type solid)
			)
			(layer "B.SilkS")
		)
		(fp_line
			(start 12.499 2.15)
			(end 12.499 2.976)
			(stroke
				(width 0.15)
				(type solid)
			)
			(layer "B.SilkS")
		)
		(fp_line
			(start 15.85 -2.7)
			(end -15.85 -2.7)
			(stroke
				(width 0.15)
				(type solid)
			)
			(layer "B.SilkS")
		)
		(fp_line
			(start 15.85 -2.7)
			(end 15.85 2.15)
			(stroke
				(width 0.15)
				(type solid)
			)
			(layer "B.SilkS")
		)
		(fp_line
			(start 15.85 2.15)
			(end 12.499 2.15)
			(stroke
				(width 0.15)
				(type solid)
			)
			(layer "B.SilkS")
		)
		(fp_circle
			(center -12.9 2.9)
			(end -12.85 2.85)
			(stroke
				(width 0.15)
				(type solid)
			)
			(fill yes)
			(layer "B.SilkS")
		)
		(fp_rect
			(start -16.2 3.25)
			(end 16.2 -3.55)
			(stroke
				(width 0.05)
				(type solid)
			)
			(fill no)
			(layer "B.CrtYd")
		)
		(fp_text user "${REFERENCE}"
			(at -16.2 -5.9 0)
			(layer "B.Fab")
			(effects
				(font
					(size 0.7 0.7)
					(thickness 0.15)
				)
				(justify right top mirror)
			)
		)
		(fp_text user "License: Apache-2.0"
			(at -16.2 -7.9 0)
			(layer "B.Fab")
			(effects
				(font
					(size 0.7 0.7)
					(thickness 0.15)
				)
				(justify right top mirror)
			)
		)
		(fp_text user "Author: Antmicro"
			(at -16.2 -6.9 0)
			(layer "B.Fab")
			(effects
				(font
					(size 0.7 0.7)
					(thickness 0.15)
				)
				(justify right top mirror)
			)
		)
		(pad "1" smd roundrect
			(at -12.25 2.15)
			(size 0.3 1.2)
			(layers "B.Cu" "B.Mask" "B.Paste")
			(roundrect_rratio 0.25)
			(net 79 "/CSI/CAM2.CSI5_D1-")
			(pintype "passive")
		)
		(pad "2" smd roundrect
			(at -11.75 2.15)
			(size 0.3 1.2)
			(layers "B.Cu" "B.Mask" "B.Paste")
			(roundrect_rratio 0.25)
			(net 163 "/CSI/CAM2.CSI5_D1+")
			(pintype "passive")
		)
		(pad "3" smd roundrect
			(at -11.25 2.15)
			(size 0.3 1.2)
			(layers "B.Cu" "B.Mask" "B.Paste")
			(roundrect_rratio 0.25)
			(net 128 "/CSI/CAM2.CSI5_D0-")
			(pintype "passive")
		)
		(pad "4" smd roundrect
			(at -10.75 2.15)
			(size 0.3 1.2)
			(layers "B.Cu" "B.Mask" "B.Paste")
			(roundrect_rratio 0.25)
			(net 125 "/CSI/CAM2.CSI5_D0+")
			(pintype "passive")
		)
		(pad "5" smd roundrect
			(at -10.25 2.15)
			(size 0.3 1.2)
			(layers "B.Cu" "B.Mask" "B.Paste")
			(roundrect_rratio 0.25)
			(net 162 "/CSI/CAM2.CSI4_D1-")
			(pintype "passive")
		)
		(pad "6" smd roundrect
			(at -9.75 2.15)
			(size 0.3 1.2)
			(layers "B.Cu" "B.Mask" "B.Paste")
			(roundrect_rratio 0.25)
			(net 87 "/CSI/CAM2.CSI4_D1+")
			(pintype "passive")
		)
		(pad "7" smd roundrect
			(at -9.25 2.15)
			(size 0.3 1.2)
			(layers "B.Cu" "B.Mask" "B.Paste")
			(roundrect_rratio 0.25)
			(net 122 "/CSI/CAM2.CSI4_D0-")
			(pintype "passive")
		)
		(pad "8" smd roundrect
			(at -8.75 2.15)
			(size 0.3 1.2)
			(layers "B.Cu" "B.Mask" "B.Paste")
			(roundrect_rratio 0.25)
			(net 144 "/CSI/CAM2.CSI4_D0+")
			(pintype "passive")
		)
		(pad "9" smd roundrect
			(at -8.25 2.15)
			(size 0.3 1.2)
			(layers "B.Cu" "B.Mask" "B.Paste")
			(roundrect_rratio 0.25)
			(net 1 "GND")
			(pintype "passive")
		)
		(pad "10" smd roundrect
			(at -7.75 2.15)
			(size 0.3 1.2)
			(layers "B.Cu" "B.Mask" "B.Paste")
			(roundrect_rratio 0.25)
			(net 84 "/CSI/CAM2.CSI4_CLK-")
			(pintype "passive")
		)
		(pad "11" smd roundrect
			(at -7.25 2.15)
			(size 0.3 1.2)
			(layers "B.Cu" "B.Mask" "B.Paste")
			(roundrect_rratio 0.25)
			(net 160 "/CSI/CAM2.CSI4_CLK+")
			(pintype "passive")
		)
		(pad "12" smd roundrect
			(at -6.75 2.15)
			(size 0.3 1.2)
			(layers "B.Cu" "B.Mask" "B.Paste")
			(roundrect_rratio 0.25)
			(net 1 "GND")
			(pintype "passive")
		)
		(pad "13" smd roundrect
			(at -6.25 2.15)
			(size 0.3 1.2)
			(layers "B.Cu" "B.Mask" "B.Paste")
			(roundrect_rratio 0.25)
			(net 181 "unconnected-(J10-Pad13)")
			(pintype "passive+no_connect")
		)
		(pad "14" smd roundrect
			(at -5.75 2.15)
			(size 0.3 1.2)
			(layers "B.Cu" "B.Mask" "B.Paste")
			(roundrect_rratio 0.25)
			(net 183 "unconnected-(J10-Pad14)")
			(pintype "passive+no_connect")
		)
		(pad "15" smd roundrect
			(at -5.25 2.15)
			(size 0.3 1.2)
			(layers "B.Cu" "B.Mask" "B.Paste")
			(roundrect_rratio 0.25)
			(net 1 "GND")
			(pintype "passive")
		)
		(pad "16" smd roundrect
			(at -4.75 2.15)
			(size 0.3 1.2)
			(layers "B.Cu" "B.Mask" "B.Paste")
			(roundrect_rratio 0.25)
			(net 180 "unconnected-(J10-Pad16)")
			(pintype "passive+no_connect")
		)
		(pad "17" smd roundrect
			(at -4.25 2.15)
			(size 0.3 1.2)
			(layers "B.Cu" "B.Mask" "B.Paste")
			(roundrect_rratio 0.25)
			(net 184 "unconnected-(J10-Pad17)")
			(pintype "passive+no_connect")
		)
		(pad "18" smd roundrect
			(at -3.75 2.15)
			(size 0.3 1.2)
			(layers "B.Cu" "B.Mask" "B.Paste")
			(roundrect_rratio 0.25)
			(net 1 "GND")
			(pintype "passive")
		)
		(pad "19" smd roundrect
			(at -3.25 2.15)
			(size 0.3 1.2)
			(layers "B.Cu" "B.Mask" "B.Paste")
			(roundrect_rratio 0.25)
			(net 86 "/CSI/CAM3.CSI7_D1-")
			(pintype "passive")
		)
		(pad "20" smd roundrect
			(at -2.75 2.15)
			(size 0.3 1.2)
			(layers "B.Cu" "B.Mask" "B.Paste")
			(roundrect_rratio 0.25)
			(net 102 "/CSI/CAM3.CSI7_D1+")
			(pintype "passive")
		)
		(pad "21" smd roundrect
			(at -2.25 2.15)
			(size 0.3 1.2)
			(layers "B.Cu" "B.Mask" "B.Paste")
			(roundrect_rratio 0.25)
			(net 59 "/CSI/CAM3.CSI7_D0-")
			(pintype "passive")
		)
		(pad "22" smd roundrect
			(at -1.75 2.15)
			(size 0.3 1.2)
			(layers "B.Cu" "B.Mask" "B.Paste")
			(roundrect_rratio 0.25)
			(net 124 "/CSI/CAM3.CSI7_D0+")
			(pintype "passive")
		)
		(pad "23" smd roundrect
			(at -1.25 2.15)
			(size 0.3 1.2)
			(layers "B.Cu" "B.Mask" "B.Paste")
			(roundrect_rratio 0.25)
			(net 62 "/CSI/CAM3.CSI6_D1-")
			(pintype "passive")
		)
		(pad "24" smd roundrect
			(at -0.75 2.15)
			(size 0.3 1.2)
			(layers "B.Cu" "B.Mask" "B.Paste")
			(roundrect_rratio 0.25)
			(net 70 "/CSI/CAM3.CSI6_D1+")
			(pintype "passive")
		)
		(pad "25" smd roundrect
			(at -0.25 2.15)
			(size 0.3 1.2)
			(layers "B.Cu" "B.Mask" "B.Paste")
			(roundrect_rratio 0.25)
			(net 135 "/CSI/CAM3.CSI6_D0-")
			(pintype "passive")
		)
		(pad "26" smd roundrect
			(at 0.248 2.15)
			(size 0.3 1.2)
			(layers "B.Cu" "B.Mask" "B.Paste")
			(roundrect_rratio 0.25)
			(net 152 "/CSI/CAM3.CSI6_D0+")
			(pintype "passive")
		)
		(pad "27" smd roundrect
			(at 0.748 2.15)
			(size 0.3 1.2)
			(layers "B.Cu" "B.Mask" "B.Paste")
			(roundrect_rratio 0.25)
			(net 1 "GND")
			(pintype "passive")
		)
		(pad "28" smd roundrect
			(at 1.249 2.15)
			(size 0.3 1.2)
			(layers "B.Cu" "B.Mask" "B.Paste")
			(roundrect_rratio 0.25)
			(net 116 "/CSI/CAM3.CSI6_CLK-")
			(pintype "passive")
		)
		(pad "29" smd roundrect
			(at 1.749 2.15)
			(size 0.3 1.2)
			(layers "B.Cu" "B.Mask" "B.Paste")
			(roundrect_rratio 0.25)
			(net 53 "/CSI/CAM3.CSI6_CLK+")
			(pintype "passive")
		)
		(pad "30" smd roundrect
			(at 2.249 2.15)
			(size 0.3 1.2)
			(layers "B.Cu" "B.Mask" "B.Paste")
			(roundrect_rratio 0.25)
			(net 1 "GND")
			(pintype "passive")
		)
		(pad "31" smd roundrect
			(at 2.749 2.15)
			(size 0.3 1.2)
			(layers "B.Cu" "B.Mask" "B.Paste")
			(roundrect_rratio 0.25)
			(net 185 "unconnected-(J10-Pad31)")
			(pintype "passive+no_connect")
		)
		(pad "32" smd roundrect
			(at 3.249 2.15)
			(size 0.3 1.2)
			(layers "B.Cu" "B.Mask" "B.Paste")
			(roundrect_rratio 0.25)
			(net 201 "/CSI/VSYNC_CAM2_3V3")
			(pintype "passive")
		)
		(pad "33" smd roundrect
			(at 3.749 2.15)
			(size 0.3 1.2)
			(layers "B.Cu" "B.Mask" "B.Paste")
			(roundrect_rratio 0.25)
			(net 191 "unconnected-(J10-Pad33)")
			(pintype "passive+no_connect")
		)
		(pad "34" smd roundrect
			(at 4.248 2.15)
			(size 0.3 1.2)
			(layers "B.Cu" "B.Mask" "B.Paste")
			(roundrect_rratio 0.25)
			(net 210 "/CSI/VSYNC_CAM3_3V3")
			(pintype "passive")
		)
		(pad "35" smd roundrect
			(at 4.748 2.15)
			(size 0.3 1.2)
			(layers "B.Cu" "B.Mask" "B.Paste")
			(roundrect_rratio 0.25)
			(net 190 "unconnected-(J10-Pad35)")
			(pintype "passive+no_connect")
		)
		(pad "36" smd roundrect
			(at 5.248 2.15)
			(size 0.3 1.2)
			(layers "B.Cu" "B.Mask" "B.Paste")
			(roundrect_rratio 0.25)
			(net 188 "unconnected-(J10-Pad36)")
			(pintype "passive+no_connect")
		)
		(pad "37" smd roundrect
			(at 5.749 2.15)
			(size 0.3 1.2)
			(layers "B.Cu" "B.Mask" "B.Paste")
			(roundrect_rratio 0.25)
			(net 187 "unconnected-(J10-Pad37)")
			(pintype "passive+no_connect")
		)
		(pad "38" smd roundrect
			(at 6.249 2.15)
			(size 0.3 1.2)
			(layers "B.Cu" "B.Mask" "B.Paste")
			(roundrect_rratio 0.25)
			(net 189 "unconnected-(J10-Pad38)")
			(pintype "passive+no_connect")
		)
		(pad "39" smd roundrect
			(at 6.749 2.15)
			(size 0.3 1.2)
			(layers "B.Cu" "B.Mask" "B.Paste")
			(roundrect_rratio 0.25)
			(net 1373 "Net-(J10-Pad39)")
			(pintype "passive")
		)
		(pad "40" smd roundrect
			(at 7.249 2.15)
			(size 0.3 1.2)
			(layers "B.Cu" "B.Mask" "B.Paste")
			(roundrect_rratio 0.25)
			(net 1372 "Net-(J10-Pad40)")
			(pintype "passive")
		)
		(pad "41" smd roundrect
			(at 7.749 2.15)
			(size 0.3 1.2)
			(layers "B.Cu" "B.Mask" "B.Paste")
			(roundrect_rratio 0.25)
			(net 937 "Net-(J10-Pad41)")
			(pintype "passive")
		)
		(pad "42" smd roundrect
			(at 8.249 2.15)
			(size 0.3 1.2)
			(layers "B.Cu" "B.Mask" "B.Paste")
			(roundrect_rratio 0.25)
			(net 938 "Net-(J10-Pad42)")
			(pintype "passive")
		)
		(pad "43" smd roundrect
			(at 8.749 2.15)
			(size 0.3 1.2)
			(layers "B.Cu" "B.Mask" "B.Paste")
			(roundrect_rratio 0.25)
			(net 193 "unconnected-(J10-Pad43)")
			(pintype "passive+no_connect")
		)
		(pad "44" smd roundrect
			(at 9.249 2.15)
			(size 0.3 1.2)
			(layers "B.Cu" "B.Mask" "B.Paste")
			(roundrect_rratio 0.25)
			(net 195 "unconnected-(J10-Pad44)")
			(pintype "passive+no_connect")
		)
		(pad "45" smd roundrect
			(at 9.749 2.15)
			(size 0.3 1.2)
			(layers "B.Cu" "B.Mask" "B.Paste")
			(roundrect_rratio 0.25)
			(net 192 "unconnected-(J10-Pad45)")
			(pintype "passive+no_connect")
		)
		(pad "46" smd roundrect
			(at 10.249 2.15)
			(size 0.3 1.2)
			(layers "B.Cu" "B.Mask" "B.Paste")
			(roundrect_rratio 0.25)
			(net 182 "unconnected-(J10-Pad46)")
			(pintype "passive+no_connect")
		)
		(pad "47" smd roundrect
			(at 10.749 2.15)
			(size 0.3 1.2)
			(layers "B.Cu" "B.Mask" "B.Paste")
			(roundrect_rratio 0.25)
			(net 8 "/CSI/CSIB_3V3")
			(pintype "passive")
		)
		(pad "48" smd roundrect
			(at 11.249 2.15)
			(size 0.3 1.2)
			(layers "B.Cu" "B.Mask" "B.Paste")
			(roundrect_rratio 0.25)
			(net 8 "/CSI/CSIB_3V3")
			(pintype "passive")
		)
		(pad "49" smd roundrect
			(at 11.749 2.15)
			(size 0.3 1.2)
			(layers "B.Cu" "B.Mask" "B.Paste")
			(roundrect_rratio 0.25)
			(net 9 "/CSI/CSIB_5V")
			(pintype "passive")
		)
		(pad "50" smd roundrect
			(at 12.249 2.15)
			(size 0.3 1.2)
			(layers "B.Cu" "B.Mask" "B.Paste")
			(roundrect_rratio 0.25)
			(net 9 "/CSI/CSIB_5V")
			(pintype "passive")
		)
		(pad "MP1" smd roundrect
			(at -14.198 0.3)
			(size 2.7 3)
			(layers "B.Cu" "B.Mask" "B.Paste")
			(roundrect_rratio 0.05)
			(net 1 "GND")
			(pinfunction "MP")
			(pintype "passive")
		)
		(pad "MP2" smd roundrect
			(at 14.198 0.3)
			(size 2.7 3)
			(layers "B.Cu" "B.Mask" "B.Paste")
			(roundrect_rratio 0.05)
			(net 1 "GND")
			(pinfunction "MP")
			(pintype "passive")
		)
	)
	(footprint "antmicro-footprints:C_0402_1005Metric"
		(layer "B.Cu")
		(at 90.780001 105.5 -90)
		(descr "Capacitor SMD 0402")
		(tags "capacitor SMD 0402")
		(property "Reference" "C325"
			(at 1 -0.5 90)
			(layer "B.SilkS")
			(effects
				(font
					(size 0.7 0.7)
					(thickness 0.15)
				)
				(justify left bottom mirror)
			)
		)
		(property "Value" "C_100n_0402"
			(at -1.022927 -2.155213 90)
			(layer "B.Fab")
			(effects
				(font
					(size 0.7 0.7)
					(thickness 0.15)
				)
				(justify left bottom mirror)
			)
		)
		(property "Datasheet" "https://www.murata.com/products/productdetail?partno=GRM155R61H104KE14%23"
			(at 0 0 90)
			(layer "B.Fab")
			(hide yes)
			(effects
				(font
					(size 1.27 1.27)
					(thickness 0.15)
				)
				(justify mirror)
			)
		)
		(property "Description" "SMD Multilayer Ceramic Capacitor, 0.1 µF, 50 V, 0402 [1005 Metric], ± 10%, X5R, GRM Series"
			(at 0 0 90)
			(layer "B.Fab")
			(hide yes)
			(effects
				(font
					(size 1.27 1.27)
					(thickness 0.15)
				)
				(justify mirror)
			)
		)
		(property "Manufacturer" "Murata"
			(at 0 0 90)
			(unlocked yes)
			(layer "B.Fab")
			(hide yes)
			(effects
				(font
					(size 1 1)
					(thickness 0.15)
				)
				(justify mirror)
			)
		)
		(property "MPN" "GRM155R61H104KE14D"
			(at 0 0 90)
			(unlocked yes)
			(layer "B.Fab")
			(hide yes)
			(effects
				(font
					(size 1 1)
					(thickness 0.15)
				)
				(justify mirror)
			)
		)
		(property "Val" "100n"
			(at 0 0 90)
			(unlocked yes)
			(layer "B.Fab")
			(hide yes)
			(effects
				(font
					(size 1 1)
					(thickness 0.15)
				)
				(justify mirror)
			)
		)
		(property "License" "Apache-2.0"
			(at 0 0 90)
			(unlocked yes)
			(layer "B.Fab")
			(hide yes)
			(effects
				(font
					(size 1 1)
					(thickness 0.15)
				)
				(justify mirror)
			)
		)
		(property "Author" "Antmicro"
			(at 0 0 90)
			(unlocked yes)
			(layer "B.Fab")
			(hide yes)
			(effects
				(font
					(size 1 1)
					(thickness 0.15)
				)
				(justify mirror)
			)
		)
		(property "Voltage" "50V"
			(at 0 0 90)
			(unlocked yes)
			(layer "B.Fab")
			(hide yes)
			(effects
				(font
					(size 1 1)
					(thickness 0.15)
				)
				(justify mirror)
			)
		)
		(property "Dielectric" "X5R"
			(at 0 0 90)
			(unlocked yes)
			(layer "B.Fab")
			(hide yes)
			(effects
				(font
					(size 1 1)
					(thickness 0.15)
				)
				(justify mirror)
			)
		)
		(sheetname "/SoM_IO2/")
		(sheetfile "som_io2.kicad_sch")
		(attr smd)
		(fp_poly
			(pts
				(xy -0.925 0.47) (xy 0.925 0.47) (xy 0.925 -0.47) (xy -0.925 -0.47)
			)
			(stroke
				(width 0.05)
				(type default)
			)
			(fill no)
			(layer "B.CrtYd")
		)
		(fp_line
			(start -0.494 0.25)
			(end 0.504 0.25)
			(stroke
				(width 0.15)
				(type solid)
			)
			(layer "B.Fab")
		)
		(fp_line
			(start 0.504 0.25)
			(end 0.504 -0.248)
			(stroke
				(width 0.15)
				(type solid)
			)
			(layer "B.Fab")
		)
		(fp_line
			(start -0.494 -0.248)
			(end -0.494 0.25)
			(stroke
				(width 0.15)
				(type solid)
			)
			(layer "B.Fab")
		)
		(fp_line
			(start 0.504 -0.248)
			(end -0.494 -0.248)
			(stroke
				(width 0.15)
				(type solid)
			)
			(layer "B.Fab")
		)
		(fp_text user "${REFERENCE}"
			(at -0.939 -4.599 90)
			(layer "B.Fab")
			(effects
				(font
					(size 0.7 0.7)
					(thickness 0.15)
				)
				(justify left bottom mirror)
			)
		)
		(fp_text user "License: Apache-2.0"
			(at -0.939 -5.799 90)
			(layer "B.Fab")
			(effects
				(font
					(size 0.7 0.7)
					(thickness 0.15)
				)
				(justify left bottom mirror)
			)
		)
		(fp_text user "Author: Antmicro"
			(at -0.939 -3.399 90)
			(layer "B.Fab")
			(effects
				(font
					(size 0.7 0.7)
					(thickness 0.15)
				)
				(justify left bottom mirror)
			)
		)
		(pad "1" smd roundrect
			(at -0.48 0 270)
			(size 0.59 0.64)
			(layers "B.Cu" "B.Mask" "B.Paste")
			(roundrect_rratio 0.25)
			(net 771 "/Expansion connector/DP1.TX1+")
			(pintype "passive")
		)
		(pad "2" smd roundrect
			(at 0.48 0 270)
			(size 0.59 0.64)
			(layers "B.Cu" "B.Mask" "B.Paste")
			(roundrect_rratio 0.25)
			(net 1209 "/SoM_IO2/DP1.TX1_C+")
			(pintype "passive")
		)
	)
	(footprint "antmicro-footprints:SOT-23-6"
		(layer "B.Cu")
		(at 179.25 91 90)
		(property "Reference" "U61"
			(at -1.75 2 90)
			(layer "B.SilkS")
			(effects
				(font
					(size 0.7 0.7)
					(thickness 0.15)
				)
				(justify right top mirror)
			)
		)
		(property "Value" "LTC4412IS6"
			(at -1.75 -2.693 90)
			(layer "B.Fab")
			(effects
				(font
					(size 0.7 0.7)
					(thickness 0.15)
				)
				(justify right top mirror)
			)
		)
		(property "Datasheet" "https://www.analog.com/media/en/technical-documentation/data-sheets/4412fb.pdf"
			(at 0 0.057 90)
			(layer "B.Fab")
			(hide yes)
			(effects
				(font
					(size 1.27 1.27)
					(thickness 0.15)
				)
				(justify mirror)
			)
		)
		(property "Description" "Ideal diode controller"
			(at 0 0.057 90)
			(layer "B.Fab")
			(hide yes)
			(effects
				(font
					(size 1.27 1.27)
					(thickness 0.15)
				)
				(justify mirror)
			)
		)
		(property "MPN" "LTC4412IS6#TRMPBF"
			(at 0 0 270)
			(unlocked yes)
			(layer "B.Fab")
			(hide yes)
			(effects
				(font
					(size 1 1)
					(thickness 0.15)
				)
				(justify mirror)
			)
		)
		(property "Manufacturer" "Analog Devices"
			(at 0 0 270)
			(unlocked yes)
			(layer "B.Fab")
			(hide yes)
			(effects
				(font
					(size 1 1)
					(thickness 0.15)
				)
				(justify mirror)
			)
		)
		(property "Author" "Antmicro"
			(at 0 0 270)
			(unlocked yes)
			(layer "B.Fab")
			(hide yes)
			(effects
				(font
					(size 1 1)
					(thickness 0.15)
				)
				(justify mirror)
			)
		)
		(property "License" "Apache-2.0"
			(at 0 0 270)
			(unlocked yes)
			(layer "B.Fab")
			(hide yes)
			(effects
				(font
					(size 1 1)
					(thickness 0.15)
				)
				(justify mirror)
			)
		)
		(sheetname "/Power/")
		(sheetfile "power.kicad_sch")
		(attr smd exclude_from_pos_files exclude_from_bom dnp)
		(fp_line
			(start 1.45 -0.643)
			(end 1.45 -0.343)
			(stroke
				(width 0.12)
				(type solid)
			)
			(layer "B.SilkS")
		)
		(fp_line
			(start 1.3 -0.643)
			(end 1.45 -0.643)
			(stroke
				(width 0.12)
				(type solid)
			)
			(layer "B.SilkS")
		)
		(fp_line
			(start -1.45 -0.643)
			(end -1.45 -0.343)
			(stroke
				(width 0.12)
				(type solid)
			)
			(layer "B.SilkS")
		)
		(fp_line
			(start 1.45 0.757)
			(end 1.45 0.457)
			(stroke
				(width 0.12)
				(type solid)
			)
			(layer "B.SilkS")
		)
		(fp_line
			(start 1.3 0.757)
			(end 1.45 0.757)
			(stroke
				(width 0.12)
				(type solid)
			)
			(layer "B.SilkS")
		)
		(fp_line
			(start -1.3 0.757)
			(end -1.45 0.757)
			(stroke
				(width 0.12)
				(type solid)
			)
			(layer "B.SilkS")
		)
		(fp_line
			(start -1.45 0.757)
			(end -1.45 0.457)
			(stroke
				(width 0.12)
				(type solid)
			)
			(layer "B.SilkS")
		)
		(fp_rect
			(start -1.55 1.85)
			(end 1.55 -1.75)
			(stroke
				(width 0.05)
				(type solid)
			)
			(fill no)
			(layer "B.CrtYd")
		)
		(fp_line
			(start 1.5 -0.643)
			(end -1.5 -0.643)
			(stroke
				(width 0.1)
				(type solid)
			)
			(layer "B.Fab")
		)
		(fp_line
			(start -1.5 -0.643)
			(end -1.5 0.757)
			(stroke
				(width 0.1)
				(type solid)
			)
			(layer "B.Fab")
		)
		(fp_line
			(start 1.5 0.757)
			(end 1.5 -0.643)
			(stroke
				(width 0.1)
				(type solid)
			)
			(layer "B.Fab")
		)
		(fp_line
			(start -1.5 0.757)
			(end 1.5 0.757)
			(stroke
				(width 0.1)
				(type solid)
			)
			(layer "B.Fab")
		)
		(fp_text user "."
			(at -1.2 -2.45 90)
			(layer "B.SilkS")
			(effects
				(font
					(size 1 1)
					(thickness 0.15)
				)
				(justify mirror)
			)
		)
		(fp_text user "${REFERENCE}"
			(at -1.75 -4 90)
			(layer "B.Fab")
			(effects
				(font
					(size 0.7 0.7)
					(thickness 0.15)
				)
				(justify right top mirror)
			)
		)
		(fp_text user "License: Apache-2.0"
			(at -1.75 -6.5 90)
			(layer "B.Fab")
			(effects
				(font
					(size 0.7 0.7)
					(thickness 0.15)
				)
				(justify right top mirror)
			)
		)
		(fp_text user "Author: Antmicro"
			(at -1.829 -5.25 90)
			(layer "B.Fab")
			(effects
				(font
					(size 0.7 0.7)
					(thickness 0.15)
				)
				(justify right top mirror)
			)
		)
		(pad "1" smd roundrect
			(at -0.954 -1.1 90)
			(size 0.55 1)
			(layers "B.Cu" "B.Mask" "B.Paste")
			(roundrect_rratio 0.15)
			(net 522 "/Power/USBPD1_HV")
			(pinfunction "IN")
			(pintype "power_in")
		)
		(pad "2" smd roundrect
			(at -0.003 -1.1 90)
			(size 0.55 1)
			(layers "B.Cu" "B.Mask" "B.Paste")
			(roundrect_rratio 0.15)
			(net 1 "GND")
			(pinfunction "GND")
			(pintype "power_in")
		)
		(pad "3" smd roundrect
			(at 0.947 -1.1 90)
			(size 0.55 1)
			(layers "B.Cu" "B.Mask" "B.Paste")
			(roundrect_rratio 0.15)
			(net 1 "GND")
			(pinfunction "CTL")
			(pintype "input")
		)
		(pad "4" smd roundrect
			(at 0.947 1.214 90)
			(size 0.55 1)
			(layers "B.Cu" "B.Mask" "B.Paste")
			(roundrect_rratio 0.15)
			(net 1224 "unconnected-(U61-STAT-Pad4)")
			(pinfunction "STAT")
			(pintype "output+no_connect")
		)
		(pad "5" smd roundrect
			(at -0.003 1.214 90)
			(size 0.55 1)
			(layers "B.Cu" "B.Mask" "B.Paste")
			(roundrect_rratio 0.15)
			(net 1200 "Net-(Q5-G)")
			(pinfunction "GATE")
			(pintype "output")
		)
		(pad "6" smd roundrect
			(at -0.954 1.214 90)
			(size 0.55 1)
			(layers "B.Cu" "B.Mask" "B.Paste")
			(roundrect_rratio 0.15)
			(net 13 "VCC")
			(pinfunction "SENSE")
			(pintype "input")
		)
	)
	(footprint "antmicro-footprints:C_0402_1005Metric"
		(layer "B.Cu")
		(at 230.17 88 180)
		(descr "Capacitor SMD 0402")
		(tags "capacitor SMD 0402")
		(property "Reference" "C153"
			(at 0.87 -0.4 0)
			(layer "B.SilkS")
			(effects
				(font
					(size 0.7 0.7)
					(thickness 0.15)
				)
				(justify left bottom mirror)
			)
		)
		(property "Value" "C_100n_0402"
			(at -1.022927 -2.155213 0)
			(layer "B.Fab")
			(effects
				(font
					(size 0.7 0.7)
					(thickness 0.15)
				)
				(justify left bottom mirror)
			)
		)
		(property "Datasheet" "https://www.murata.com/products/productdetail?partno=GRM155R61H104KE14%23"
			(at 0 0 0)
			(layer "B.Fab")
			(hide yes)
			(effects
				(font
					(size 1.27 1.27)
					(thickness 0.15)
				)
				(justify mirror)
			)
		)
		(property "Description" "SMD Multilayer Ceramic Capacitor, 0.1 µF, 50 V, 0402 [1005 Metric], ± 10%, X5R, GRM Series"
			(at 0 0 0)
			(layer "B.Fab")
			(hide yes)
			(effects
				(font
					(size 1.27 1.27)
					(thickness 0.15)
				)
				(justify mirror)
			)
		)
		(property "MPN" "GRM155R61H104KE14D"
			(at 0 0 0)
			(unlocked yes)
			(layer "B.Fab")
			(hide yes)
			(effects
				(font
					(size 1 1)
					(thickness 0.15)
				)
				(justify mirror)
			)
		)
		(property "Manufacturer" "Murata"
			(at 0 0 0)
			(unlocked yes)
			(layer "B.Fab")
			(hide yes)
			(effects
				(font
					(size 1 1)
					(thickness 0.15)
				)
				(justify mirror)
			)
		)
		(property "Val" "100n"
			(at 0 0 0)
			(unlocked yes)
			(layer "B.Fab")
			(hide yes)
			(effects
				(font
					(size 1 1)
					(thickness 0.15)
				)
				(justify mirror)
			)
		)
		(property "License" "Apache-2.0"
			(at 0 0 0)
			(unlocked yes)
			(layer "B.Fab")
			(hide yes)
			(effects
				(font
					(size 1 1)
					(thickness 0.15)
				)
				(justify mirror)
			)
		)
		(property "Author" "Antmicro"
			(at 0 0 0)
			(unlocked yes)
			(layer "B.Fab")
			(hide yes)
			(effects
				(font
					(size 1 1)
					(thickness 0.15)
				)
				(justify mirror)
			)
		)
		(property "Voltage" "50V"
			(at 0 0 0)
			(unlocked yes)
			(layer "B.Fab")
			(hide yes)
			(effects
				(font
					(size 1 1)
					(thickness 0.15)
				)
				(justify mirror)
			)
		)
		(property "Dielectric" "X5R"
			(at 0 0 0)
			(unlocked yes)
			(layer "B.Fab")
			(hide yes)
			(effects
				(font
					(size 1 1)
					(thickness 0.15)
				)
				(justify mirror)
			)
		)
		(sheetname "/USB DP Alt mode/")
		(sheetfile "usb_dp.kicad_sch")
		(attr smd)
		(fp_poly
			(pts
				(xy -0.925 0.47) (xy 0.925 0.47) (xy 0.925 -0.47) (xy -0.925 -0.47)
			)
			(stroke
				(width 0.05)
				(type default)
			)
			(fill no)
			(layer "B.CrtYd")
		)
		(fp_line
			(start 0.504 0.25)
			(end 0.504 -0.248)
			(stroke
				(width 0.15)
				(type solid)
			)
			(layer "B.Fab")
		)
		(fp_line
			(start 0.504 -0.248)
			(end -0.494 -0.248)
			(stroke
				(width 0.15)
				(type solid)
			)
			(layer "B.Fab")
		)
		(fp_line
			(start -0.494 0.25)
			(end 0.504 0.25)
			(stroke
				(width 0.15)
				(type solid)
			)
			(layer "B.Fab")
		)
		(fp_line
			(start -0.494 -0.248)
			(end -0.494 0.25)
			(stroke
				(width 0.15)
				(type solid)
			)
			(layer "B.Fab")
		)
		(fp_text user "${REFERENCE}"
			(at -0.939 -4.599 0)
			(layer "B.Fab")
			(effects
				(font
					(size 0.7 0.7)
					(thickness 0.15)
				)
				(justify left bottom mirror)
			)
		)
		(fp_text user "Author: Antmicro"
			(at -0.939 -3.399 0)
			(layer "B.Fab")
			(effects
				(font
					(size 0.7 0.7)
					(thickness 0.15)
				)
				(justify left bottom mirror)
			)
		)
		(fp_text user "License: Apache-2.0"
			(at -0.939 -5.799 0)
			(layer "B.Fab")
			(effects
				(font
					(size 0.7 0.7)
					(thickness 0.15)
				)
				(justify left bottom mirror)
			)
		)
		(pad "1" smd roundrect
			(at -0.48 0 180)
			(size 0.59 0.64)
			(layers "B.Cu" "B.Mask" "B.Paste")
			(roundrect_rratio 0.25)
			(net 376 "/USB DP Alt mode/USBC1_VBUS")
			(pintype "passive")
		)
		(pad "2" smd roundrect
			(at 0.48 0 180)
			(size 0.59 0.64)
			(layers "B.Cu" "B.Mask" "B.Paste")
			(roundrect_rratio 0.25)
			(net 1 "GND")
			(pintype "passive")
		)
	)
	(footprint "antmicro-footprints:TP_SMD_0.75mm"
		(layer "B.Cu")
		(at 124.6 136.1 180)
		(property "Reference" "TP39"
			(at -3.23 -0.395 0)
			(layer "B.SilkS")
			(effects
				(font
					(size 0.7 0.7)
					(thickness 0.15)
				)
				(justify left bottom mirror)
			)
		)
		(property "Value" "TP_0.75mm_SMD"
			(at 0 -1.2 0)
			(layer "B.Fab")
			(effects
				(font
					(size 0.7 0.7)
					(thickness 0.15)
				)
				(justify left bottom mirror)
			)
		)
		(property "Description" "SMT test point"
			(at 0 0 0)
			(layer "B.Fab")
			(hide yes)
			(effects
				(font
					(size 1.27 1.27)
					(thickness 0.15)
				)
				(justify mirror)
			)
		)
		(property "MPN" ""
			(at 0 0 0)
			(unlocked yes)
			(layer "B.Fab")
			(hide yes)
			(effects
				(font
					(size 1 1)
					(thickness 0.15)
				)
				(justify mirror)
			)
		)
		(property "Manufacturer" ""
			(at 0 0 0)
			(unlocked yes)
			(layer "B.Fab")
			(hide yes)
			(effects
				(font
					(size 1 1)
					(thickness 0.15)
				)
				(justify mirror)
			)
		)
		(property "Author" "Antmicro"
			(at 0 0 0)
			(unlocked yes)
			(layer "B.Fab")
			(hide yes)
			(effects
				(font
					(size 1 1)
					(thickness 0.15)
				)
				(justify mirror)
			)
		)
		(property "License" "Apache-2.0"
			(at 0 0 0)
			(unlocked yes)
			(layer "B.Fab")
			(hide yes)
			(effects
				(font
					(size 1 1)
					(thickness 0.15)
				)
				(justify mirror)
			)
		)
		(sheetname "/M.2/")
		(sheetfile "m2.kicad_sch")
		(attr exclude_from_pos_files exclude_from_bom)
		(fp_circle
			(center 0 0)
			(end 0.475 0)
			(stroke
				(width 0.05)
				(type default)
			)
			(fill no)
			(layer "B.CrtYd")
		)
		(fp_text user "Author: Antmicro"
			(at -0.4 -3.901 0)
			(layer "B.Fab")
			(effects
				(font
					(size 0.7 0.7)
					(thickness 0.15)
				)
				(justify left bottom mirror)
			)
		)
		(fp_text user "${REFERENCE}"
			(at -0.4 -2.7 0)
			(layer "B.Fab")
			(effects
				(font
					(size 0.7 0.7)
					(thickness 0.15)
				)
				(justify left bottom mirror)
			)
		)
		(fp_text user "License: Apache-2.0"
			(at -0.4 -5.101 0)
			(layer "B.Fab")
			(effects
				(font
					(size 0.7 0.7)
					(thickness 0.15)
				)
				(justify left bottom mirror)
			)
		)
		(pad "1" smd circle
			(at 0 0 180)
			(size 0.75 0.75)
			(layers "B.Cu" "B.Mask")
			(net 257 "/M.2/~{M2_E_ALERT}")
			(pinfunction "1")
			(pintype "passive")
		)
	)
	(footprint "antmicro-footprints:R_0402_1005Metric"
		(layer "B.Cu")
		(at 66.15 63.58 90)
		(descr "Resistor SMD 0402")
		(tags "resistor SMD 0402")
		(property "Reference" "R170"
			(at 0.78 -0.31 90)
			(layer "B.SilkS")
			(effects
				(font
					(size 0.7 0.7)
					(thickness 0.15)
				)
				(justify right top mirror)
			)
		)
		(property "Value" "R_0R_0402"
			(at -1.011843 -1.772046 90)
			(layer "B.Fab")
			(effects
				(font
					(size 0.7 0.7)
					(thickness 0.15)
				)
				(justify right top mirror)
			)
		)
		(property "Datasheet" "https://industrial.panasonic.com/cdbs/www-data/pdf/RDA0000/AOA0000C301.pdf"
			(at 0 0 90)
			(layer "B.Fab")
			(hide yes)
			(effects
				(font
					(size 1.27 1.27)
					(thickness 0.15)
				)
				(justify mirror)
			)
		)
		(property "Description" "SMD Chip Resistor, Jumper, 0 ohm, 100 mW, 0402 [1005 Metric], Thick Film, General Purpose"
			(at 0 0 90)
			(layer "B.Fab")
			(hide yes)
			(effects
				(font
					(size 1.27 1.27)
					(thickness 0.15)
				)
				(justify mirror)
			)
		)
		(property "Manufacturer" "Panasonic"
			(at 0 0 270)
			(unlocked yes)
			(layer "B.Fab")
			(hide yes)
			(effects
				(font
					(size 1 1)
					(thickness 0.15)
				)
				(justify mirror)
			)
		)
		(property "MPN" "ERJ2GE0R00X"
			(at 0 0 270)
			(unlocked yes)
			(layer "B.Fab")
			(hide yes)
			(effects
				(font
					(size 1 1)
					(thickness 0.15)
				)
				(justify mirror)
			)
		)
		(property "Val" "0R"
			(at 0 0 270)
			(unlocked yes)
			(layer "B.Fab")
			(hide yes)
			(effects
				(font
					(size 1 1)
					(thickness 0.15)
				)
				(justify mirror)
			)
		)
		(property "License" "Apache-2.0"
			(at 0 0 270)
			(unlocked yes)
			(layer "B.Fab")
			(hide yes)
			(effects
				(font
					(size 1 1)
					(thickness 0.15)
				)
				(justify mirror)
			)
		)
		(property "Author" "Antmicro"
			(at 0 0 270)
			(unlocked yes)
			(layer "B.Fab")
			(hide yes)
			(effects
				(font
					(size 1 1)
					(thickness 0.15)
				)
				(justify mirror)
			)
		)
		(property "Tolerance" "~"
			(at 0 0 270)
			(unlocked yes)
			(layer "B.Fab")
			(hide yes)
			(effects
				(font
					(size 1 1)
					(thickness 0.15)
				)
				(justify mirror)
			)
		)
		(property "Current" "1A"
			(at 0 0 270)
			(unlocked yes)
			(layer "B.Fab")
			(hide yes)
			(effects
				(font
					(size 1 1)
					(thickness 0.15)
				)
				(justify mirror)
			)
		)
		(sheetname "/CSI/")
		(sheetfile "csi.kicad_sch")
		(attr smd exclude_from_pos_files exclude_from_bom dnp)
		(fp_poly
			(pts
				(xy -0.925 0.47) (xy -0.925 -0.47) (xy 0.925 -0.47) (xy 0.925 0.47)
			)
			(stroke
				(width 0.05)
				(type default)
			)
			(fill no)
			(layer "B.CrtYd")
		)
		(fp_poly
			(pts
				(xy -0.5 0.25) (xy -0.5 -0.25) (xy 0.5 -0.25) (xy 0.5 0.25)
			)
			(stroke
				(width 0.15)
				(type solid)
			)
			(fill no)
			(layer "B.Fab")
		)
		(fp_text user "License: Apache-2.0"
			(at -0.949999 -5.169 90)
			(layer "B.Fab")
			(effects
				(font
					(size 0.7 0.7)
					(thickness 0.15)
				)
				(justify right top mirror)
			)
		)
		(fp_text user "${REFERENCE}"
			(at -0.95 -3.168 90)
			(layer "B.Fab")
			(effects
				(font
					(size 0.7 0.7)
					(thickness 0.15)
				)
				(justify right top mirror)
			)
		)
		(fp_text user "Author: Antmicro"
			(at -0.95 -4.169 90)
			(layer "B.Fab")
			(effects
				(font
					(size 0.7 0.7)
					(thickness 0.15)
				)
				(justify right top mirror)
			)
		)
		(pad "1" smd roundrect
			(at -0.48 0 90)
			(size 0.59 0.64)
			(layers "B.Cu" "B.Mask" "B.Paste")
			(roundrect_rratio 0.25)
			(net 990 "/CSI/CSIB_I2C_VCC")
			(pintype "passive")
		)
		(pad "2" smd roundrect
			(at 0.48 0 90)
			(size 0.59 0.64)
			(layers "B.Cu" "B.Mask" "B.Paste")
			(roundrect_rratio 0.25)
			(net 11 "+1V8")
			(pintype "passive")
		)
	)
	(footprint "antmicro-footprints:SOT-23-6"
		(layer "B.Cu")
		(at 179.286 76.046 90)
		(property "Reference" "U64"
			(at -1.14 -2.68 90)
			(layer "B.SilkS")
			(effects
				(font
					(size 0.7 0.7)
					(thickness 0.15)
				)
				(justify right top mirror)
			)
		)
		(property "Value" "LTC4412IS6"
			(at -1.75 -2.693 90)
			(layer "B.Fab")
			(effects
				(font
					(size 0.7 0.7)
					(thickness 0.15)
				)
				(justify right top mirror)
			)
		)
		(property "Datasheet" "https://www.analog.com/media/en/technical-documentation/data-sheets/4412fb.pdf"
			(at 0 0.057 90)
			(layer "B.Fab")
			(hide yes)
			(effects
				(font
					(size 1.27 1.27)
					(thickness 0.15)
				)
				(justify mirror)
			)
		)
		(property "Description" "Ideal diode controller"
			(at 0 0.057 90)
			(layer "B.Fab")
			(hide yes)
			(effects
				(font
					(size 1.27 1.27)
					(thickness 0.15)
				)
				(justify mirror)
			)
		)
		(property "MPN" "LTC4412IS6#TRMPBF"
			(at 0 0 270)
			(unlocked yes)
			(layer "B.Fab")
			(hide yes)
			(effects
				(font
					(size 1 1)
					(thickness 0.15)
				)
				(justify mirror)
			)
		)
		(property "Manufacturer" "Analog Devices"
			(at 0 0 270)
			(unlocked yes)
			(layer "B.Fab")
			(hide yes)
			(effects
				(font
					(size 1 1)
					(thickness 0.15)
				)
				(justify mirror)
			)
		)
		(property "Author" "Antmicro"
			(at 0 0 270)
			(unlocked yes)
			(layer "B.Fab")
			(hide yes)
			(effects
				(font
					(size 1 1)
					(thickness 0.15)
				)
				(justify mirror)
			)
		)
		(property "License" "Apache-2.0"
			(at 0 0 270)
			(unlocked yes)
			(layer "B.Fab")
			(hide yes)
			(effects
				(font
					(size 1 1)
					(thickness 0.15)
				)
				(justify mirror)
			)
		)
		(sheetname "/Power/")
		(sheetfile "power.kicad_sch")
		(attr smd)
		(fp_line
			(start 1.45 -0.643)
			(end 1.45 -0.343)
			(stroke
				(width 0.12)
				(type solid)
			)
			(layer "B.SilkS")
		)
		(fp_line
			(start 1.3 -0.643)
			(end 1.45 -0.643)
			(stroke
				(width 0.12)
				(type solid)
			)
			(layer "B.SilkS")
		)
		(fp_line
			(start -1.45 -0.643)
			(end -1.45 -0.343)
			(stroke
				(width 0.12)
				(type solid)
			)
			(layer "B.SilkS")
		)
		(fp_line
			(start 1.45 0.757)
			(end 1.45 0.457)
			(stroke
				(width 0.12)
				(type solid)
			)
			(layer "B.SilkS")
		)
		(fp_line
			(start 1.3 0.757)
			(end 1.45 0.757)
			(stroke
				(width 0.12)
				(type solid)
			)
			(layer "B.SilkS")
		)
		(fp_line
			(start -1.3 0.757)
			(end -1.45 0.757)
			(stroke
				(width 0.12)
				(type solid)
			)
			(layer "B.SilkS")
		)
		(fp_line
			(start -1.45 0.757)
			(end -1.45 0.457)
			(stroke
				(width 0.12)
				(type solid)
			)
			(layer "B.SilkS")
		)
		(fp_rect
			(start -1.55 1.85)
			(end 1.55 -1.75)
			(stroke
				(width 0.05)
				(type solid)
			)
			(fill no)
			(layer "B.CrtYd")
		)
		(fp_line
			(start 1.5 -0.643)
			(end -1.5 -0.643)
			(stroke
				(width 0.1)
				(type solid)
			)
			(layer "B.Fab")
		)
		(fp_line
			(start -1.5 -0.643)
			(end -1.5 0.757)
			(stroke
				(width 0.1)
				(type solid)
			)
			(layer "B.Fab")
		)
		(fp_line
			(start 1.5 0.757)
			(end 1.5 -0.643)
			(stroke
				(width 0.1)
				(type solid)
			)
			(layer "B.Fab")
		)
		(fp_line
			(start -1.5 0.757)
			(end 1.5 0.757)
			(stroke
				(width 0.1)
				(type solid)
			)
			(layer "B.Fab")
		)
		(fp_text user "."
			(at -1.4 -2.486 90)
			(layer "B.SilkS")
			(effects
				(font
					(size 1 1)
					(thickness 0.15)
				)
				(justify mirror)
			)
		)
		(fp_text user "License: Apache-2.0"
			(at -1.75 -6.5 90)
			(layer "B.Fab")
			(effects
				(font
					(size 0.7 0.7)
					(thickness 0.15)
				)
				(justify right top mirror)
			)
		)
		(fp_text user "Author: Antmicro"
			(at -1.829 -5.25 90)
			(layer "B.Fab")
			(effects
				(font
					(size 0.7 0.7)
					(thickness 0.15)
				)
				(justify right top mirror)
			)
		)
		(fp_text user "${REFERENCE}"
			(at -1.75 -4 90)
			(layer "B.Fab")
			(effects
				(font
					(size 0.7 0.7)
					(thickness 0.15)
				)
				(justify right top mirror)
			)
		)
		(pad "1" smd roundrect
			(at -0.954 -1.1 90)
			(size 0.55 1)
			(layers "B.Cu" "B.Mask" "B.Paste")
			(roundrect_rratio 0.15)
			(net 904 "+20V")
			(pinfunction "IN")
			(pintype "power_in")
		)
		(pad "2" smd roundrect
			(at -0.003 -1.1 90)
			(size 0.55 1)
			(layers "B.Cu" "B.Mask" "B.Paste")
			(roundrect_rratio 0.15)
			(net 1 "GND")
			(pinfunction "GND")
			(pintype "power_in")
		)
		(pad "3" smd roundrect
			(at 0.947 -1.1 90)
			(size 0.55 1)
			(layers "B.Cu" "B.Mask" "B.Paste")
			(roundrect_rratio 0.15)
			(net 1 "GND")
			(pinfunction "CTL")
			(pintype "input")
		)
		(pad "4" smd roundrect
			(at 0.947 1.214 90)
			(size 0.55 1)
			(layers "B.Cu" "B.Mask" "B.Paste")
			(roundrect_rratio 0.15)
			(net 1227 "unconnected-(U64-STAT-Pad4)")
			(pinfunction "STAT")
			(pintype "output+no_connect")
		)
		(pad "5" smd roundrect
			(at -0.003 1.214 90)
			(size 0.55 1)
			(layers "B.Cu" "B.Mask" "B.Paste")
			(roundrect_rratio 0.15)
			(net 1203 "Net-(Q25-G)")
			(pinfunction "GATE")
			(pintype "output")
		)
		(pad "6" smd roundrect
			(at -0.954 1.214 90)
			(size 0.55 1)
			(layers "B.Cu" "B.Mask" "B.Paste")
			(roundrect_rratio 0.15)
			(net 525 "/Power/USBPD2_HV")
			(pinfunction "SENSE")
			(pintype "input")
		)
	)
	(footprint "antmicro-footprints:R_0402_1005Metric"
		(layer "B.Cu")
		(at 111.12 120.59)
		(descr "Resistor SMD 0402")
		(tags "resistor SMD 0402")
		(property "Reference" "R218"
			(at -3.72 -0.39 0)
			(layer "B.SilkS")
			(effects
				(font
					(size 0.7 0.7)
					(thickness 0.15)
				)
				(justify right top mirror)
			)
		)
		(property "Value" "R_0R_0402"
			(at -1.011843 -1.772047 0)
			(layer "B.Fab")
			(effects
				(font
					(size 0.7 0.7)
					(thickness 0.15)
				)
				(justify right top mirror)
			)
		)
		(property "Datasheet" "https://industrial.panasonic.com/cdbs/www-data/pdf/RDA0000/AOA0000C301.pdf"
			(at 0 0 0)
			(layer "B.Fab")
			(hide yes)
			(effects
				(font
					(size 1.27 1.27)
					(thickness 0.15)
				)
				(justify mirror)
			)
		)
		(property "Description" "SMD Chip Resistor, Jumper, 0 ohm, 100 mW, 0402 [1005 Metric], Thick Film, General Purpose"
			(at 0 0 0)
			(layer "B.Fab")
			(hide yes)
			(effects
				(font
					(size 1.27 1.27)
					(thickness 0.15)
				)
				(justify mirror)
			)
		)
		(property "MPN" "ERJ2GE0R00X"
			(at 0 0 180)
			(unlocked yes)
			(layer "B.Fab")
			(hide yes)
			(effects
				(font
					(size 1 1)
					(thickness 0.15)
				)
				(justify mirror)
			)
		)
		(property "Manufacturer" "Panasonic"
			(at 0 0 180)
			(unlocked yes)
			(layer "B.Fab")
			(hide yes)
			(effects
				(font
					(size 1 1)
					(thickness 0.15)
				)
				(justify mirror)
			)
		)
		(property "License" "Apache-2.0"
			(at 0 0 180)
			(unlocked yes)
			(layer "B.Fab")
			(hide yes)
			(effects
				(font
					(size 1 1)
					(thickness 0.15)
				)
				(justify mirror)
			)
		)
		(property "Val" "0R"
			(at 0 0 180)
			(unlocked yes)
			(layer "B.Fab")
			(hide yes)
			(effects
				(font
					(size 1 1)
					(thickness 0.15)
				)
				(justify mirror)
			)
		)
		(property "Tolerance" "~"
			(at 0 0 180)
			(unlocked yes)
			(layer "B.Fab")
			(hide yes)
			(effects
				(font
					(size 1 1)
					(thickness 0.15)
				)
				(justify mirror)
			)
		)
		(property "Current" "1A"
			(at 0 0 180)
			(unlocked yes)
			(layer "B.Fab")
			(hide yes)
			(effects
				(font
					(size 1 1)
					(thickness 0.15)
				)
				(justify mirror)
			)
		)
		(property "Author" "Antmicro"
			(at 0 0 180)
			(unlocked yes)
			(layer "B.Fab")
			(hide yes)
			(effects
				(font
					(size 1 1)
					(thickness 0.15)
				)
				(justify mirror)
			)
		)
		(property "Public" "False"
			(at 0 0 180)
			(unlocked yes)
			(layer "B.Fab")
			(hide yes)
			(effects
				(font
					(size 1 1)
					(thickness 0.15)
				)
				(justify mirror)
			)
		)
		(sheetname "/M.2/")
		(sheetfile "m2.kicad_sch")
		(attr smd)
		(fp_rect
			(start -0.925 0.47)
			(end 0.925 -0.47)
			(stroke
				(width 0.05)
				(type default)
			)
			(fill no)
			(layer "B.CrtYd")
		)
		(fp_rect
			(start -0.5 0.25)
			(end 0.5 -0.25)
			(stroke
				(width 0.15)
				(type solid)
			)
			(fill no)
			(layer "B.Fab")
		)
		(fp_text user "${REFERENCE}"
			(at -0.95 -3.168 0)
			(layer "B.Fab")
			(effects
				(font
					(size 0.7 0.7)
					(thickness 0.15)
				)
				(justify right top mirror)
			)
		)
		(fp_text user "License: Apache-2.0"
			(at -0.95 -5.169 0)
			(layer "B.Fab")
			(effects
				(font
					(size 0.7 0.7)
					(thickness 0.15)
				)
				(justify right top mirror)
			)
		)
		(fp_text user "Author: Antmicro"
			(at -0.95 -4.169 0)
			(layer "B.Fab")
			(effects
				(font
					(size 0.7 0.7)
					(thickness 0.15)
				)
				(justify right top mirror)
			)
		)
		(pad "1" smd roundrect
			(at -0.48 0)
			(size 0.59 0.64)
			(layers "B.Cu" "B.Mask" "B.Paste")
			(roundrect_rratio 0.25)
			(net 653 "/M.2/USB3.D+")
			(pintype "passive")
		)
		(pad "2" smd roundrect
			(at 0.48 0)
			(size 0.59 0.64)
			(layers "B.Cu" "B.Mask" "B.Paste")
			(roundrect_rratio 0.25)
			(net 272 "/M.2/WIFI_BT_USB_D_P")
			(pintype "passive")
		)
	)
	(footprint "antmicro-footprints:R_0402_1005Metric"
		(layer "B.Cu")
		(at 194.8 87.8 90)
		(descr "Resistor SMD 0402")
		(tags "resistor SMD 0402")
		(property "Reference" "R383"
			(at -3.7 -0.4 90)
			(layer "B.SilkS")
			(effects
				(font
					(size 0.7 0.7)
					(thickness 0.15)
				)
				(justify right top mirror)
			)
		)
		(property "Value" "R_0R_0402"
			(at -1.011843 -1.772047 90)
			(layer "B.Fab")
			(effects
				(font
					(size 0.7 0.7)
					(thickness 0.15)
				)
				(justify right top mirror)
			)
		)
		(property "Datasheet" "https://industrial.panasonic.com/cdbs/www-data/pdf/RDA0000/AOA0000C301.pdf"
			(at 0 0 90)
			(layer "B.Fab")
			(hide yes)
			(effects
				(font
					(size 1.27 1.27)
					(thickness 0.15)
				)
				(justify mirror)
			)
		)
		(property "Description" "SMD Chip Resistor, Jumper, 0 ohm, 100 mW, 0402 [1005 Metric], Thick Film, General Purpose"
			(at 0 0 90)
			(layer "B.Fab")
			(hide yes)
			(effects
				(font
					(size 1.27 1.27)
					(thickness 0.15)
				)
				(justify mirror)
			)
		)
		(property "MPN" "ERJ2GE0R00X"
			(at 0 0 270)
			(unlocked yes)
			(layer "B.Fab")
			(hide yes)
			(effects
				(font
					(size 1 1)
					(thickness 0.15)
				)
				(justify mirror)
			)
		)
		(property "Manufacturer" "Panasonic"
			(at 0 0 270)
			(unlocked yes)
			(layer "B.Fab")
			(hide yes)
			(effects
				(font
					(size 1 1)
					(thickness 0.15)
				)
				(justify mirror)
			)
		)
		(property "License" "Apache-2.0"
			(at 0 0 270)
			(unlocked yes)
			(layer "B.Fab")
			(hide yes)
			(effects
				(font
					(size 1 1)
					(thickness 0.15)
				)
				(justify mirror)
			)
		)
		(property "Author" "Antmicro"
			(at 0 0 270)
			(unlocked yes)
			(layer "B.Fab")
			(hide yes)
			(effects
				(font
					(size 1 1)
					(thickness 0.15)
				)
				(justify mirror)
			)
		)
		(property "Val" "0R"
			(at 0 0 270)
			(unlocked yes)
			(layer "B.Fab")
			(hide yes)
			(effects
				(font
					(size 1 1)
					(thickness 0.15)
				)
				(justify mirror)
			)
		)
		(property "Tolerance" "~"
			(at 0 0 270)
			(unlocked yes)
			(layer "B.Fab")
			(hide yes)
			(effects
				(font
					(size 1 1)
					(thickness 0.15)
				)
				(justify mirror)
			)
		)
		(property "Current" "1A"
			(at 0 0 270)
			(unlocked yes)
			(layer "B.Fab")
			(hide yes)
			(effects
				(font
					(size 1 1)
					(thickness 0.15)
				)
				(justify mirror)
			)
		)
		(sheetname "/USB Debug, PD/")
		(sheetfile "usb_debug_pd.kicad_sch")
		(attr smd)
		(fp_rect
			(start -0.925 0.47)
			(end 0.925 -0.47)
			(stroke
				(width 0.05)
				(type default)
			)
			(fill no)
			(layer "B.CrtYd")
		)
		(fp_rect
			(start -0.5 0.25)
			(end 0.5 -0.25)
			(stroke
				(width 0.15)
				(type solid)
			)
			(fill no)
			(layer "B.Fab")
		)
		(fp_text user "${REFERENCE}"
			(at -0.95 -3.168 90)
			(layer "B.Fab")
			(effects
				(font
					(size 0.7 0.7)
					(thickness 0.15)
				)
				(justify right top mirror)
			)
		)
		(fp_text user "Author: Antmicro"
			(at -0.95 -4.169 90)
			(layer "B.Fab")
			(effects
				(font
					(size 0.7 0.7)
					(thickness 0.15)
				)
				(justify right top mirror)
			)
		)
		(fp_text user "License: Apache-2.0"
			(at -0.95 -5.169 90)
			(layer "B.Fab")
			(effects
				(font
					(size 0.7 0.7)
					(thickness 0.15)
				)
				(justify right top mirror)
			)
		)
		(pad "1" smd roundrect
			(at -0.48 0 90)
			(size 0.59 0.64)
			(layers "B.Cu" "B.Mask" "B.Paste")
			(roundrect_rratio 0.25)
			(net 532 "/USB Debug, PD/SCK")
			(pintype "passive")
		)
		(pad "2" smd roundrect
			(at 0.48 0 90)
			(size 0.59 0.64)
			(layers "B.Cu" "B.Mask" "B.Paste")
			(roundrect_rratio 0.25)
			(net 941 "/USB Debug, PD/PDC_SCLK")
			(pintype "passive")
		)
	)
	(footprint "antmicro-footprints:C_0402_1005Metric"
		(layer "B.Cu")
		(at 212.8 95.409002 90)
		(descr "Capacitor SMD 0402")
		(tags "capacitor SMD 0402")
		(property "Reference" "C322"
			(at -3.7 -0.4 90)
			(layer "B.SilkS")
			(effects
				(font
					(size 0.7 0.7)
					(thickness 0.15)
				)
				(justify right top mirror)
			)
		)
		(property "Value" "C_100n_0402"
			(at -1.022927 -2.155213 90)
			(layer "B.Fab")
			(effects
				(font
					(size 0.7 0.7)
					(thickness 0.15)
				)
				(justify right top mirror)
			)
		)
		(property "Datasheet" "https://www.murata.com/products/productdetail?partno=GRM155R61H104KE14%23"
			(at 0 0 90)
			(layer "B.Fab")
			(hide yes)
			(effects
				(font
					(size 1.27 1.27)
					(thickness 0.15)
				)
				(justify mirror)
			)
		)
		(property "Description" "SMD Multilayer Ceramic Capacitor, 0.1 µF, 50 V, 0402 [1005 Metric], ± 10%, X5R, GRM Series"
			(at 0 0 90)
			(layer "B.Fab")
			(hide yes)
			(effects
				(font
					(size 1.27 1.27)
					(thickness 0.15)
				)
				(justify mirror)
			)
		)
		(property "Manufacturer" "Murata"
			(at 0 0 270)
			(unlocked yes)
			(layer "B.Fab")
			(hide yes)
			(effects
				(font
					(size 1 1)
					(thickness 0.15)
				)
				(justify mirror)
			)
		)
		(property "MPN" "GRM155R61H104KE14D"
			(at 0 0 270)
			(unlocked yes)
			(layer "B.Fab")
			(hide yes)
			(effects
				(font
					(size 1 1)
					(thickness 0.15)
				)
				(justify mirror)
			)
		)
		(property "Val" "100n"
			(at 0 0 270)
			(unlocked yes)
			(layer "B.Fab")
			(hide yes)
			(effects
				(font
					(size 1 1)
					(thickness 0.15)
				)
				(justify mirror)
			)
		)
		(property "License" "Apache-2.0"
			(at 0 0 270)
			(unlocked yes)
			(layer "B.Fab")
			(hide yes)
			(effects
				(font
					(size 1 1)
					(thickness 0.15)
				)
				(justify mirror)
			)
		)
		(property "Author" "Antmicro"
			(at 0 0 270)
			(unlocked yes)
			(layer "B.Fab")
			(hide yes)
			(effects
				(font
					(size 1 1)
					(thickness 0.15)
				)
				(justify mirror)
			)
		)
		(property "Voltage" "50V"
			(at 0 0 270)
			(unlocked yes)
			(layer "B.Fab")
			(hide yes)
			(effects
				(font
					(size 1 1)
					(thickness 0.15)
				)
				(justify mirror)
			)
		)
		(property "Dielectric" "X5R"
			(at 0 0 270)
			(unlocked yes)
			(layer "B.Fab")
			(hide yes)
			(effects
				(font
					(size 1 1)
					(thickness 0.15)
				)
				(justify mirror)
			)
		)
		(sheetname "/SoM_IO2/")
		(sheetfile "som_io2.kicad_sch")
		(attr smd)
		(fp_rect
			(start -0.925 0.47)
			(end 0.925 -0.47)
			(stroke
				(width 0.05)
				(type default)
			)
			(fill no)
			(layer "B.CrtYd")
		)
		(fp_line
			(start 0.504 -0.248)
			(end -0.494 -0.248)
			(stroke
				(width 0.15)
				(type solid)
			)
			(layer "B.Fab")
		)
		(fp_line
			(start -0.494 -0.248)
			(end -0.494 0.25)
			(stroke
				(width 0.15)
				(type solid)
			)
			(layer "B.Fab")
		)
		(fp_line
			(start 0.504 0.25)
			(end 0.504 -0.248)
			(stroke
				(width 0.15)
				(type solid)
			)
			(layer "B.Fab")
		)
		(fp_line
			(start -0.494 0.25)
			(end 0.504 0.25)
			(stroke
				(width 0.15)
				(type solid)
			)
			(layer "B.Fab")
		)
		(fp_text user "License: Apache-2.0"
			(at -0.939 -5.799 90)
			(layer "B.Fab")
			(effects
				(font
					(size 0.7 0.7)
					(thickness 0.15)
				)
				(justify right top mirror)
			)
		)
		(fp_text user "${REFERENCE}"
			(at -0.939 -4.599 90)
			(layer "B.Fab")
			(effects
				(font
					(size 0.7 0.7)
					(thickness 0.15)
				)
				(justify right top mirror)
			)
		)
		(fp_text user "Author: Antmicro"
			(at -0.939 -3.399 90)
			(layer "B.Fab")
			(effects
				(font
					(size 0.7 0.7)
					(thickness 0.15)
				)
				(justify right top mirror)
			)
		)
		(pad "1" smd roundrect
			(at -0.48 0 90)
			(size 0.59 0.64)
			(layers "B.Cu" "B.Mask" "B.Paste")
			(roundrect_rratio 0.25)
			(net 1088 "/SoM_IO2/DP0.AUX_C+")
			(pintype "passive")
		)
		(pad "2" smd roundrect
			(at 0.48 0 90)
			(size 0.59 0.64)
			(layers "B.Cu" "B.Mask" "B.Paste")
			(roundrect_rratio 0.25)
			(net 635 "/SoM_IO2/DP0.AUX+")
			(pintype "passive")
		)
	)
	(footprint "antmicro-footprints:C_0402_1005Metric"
		(layer "B.Cu")
		(at 92.180001 103.6 -90)
		(descr "Capacitor SMD 0402")
		(tags "capacitor SMD 0402")
		(property "Reference" "C327"
			(at -3.8 -0.419999 90)
			(layer "B.SilkS")
			(effects
				(font
					(size 0.7 0.7)
					(thickness 0.15)
				)
				(justify left bottom mirror)
			)
		)
		(property "Value" "C_100n_0402"
			(at -1.022927 -2.155213 90)
			(layer "B.Fab")
			(effects
				(font
					(size 0.7 0.7)
					(thickness 0.15)
				)
				(justify left bottom mirror)
			)
		)
		(property "Datasheet" "https://www.murata.com/products/productdetail?partno=GRM155R61H104KE14%23"
			(at 0 0 90)
			(layer "B.Fab")
			(hide yes)
			(effects
				(font
					(size 1.27 1.27)
					(thickness 0.15)
				)
				(justify mirror)
			)
		)
		(property "Description" "SMD Multilayer Ceramic Capacitor, 0.1 µF, 50 V, 0402 [1005 Metric], ± 10%, X5R, GRM Series"
			(at 0 0 90)
			(layer "B.Fab")
			(hide yes)
			(effects
				(font
					(size 1.27 1.27)
					(thickness 0.15)
				)
				(justify mirror)
			)
		)
		(property "Manufacturer" "Murata"
			(at 0 0 90)
			(unlocked yes)
			(layer "B.Fab")
			(hide yes)
			(effects
				(font
					(size 1 1)
					(thickness 0.15)
				)
				(justify mirror)
			)
		)
		(property "MPN" "GRM155R61H104KE14D"
			(at 0 0 90)
			(unlocked yes)
			(layer "B.Fab")
			(hide yes)
			(effects
				(font
					(size 1 1)
					(thickness 0.15)
				)
				(justify mirror)
			)
		)
		(property "Val" "100n"
			(at 0 0 90)
			(unlocked yes)
			(layer "B.Fab")
			(hide yes)
			(effects
				(font
					(size 1 1)
					(thickness 0.15)
				)
				(justify mirror)
			)
		)
		(property "License" "Apache-2.0"
			(at 0 0 90)
			(unlocked yes)
			(layer "B.Fab")
			(hide yes)
			(effects
				(font
					(size 1 1)
					(thickness 0.15)
				)
				(justify mirror)
			)
		)
		(property "Author" "Antmicro"
			(at 0 0 90)
			(unlocked yes)
			(layer "B.Fab")
			(hide yes)
			(effects
				(font
					(size 1 1)
					(thickness 0.15)
				)
				(justify mirror)
			)
		)
		(property "Voltage" "50V"
			(at 0 0 90)
			(unlocked yes)
			(layer "B.Fab")
			(hide yes)
			(effects
				(font
					(size 1 1)
					(thickness 0.15)
				)
				(justify mirror)
			)
		)
		(property "Dielectric" "X5R"
			(at 0 0 90)
			(unlocked yes)
			(layer "B.Fab")
			(hide yes)
			(effects
				(font
					(size 1 1)
					(thickness 0.15)
				)
				(justify mirror)
			)
		)
		(sheetname "/SoM_IO2/")
		(sheetfile "som_io2.kicad_sch")
		(attr smd)
		(fp_poly
			(pts
				(xy -0.925 0.47) (xy 0.925 0.47) (xy 0.925 -0.47) (xy -0.925 -0.47)
			)
			(stroke
				(width 0.05)
				(type default)
			)
			(fill no)
			(layer "B.CrtYd")
		)
		(fp_line
			(start -0.494 0.25)
			(end 0.504 0.25)
			(stroke
				(width 0.15)
				(type solid)
			)
			(layer "B.Fab")
		)
		(fp_line
			(start 0.504 0.25)
			(end 0.504 -0.248)
			(stroke
				(width 0.15)
				(type solid)
			)
			(layer "B.Fab")
		)
		(fp_line
			(start -0.494 -0.248)
			(end -0.494 0.25)
			(stroke
				(width 0.15)
				(type solid)
			)
			(layer "B.Fab")
		)
		(fp_line
			(start 0.504 -0.248)
			(end -0.494 -0.248)
			(stroke
				(width 0.15)
				(type solid)
			)
			(layer "B.Fab")
		)
		(fp_text user "License: Apache-2.0"
			(at -0.939 -5.799 90)
			(layer "B.Fab")
			(effects
				(font
					(size 0.7 0.7)
					(thickness 0.15)
				)
				(justify left bottom mirror)
			)
		)
		(fp_text user "Author: Antmicro"
			(at -0.939 -3.399 90)
			(layer "B.Fab")
			(effects
				(font
					(size 0.7 0.7)
					(thickness 0.15)
				)
				(justify left bottom mirror)
			)
		)
		(fp_text user "${REFERENCE}"
			(at -0.939 -4.599 90)
			(layer "B.Fab")
			(effects
				(font
					(size 0.7 0.7)
					(thickness 0.15)
				)
				(justify left bottom mirror)
			)
		)
		(pad "1" smd roundrect
			(at -0.48 0 270)
			(size 0.59 0.64)
			(layers "B.Cu" "B.Mask" "B.Paste")
			(roundrect_rratio 0.25)
			(net 794 "/Expansion connector/DP1.TX3+")
			(pintype "passive")
		)
		(pad "2" smd roundrect
			(at 0.48 0 270)
			(size 0.59 0.64)
			(layers "B.Cu" "B.Mask" "B.Paste")
			(roundrect_rratio 0.25)
			(net 1247 "/SoM_IO2/DP1.TX3_C+")
			(pintype "passive")
		)
	)
	(footprint "antmicro-footprints:Conn_JST_SH_1x4_SM04B-SRSS-TB-LF-SN"
		(locked yes)
		(layer "B.Cu")
		(at 147.13 56.86)
		(property "Reference" "J17"
			(at 3.97 -0.96 270)
			(layer "B.SilkS")
			(effects
				(font
					(size 0.7 0.7)
					(thickness 0.15)
				)
				(justify right top mirror)
			)
		)
		(property "Value" "JST_SH_1x4_SM04B-SRSS-TB-LF-SN"
			(at -4 -3.88 0)
			(layer "B.Fab")
			(effects
				(font
					(size 0.7 0.7)
					(thickness 0.15)
				)
				(justify right top mirror)
			)
		)
		(property "Datasheet" "https://www.jst-mfg.com/product/pdf/eng/eSH.pdf"
			(at 0 0 0)
			(layer "B.Fab")
			(hide yes)
			(effects
				(font
					(size 1.27 1.27)
					(thickness 0.15)
				)
				(justify mirror)
			)
		)
		(property "Description" "Pin Header, Right Angle, Wire-to-Board, 1 mm, 1 Rows, 4 Contacts, Surface Mount Right Angle, SH"
			(at 0 0 0)
			(layer "B.Fab")
			(hide yes)
			(effects
				(font
					(size 1.27 1.27)
					(thickness 0.15)
				)
				(justify mirror)
			)
		)
		(property "MPN" "SM04B-SRSS-TB(LF)(SN)"
			(at 0 0 180)
			(unlocked yes)
			(layer "B.Fab")
			(hide yes)
			(effects
				(font
					(size 1 1)
					(thickness 0.15)
				)
				(justify mirror)
			)
		)
		(property "Manufacturer" "JST Automotive Connectors"
			(at 0 0 180)
			(unlocked yes)
			(layer "B.Fab")
			(hide yes)
			(effects
				(font
					(size 1 1)
					(thickness 0.15)
				)
				(justify mirror)
			)
		)
		(property "Author" "Antmicro"
			(at 0 0 180)
			(unlocked yes)
			(layer "B.Fab")
			(hide yes)
			(effects
				(font
					(size 1 1)
					(thickness 0.15)
				)
				(justify mirror)
			)
		)
		(property "License" "Apache-2.0"
			(at 0 0 180)
			(unlocked yes)
			(layer "B.Fab")
			(hide yes)
			(effects
				(font
					(size 1 1)
					(thickness 0.15)
				)
				(justify mirror)
			)
		)
		(sheetname "/Peripherals/")
		(sheetfile "peripherals.kicad_sch")
		(attr smd)
		(fp_line
			(start -3.2 2)
			(end -3.2 -0.6)
			(stroke
				(width 0.15)
				(type solid)
			)
			(layer "B.SilkS")
		)
		(fp_line
			(start -2 -2.6)
			(end 2 -2.6)
			(stroke
				(width 0.15)
				(type solid)
			)
			(layer "B.SilkS")
		)
		(fp_line
			(start -2 2)
			(end -3.2 2)
			(stroke
				(width 0.15)
				(type solid)
			)
			(layer "B.SilkS")
		)
		(fp_line
			(start 2 2)
			(end 3.2 2)
			(stroke
				(width 0.15)
				(type solid)
			)
			(layer "B.SilkS")
		)
		(fp_line
			(start 3.2 2)
			(end 3.2 -0.6)
			(stroke
				(width 0.15)
				(type solid)
			)
			(layer "B.SilkS")
		)
		(fp_circle
			(center -2.1 2.5)
			(end -2.05 2.5)
			(stroke
				(width 0.15)
				(type solid)
			)
			(fill yes)
			(layer "B.SilkS")
		)
		(fp_rect
			(start -3.65 3.14)
			(end 3.65 -2.9)
			(stroke
				(width 0.05)
				(type solid)
			)
			(fill no)
			(layer "B.CrtYd")
		)
		(fp_rect
			(start -3 2.475)
			(end 3 -2.475)
			(stroke
				(width 0.15)
				(type solid)
			)
			(fill no)
			(layer "B.Fab")
		)
		(fp_text user "${REFERENCE}"
			(at -4 -8.28 0)
			(layer "B.Fab")
			(effects
				(font
					(size 0.7 0.7)
					(thickness 0.15)
				)
				(justify right top mirror)
			)
		)
		(fp_text user "Author: Antmicro"
			(at -4 -7.08 0)
			(layer "B.Fab")
			(effects
				(font
					(size 0.7 0.7)
					(thickness 0.15)
				)
				(justify right top mirror)
			)
		)
		(fp_text user "License: Apache-2.0"
			(at -4 -5.88 0)
			(layer "B.Fab")
			(effects
				(font
					(size 0.7 0.7)
					(thickness 0.15)
				)
				(justify right top mirror)
			)
		)
		(pad "1" smd roundrect
			(at -1.5 2.12 180)
			(size 0.6 1.55)
			(layers "B.Cu" "B.Mask" "B.Paste")
			(roundrect_rratio 0.25)
			(net 1 "GND")
			(pintype "passive")
		)
		(pad "2" smd roundrect
			(at -0.5 2.12 180)
			(size 0.6 1.55)
			(layers "B.Cu" "B.Mask" "B.Paste")
			(roundrect_rratio 0.25)
			(net 839 "/Peripherals/I2C_CONN2_3V3")
			(pintype "passive")
		)
		(pad "3" smd roundrect
			(at 0.5 2.12 180)
			(size 0.6 1.55)
			(layers "B.Cu" "B.Mask" "B.Paste")
			(roundrect_rratio 0.25)
			(net 43 "/Peripherals/I2C_{CONN}.SDA")
			(pintype "passive")
		)
		(pad "4" smd roundrect
			(at 1.5 2.12 180)
			(size 0.6 1.55)
			(layers "B.Cu" "B.Mask" "B.Paste")
			(roundrect_rratio 0.25)
			(net 42 "/Peripherals/I2C_{CONN}.SCL")
			(pintype "passive")
		)
		(pad "MP" smd roundrect
			(at -2.8 -1.755)
			(size 1.2 1.8)
			(layers "B.Cu" "B.Mask" "B.Paste")
			(roundrect_rratio 0.25)
			(net 1 "GND")
			(pintype "passive")
		)
		(pad "MP" smd roundrect
			(at 2.8 -1.755)
			(size 1.2 1.8)
			(layers "B.Cu" "B.Mask" "B.Paste")
			(roundrect_rratio 0.25)
			(net 1 "GND")
			(pintype "passive")
		)
	)
	(footprint "antmicro-footprints:R_0402_1005Metric"
		(layer "B.Cu")
		(at 164 57.5 -90)
		(descr "Resistor SMD 0402")
		(tags "resistor SMD 0402")
		(property "Reference" "R257"
			(at -3.62 -0.335532 90)
			(layer "B.SilkS")
			(effects
				(font
					(size 0.7 0.7)
					(thickness 0.15)
				)
				(justify left bottom mirror)
			)
		)
		(property "Value" "R_470R_0402"
			(at -1.011843 -1.772047 90)
			(layer "B.Fab")
			(effects
				(font
					(size 0.7 0.7)
					(thickness 0.15)
				)
				(justify left bottom mirror)
			)
		)
		(property "Datasheet" "https://www.bourns.com/docs/product-datasheets/cr.pdf"
			(at 0 0 90)
			(layer "B.Fab")
			(hide yes)
			(effects
				(font
					(size 1.27 1.27)
					(thickness 0.15)
				)
				(justify mirror)
			)
		)
		(property "Description" "SMD Chip Resistor, 470 ohm, ± 1%, 62.5 mW, 0402 [1005 Metric], Thick Film, General Purpose"
			(at 0 0 90)
			(layer "B.Fab")
			(hide yes)
			(effects
				(font
					(size 1.27 1.27)
					(thickness 0.15)
				)
				(justify mirror)
			)
		)
		(property "Manufacturer" "Bourns"
			(at 0 0 90)
			(unlocked yes)
			(layer "B.Fab")
			(hide yes)
			(effects
				(font
					(size 1 1)
					(thickness 0.15)
				)
				(justify mirror)
			)
		)
		(property "MPN" "CR0402-FX-4700GLF"
			(at 0 0 90)
			(unlocked yes)
			(layer "B.Fab")
			(hide yes)
			(effects
				(font
					(size 1 1)
					(thickness 0.15)
				)
				(justify mirror)
			)
		)
		(property "Val" "470R"
			(at 0 0 90)
			(unlocked yes)
			(layer "B.Fab")
			(hide yes)
			(effects
				(font
					(size 1 1)
					(thickness 0.15)
				)
				(justify mirror)
			)
		)
		(property "License" "Apache-2.0"
			(at 0 0 90)
			(unlocked yes)
			(layer "B.Fab")
			(hide yes)
			(effects
				(font
					(size 1 1)
					(thickness 0.15)
				)
				(justify mirror)
			)
		)
		(property "Author" "Antmicro"
			(at 0 0 90)
			(unlocked yes)
			(layer "B.Fab")
			(hide yes)
			(effects
				(font
					(size 1 1)
					(thickness 0.15)
				)
				(justify mirror)
			)
		)
		(property "Tolerance" "1%"
			(at 0 0 90)
			(unlocked yes)
			(layer "B.Fab")
			(hide yes)
			(effects
				(font
					(size 1 1)
					(thickness 0.15)
				)
				(justify mirror)
			)
		)
		(sheetname "/Power/")
		(sheetfile "power.kicad_sch")
		(attr smd)
		(fp_rect
			(start -0.925 0.47)
			(end 0.925 -0.47)
			(stroke
				(width 0.05)
				(type default)
			)
			(fill no)
			(layer "B.CrtYd")
		)
		(fp_rect
			(start -0.5 0.25)
			(end 0.5 -0.25)
			(stroke
				(width 0.15)
				(type solid)
			)
			(fill no)
			(layer "B.Fab")
		)
		(fp_text user "Author: Antmicro"
			(at -0.95 -4.169 90)
			(layer "B.Fab")
			(effects
				(font
					(size 0.7 0.7)
					(thickness 0.15)
				)
				(justify left bottom mirror)
			)
		)
		(fp_text user "License: Apache-2.0"
			(at -0.95 -5.169 90)
			(layer "B.Fab")
			(effects
				(font
					(size 0.7 0.7)
					(thickness 0.15)
				)
				(justify left bottom mirror)
			)
		)
		(fp_text user "${REFERENCE}"
			(at -0.95 -3.168 90)
			(layer "B.Fab")
			(effects
				(font
					(size 0.7 0.7)
					(thickness 0.15)
				)
				(justify left bottom mirror)
			)
		)
		(pad "1" smd roundrect
			(at -0.48 0 270)
			(size 0.59 0.64)
			(layers "B.Cu" "B.Mask" "B.Paste")
			(roundrect_rratio 0.25)
			(net 645 "Net-(D43-A)")
			(pintype "passive")
		)
		(pad "2" smd roundrect
			(at 0.48 0 270)
			(size 0.59 0.64)
			(layers "B.Cu" "B.Mask" "B.Paste")
			(roundrect_rratio 0.25)
			(net 5 "+5V")
			(pintype "passive")
		)
	)
	(footprint "antmicro-footprints:R_0402_1005Metric"
		(layer "B.Cu")
		(at 196.6 131.65 90)
		(descr "Resistor SMD 0402")
		(tags "resistor SMD 0402")
		(property "Reference" "R322"
			(at -1.32 0.578198 90)
			(layer "B.SilkS")
			(effects
				(font
					(size 0.7 0.7)
					(thickness 0.15)
				)
				(justify right top mirror)
			)
		)
		(property "Value" "R_200k_0402"
			(at -1.011843 -1.772046 90)
			(layer "B.Fab")
			(effects
				(font
					(size 0.7 0.7)
					(thickness 0.15)
				)
				(justify right top mirror)
			)
		)
		(property "Datasheet" "https://www.bourns.com/docs/product-datasheets/cr.pdf"
			(at 0 0 90)
			(layer "B.Fab")
			(hide yes)
			(effects
				(font
					(size 1.27 1.27)
					(thickness 0.15)
				)
				(justify mirror)
			)
		)
		(property "Description" "SMD Chip Resistor, 200 kohm, ± 1%, 62.5 mW, 0402 [1005 Metric], Thick Film, General Purpose"
			(at 0 0 90)
			(layer "B.Fab")
			(hide yes)
			(effects
				(font
					(size 1.27 1.27)
					(thickness 0.15)
				)
				(justify mirror)
			)
		)
		(property "MPN" "CR0402-FX-2003GLF"
			(at 0 0 270)
			(unlocked yes)
			(layer "B.Fab")
			(hide yes)
			(effects
				(font
					(size 1 1)
					(thickness 0.15)
				)
				(justify mirror)
			)
		)
		(property "Manufacturer" "Bourns"
			(at 0 0 270)
			(unlocked yes)
			(layer "B.Fab")
			(hide yes)
			(effects
				(font
					(size 1 1)
					(thickness 0.15)
				)
				(justify mirror)
			)
		)
		(property "License" "Apache-2.0"
			(at 0 0 270)
			(unlocked yes)
			(layer "B.Fab")
			(hide yes)
			(effects
				(font
					(size 1 1)
					(thickness 0.15)
				)
				(justify mirror)
			)
		)
		(property "Author" "Antmicro"
			(at 0 0 270)
			(unlocked yes)
			(layer "B.Fab")
			(hide yes)
			(effects
				(font
					(size 1 1)
					(thickness 0.15)
				)
				(justify mirror)
			)
		)
		(property "Val" "200k"
			(at 0 0 270)
			(unlocked yes)
			(layer "B.Fab")
			(hide yes)
			(effects
				(font
					(size 1 1)
					(thickness 0.15)
				)
				(justify mirror)
			)
		)
		(property "Tolerance" "1%"
			(at 0 0 270)
			(unlocked yes)
			(layer "B.Fab")
			(hide yes)
			(effects
				(font
					(size 1 1)
					(thickness 0.15)
				)
				(justify mirror)
			)
		)
		(sheetname "/USB Hub/")
		(sheetfile "usb_hub.kicad_sch")
		(attr smd)
		(fp_poly
			(pts
				(xy -0.925 0.47) (xy -0.925 -0.47) (xy 0.925 -0.47) (xy 0.925 0.47)
			)
			(stroke
				(width 0.05)
				(type default)
			)
			(fill no)
			(layer "B.CrtYd")
		)
		(fp_poly
			(pts
				(xy -0.5 0.25) (xy -0.5 -0.25) (xy 0.5 -0.25) (xy 0.5 0.25)
			)
			(stroke
				(width 0.15)
				(type solid)
			)
			(fill no)
			(layer "B.Fab")
		)
		(fp_text user "Author: Antmicro"
			(at -0.95 -4.169 90)
			(layer "B.Fab")
			(effects
				(font
					(size 0.7 0.7)
					(thickness 0.15)
				)
				(justify right top mirror)
			)
		)
		(fp_text user "License: Apache-2.0"
			(at -0.949999 -5.169 90)
			(layer "B.Fab")
			(effects
				(font
					(size 0.7 0.7)
					(thickness 0.15)
				)
				(justify right top mirror)
			)
		)
		(fp_text user "${REFERENCE}"
			(at -0.95 -3.168 90)
			(layer "B.Fab")
			(effects
				(font
					(size 0.7 0.7)
					(thickness 0.15)
				)
				(justify right top mirror)
			)
		)
		(pad "1" smd roundrect
			(at -0.48 0 90)
			(size 0.59 0.64)
			(layers "B.Cu" "B.Mask" "B.Paste")
			(roundrect_rratio 0.25)
			(net 1 "GND")
			(pintype "passive")
		)
		(pad "2" smd roundrect
			(at 0.48 0 90)
			(size 0.59 0.64)
			(layers "B.Cu" "B.Mask" "B.Paste")
			(roundrect_rratio 0.25)
			(net 930 "/USB Hub/HUB_SPI_CE_N")
			(pintype "passive")
		)
	)
	(footprint "antmicro-footprints:TP_SMD_0.75mm"
		(layer "B.Cu")
		(at 217.4 90.81 -90)
		(property "Reference" "TP17"
			(at 0.39 -3.3 0)
			(layer "B.SilkS")
			(effects
				(font
					(size 0.7 0.7)
					(thickness 0.15)
				)
				(justify left bottom mirror)
			)
		)
		(property "Value" "TP_0.75mm_SMD"
			(at 0 -1.2 90)
			(layer "B.Fab")
			(effects
				(font
					(size 0.7 0.7)
					(thickness 0.15)
				)
				(justify left bottom mirror)
			)
		)
		(property "Description" "SMT test point"
			(at 0 0 90)
			(layer "B.Fab")
			(hide yes)
			(effects
				(font
					(size 1.27 1.27)
					(thickness 0.15)
				)
				(justify mirror)
			)
		)
		(property "MPN" ""
			(at 0 0 90)
			(unlocked yes)
			(layer "B.Fab")
			(hide yes)
			(effects
				(font
					(size 1 1)
					(thickness 0.15)
				)
				(justify mirror)
			)
		)
		(property "Manufacturer" ""
			(at 0 0 90)
			(unlocked yes)
			(layer "B.Fab")
			(hide yes)
			(effects
				(font
					(size 1 1)
					(thickness 0.15)
				)
				(justify mirror)
			)
		)
		(property "Author" "Antmicro"
			(at 0 0 90)
			(unlocked yes)
			(layer "B.Fab")
			(hide yes)
			(effects
				(font
					(size 1 1)
					(thickness 0.15)
				)
				(justify mirror)
			)
		)
		(property "License" "Apache-2.0"
			(at 0 0 90)
			(unlocked yes)
			(layer "B.Fab")
			(hide yes)
			(effects
				(font
					(size 1 1)
					(thickness 0.15)
				)
				(justify mirror)
			)
		)
		(sheetname "/USB DP Alt mode/")
		(sheetfile "usb_dp.kicad_sch")
		(attr exclude_from_pos_files exclude_from_bom)
		(fp_circle
			(center 0 0)
			(end 0.475 0)
			(stroke
				(width 0.05)
				(type default)
			)
			(fill no)
			(layer "B.CrtYd")
		)
		(fp_text user "Author: Antmicro"
			(at -0.4 -3.901 90)
			(layer "B.Fab")
			(effects
				(font
					(size 0.7 0.7)
					(thickness 0.15)
				)
				(justify left bottom mirror)
			)
		)
		(fp_text user "${REFERENCE}"
			(at -0.4 -2.7 90)
			(layer "B.Fab")
			(effects
				(font
					(size 0.7 0.7)
					(thickness 0.15)
				)
				(justify left bottom mirror)
			)
		)
		(fp_text user "License: Apache-2.0"
			(at -0.4 -5.101 90)
			(layer "B.Fab")
			(effects
				(font
					(size 0.7 0.7)
					(thickness 0.15)
				)
				(justify left bottom mirror)
			)
		)
		(pad "1" smd circle
			(at -0.01 0 270)
			(size 0.75 0.75)
			(layers "B.Cu" "B.Mask")
			(net 957 "/USB DP Alt mode/HPDIN")
			(pinfunction "1")
			(pintype "passive")
		)
	)
	(footprint "antmicro-footprints:C_0402_1005Metric"
		(layer "B.Cu")
		(at 213.8 95.4 90)
		(descr "Capacitor SMD 0402")
		(tags "capacitor SMD 0402")
		(property "Reference" "C323"
			(at -3.7 -0.4 90)
			(layer "B.SilkS")
			(effects
				(font
					(size 0.7 0.7)
					(thickness 0.15)
				)
				(justify right top mirror)
			)
		)
		(property "Value" "C_100n_0402"
			(at -1.022927 -2.155213 90)
			(layer "B.Fab")
			(effects
				(font
					(size 0.7 0.7)
					(thickness 0.15)
				)
				(justify right top mirror)
			)
		)
		(property "Datasheet" "https://www.murata.com/products/productdetail?partno=GRM155R61H104KE14%23"
			(at 0 0 90)
			(layer "B.Fab")
			(hide yes)
			(effects
				(font
					(size 1.27 1.27)
					(thickness 0.15)
				)
				(justify mirror)
			)
		)
		(property "Description" "SMD Multilayer Ceramic Capacitor, 0.1 µF, 50 V, 0402 [1005 Metric], ± 10%, X5R, GRM Series"
			(at 0 0 90)
			(layer "B.Fab")
			(hide yes)
			(effects
				(font
					(size 1.27 1.27)
					(thickness 0.15)
				)
				(justify mirror)
			)
		)
		(property "Manufacturer" "Murata"
			(at 0 0 270)
			(unlocked yes)
			(layer "B.Fab")
			(hide yes)
			(effects
				(font
					(size 1 1)
					(thickness 0.15)
				)
				(justify mirror)
			)
		)
		(property "MPN" "GRM155R61H104KE14D"
			(at 0 0 270)
			(unlocked yes)
			(layer "B.Fab")
			(hide yes)
			(effects
				(font
					(size 1 1)
					(thickness 0.15)
				)
				(justify mirror)
			)
		)
		(property "Val" "100n"
			(at 0 0 270)
			(unlocked yes)
			(layer "B.Fab")
			(hide yes)
			(effects
				(font
					(size 1 1)
					(thickness 0.15)
				)
				(justify mirror)
			)
		)
		(property "License" "Apache-2.0"
			(at 0 0 270)
			(unlocked yes)
			(layer "B.Fab")
			(hide yes)
			(effects
				(font
					(size 1 1)
					(thickness 0.15)
				)
				(justify mirror)
			)
		)
		(property "Author" "Antmicro"
			(at 0 0 270)
			(unlocked yes)
			(layer "B.Fab")
			(hide yes)
			(effects
				(font
					(size 1 1)
					(thickness 0.15)
				)
				(justify mirror)
			)
		)
		(property "Voltage" "50V"
			(at 0 0 270)
			(unlocked yes)
			(layer "B.Fab")
			(hide yes)
			(effects
				(font
					(size 1 1)
					(thickness 0.15)
				)
				(justify mirror)
			)
		)
		(property "Dielectric" "X5R"
			(at 0 0 270)
			(unlocked yes)
			(layer "B.Fab")
			(hide yes)
			(effects
				(font
					(size 1 1)
					(thickness 0.15)
				)
				(justify mirror)
			)
		)
		(sheetname "/SoM_IO2/")
		(sheetfile "som_io2.kicad_sch")
		(attr smd)
		(fp_rect
			(start -0.925 0.47)
			(end 0.925 -0.47)
			(stroke
				(width 0.05)
				(type default)
			)
			(fill no)
			(layer "B.CrtYd")
		)
		(fp_line
			(start 0.504 -0.248)
			(end -0.494 -0.248)
			(stroke
				(width 0.15)
				(type solid)
			)
			(layer "B.Fab")
		)
		(fp_line
			(start -0.494 -0.248)
			(end -0.494 0.25)
			(stroke
				(width 0.15)
				(type solid)
			)
			(layer "B.Fab")
		)
		(fp_line
			(start 0.504 0.25)
			(end 0.504 -0.248)
			(stroke
				(width 0.15)
				(type solid)
			)
			(layer "B.Fab")
		)
		(fp_line
			(start -0.494 0.25)
			(end 0.504 0.25)
			(stroke
				(width 0.15)
				(type solid)
			)
			(layer "B.Fab")
		)
		(fp_text user "License: Apache-2.0"
			(at -0.939 -5.799 90)
			(layer "B.Fab")
			(effects
				(font
					(size 0.7 0.7)
					(thickness 0.15)
				)
				(justify right top mirror)
			)
		)
		(fp_text user "Author: Antmicro"
			(at -0.939 -3.399 90)
			(layer "B.Fab")
			(effects
				(font
					(size 0.7 0.7)
					(thickness 0.15)
				)
				(justify right top mirror)
			)
		)
		(fp_text user "${REFERENCE}"
			(at -0.939 -4.599 90)
			(layer "B.Fab")
			(effects
				(font
					(size 0.7 0.7)
					(thickness 0.15)
				)
				(justify right top mirror)
			)
		)
		(pad "1" smd roundrect
			(at -0.48 0 90)
			(size 0.59 0.64)
			(layers "B.Cu" "B.Mask" "B.Paste")
			(roundrect_rratio 0.25)
			(net 1112 "/SoM_IO2/DP0.AUX_C-")
			(pintype "passive")
		)
		(pad "2" smd roundrect
			(at 0.48 0 90)
			(size 0.59 0.64)
			(layers "B.Cu" "B.Mask" "B.Paste")
			(roundrect_rratio 0.25)
			(net 607 "/SoM_IO2/DP0.AUX-")
			(pintype "passive")
		)
	)
	(footprint "antmicro-footprints:R_0402_1005Metric"
		(layer "B.Cu")
		(at 103.46 66.01)
		(descr "Resistor SMD 0402")
		(tags "resistor SMD 0402")
		(property "Reference" "R4"
			(at -0.89 0.6 0)
			(layer "B.SilkS")
			(effects
				(font
					(size 0.7 0.7)
					(thickness 0.15)
				)
				(justify right top mirror)
			)
		)
		(property "Value" "R_49R9_0402"
			(at -1.011843 -1.772047 0)
			(layer "B.Fab")
			(effects
				(font
					(size 0.7 0.7)
					(thickness 0.15)
				)
				(justify right top mirror)
			)
		)
		(property "Datasheet" "https://www.bourns.com/docs/product-datasheets/cr.pdf"
			(at 0 0 0)
			(layer "B.Fab")
			(hide yes)
			(effects
				(font
					(size 1.27 1.27)
					(thickness 0.15)
				)
				(justify mirror)
			)
		)
		(property "Description" "SMD Chip Resistor, 49.9 ohm, ± 1%, 62.5 mW, 0402 [1005 Metric], Thick Film, General Purpose"
			(at 0 0 0)
			(layer "B.Fab")
			(hide yes)
			(effects
				(font
					(size 1.27 1.27)
					(thickness 0.15)
				)
				(justify mirror)
			)
		)
		(property "MPN" "CR0402-FX-49R9GLF"
			(at 0 0 180)
			(unlocked yes)
			(layer "B.Fab")
			(hide yes)
			(effects
				(font
					(size 1 1)
					(thickness 0.15)
				)
				(justify mirror)
			)
		)
		(property "Manufacturer" "Bourns"
			(at 0 0 180)
			(unlocked yes)
			(layer "B.Fab")
			(hide yes)
			(effects
				(font
					(size 1 1)
					(thickness 0.15)
				)
				(justify mirror)
			)
		)
		(property "License" "Apache-2.0"
			(at 0 0 180)
			(unlocked yes)
			(layer "B.Fab")
			(hide yes)
			(effects
				(font
					(size 1 1)
					(thickness 0.15)
				)
				(justify mirror)
			)
		)
		(property "Author" "Antmicro"
			(at 0 0 180)
			(unlocked yes)
			(layer "B.Fab")
			(hide yes)
			(effects
				(font
					(size 1 1)
					(thickness 0.15)
				)
				(justify mirror)
			)
		)
		(property "Val" "49R9"
			(at 0 0 180)
			(unlocked yes)
			(layer "B.Fab")
			(hide yes)
			(effects
				(font
					(size 1 1)
					(thickness 0.15)
				)
				(justify mirror)
			)
		)
		(property "Tolerance" "1%"
			(at 0 0 180)
			(unlocked yes)
			(layer "B.Fab")
			(hide yes)
			(effects
				(font
					(size 1 1)
					(thickness 0.15)
				)
				(justify mirror)
			)
		)
		(sheetname "/SoM_IO2/")
		(sheetfile "som_io2.kicad_sch")
		(attr smd)
		(fp_rect
			(start -0.925 0.47)
			(end 0.925 -0.47)
			(stroke
				(width 0.05)
				(type default)
			)
			(fill no)
			(layer "B.CrtYd")
		)
		(fp_rect
			(start -0.5 0.25)
			(end 0.5 -0.25)
			(stroke
				(width 0.15)
				(type solid)
			)
			(fill no)
			(layer "B.Fab")
		)
		(fp_text user "${REFERENCE}"
			(at -0.95 -3.168 0)
			(layer "B.Fab")
			(effects
				(font
					(size 0.7 0.7)
					(thickness 0.15)
				)
				(justify right top mirror)
			)
		)
		(fp_text user "License: Apache-2.0"
			(at -0.95 -5.169 0)
			(layer "B.Fab")
			(effects
				(font
					(size 0.7 0.7)
					(thickness 0.15)
				)
				(justify right top mirror)
			)
		)
		(fp_text user "Author: Antmicro"
			(at -0.95 -4.169 0)
			(layer "B.Fab")
			(effects
				(font
					(size 0.7 0.7)
					(thickness 0.15)
				)
				(justify right top mirror)
			)
		)
		(pad "1" smd roundrect
			(at -0.48 0)
			(size 0.59 0.64)
			(layers "B.Cu" "B.Mask" "B.Paste")
			(roundrect_rratio 0.25)
			(net 1 "GND")
			(pintype "passive")
		)
		(pad "2" smd roundrect
			(at 0.48 0)
			(size 0.59 0.64)
			(layers "B.Cu" "B.Mask" "B.Paste")
			(roundrect_rratio 0.25)
			(net 171 "/SoM_IO2/SFI_REFCLK-")
			(pintype "passive")
		)
	)
	(footprint "antmicro-footprints:TP_SMD_0.75mm"
		(layer "B.Cu")
		(at 165.15 58.02 180)
		(property "Reference" "TP134"
			(at -0.42 4.06 90)
			(layer "B.SilkS")
			(effects
				(font
					(size 0.7 0.7)
					(thickness 0.15)
				)
				(justify left bottom mirror)
			)
		)
		(property "Value" "TP_0.75mm_SMD"
			(at 0 -1.2 0)
			(layer "B.Fab")
			(effects
				(font
					(size 0.7 0.7)
					(thickness 0.15)
				)
				(justify left bottom mirror)
			)
		)
		(property "Description" "SMT test point"
			(at 0 0 0)
			(layer "B.Fab")
			(hide yes)
			(effects
				(font
					(size 1.27 1.27)
					(thickness 0.15)
				)
				(justify mirror)
			)
		)
		(property "MPN" ""
			(at 0 0 0)
			(unlocked yes)
			(layer "B.Fab")
			(hide yes)
			(effects
				(font
					(size 1 1)
					(thickness 0.15)
				)
				(justify mirror)
			)
		)
		(property "Manufacturer" ""
			(at 0 0 0)
			(unlocked yes)
			(layer "B.Fab")
			(hide yes)
			(effects
				(font
					(size 1 1)
					(thickness 0.15)
				)
				(justify mirror)
			)
		)
		(property "Author" "Antmicro"
			(at 0 0 0)
			(unlocked yes)
			(layer "B.Fab")
			(hide yes)
			(effects
				(font
					(size 1 1)
					(thickness 0.15)
				)
				(justify mirror)
			)
		)
		(property "License" "Apache-2.0"
			(at 0 0 0)
			(unlocked yes)
			(layer "B.Fab")
			(hide yes)
			(effects
				(font
					(size 1 1)
					(thickness 0.15)
				)
				(justify mirror)
			)
		)
		(sheetname "/Power/")
		(sheetfile "power.kicad_sch")
		(attr exclude_from_pos_files exclude_from_bom)
		(fp_circle
			(center 0 0)
			(end 0.475 0)
			(stroke
				(width 0.05)
				(type default)
			)
			(fill no)
			(layer "B.CrtYd")
		)
		(fp_text user "${REFERENCE}"
			(at -0.4 -2.7 0)
			(layer "B.Fab")
			(effects
				(font
					(size 0.7 0.7)
					(thickness 0.15)
				)
				(justify left bottom mirror)
			)
		)
		(fp_text user "License: Apache-2.0"
			(at -0.4 -5.101 0)
			(layer "B.Fab")
			(effects
				(font
					(size 0.7 0.7)
					(thickness 0.15)
				)
				(justify left bottom mirror)
			)
		)
		(fp_text user "Author: Antmicro"
			(at -0.4 -3.901 0)
			(layer "B.Fab")
			(effects
				(font
					(size 0.7 0.7)
					(thickness 0.15)
				)
				(justify left bottom mirror)
			)
		)
		(pad "1" smd circle
			(at 0 0 180)
			(size 0.75 0.75)
			(layers "B.Cu" "B.Mask")
			(net 1 "GND")
			(pinfunction "1")
			(pintype "passive")
		)
	)
	(footprint "antmicro-footprints:C_0402_1005Metric"
		(layer "B.Cu")
		(at 214.5 70.65 90)
		(descr "Capacitor SMD 0402")
		(tags "capacitor SMD 0402")
		(property "Reference" "C135"
			(at 0.95 -0.4 90)
			(layer "B.SilkS")
			(effects
				(font
					(size 0.7 0.7)
					(thickness 0.15)
				)
				(justify right top mirror)
			)
		)
		(property "Value" "C_10u_0402"
			(at -1.022927 -2.155213 90)
			(layer "B.Fab")
			(effects
				(font
					(size 0.7 0.7)
					(thickness 0.15)
				)
				(justify right top mirror)
			)
		)
		(property "Datasheet" "https://www.yageo.com/en/Chart/Download/pdf/CC0402MRX5R5BB106"
			(at 0 0 90)
			(layer "B.Fab")
			(hide yes)
			(effects
				(font
					(size 1.27 1.27)
					(thickness 0.15)
				)
				(justify mirror)
			)
		)
		(property "Description" "SMD Multilayer Ceramic Capacitor, 10 µF, 6.3 V, 0402 [1005 Metric], ± 20%, X5R, CC Series"
			(at 0 0 90)
			(layer "B.Fab")
			(hide yes)
			(effects
				(font
					(size 1.27 1.27)
					(thickness 0.15)
				)
				(justify mirror)
			)
		)
		(property "MPN" "CC0402MRX5R5BB106"
			(at 0 0 270)
			(unlocked yes)
			(layer "B.Fab")
			(hide yes)
			(effects
				(font
					(size 1 1)
					(thickness 0.15)
				)
				(justify mirror)
			)
		)
		(property "Manufacturer" "YAGEO"
			(at 0 0 270)
			(unlocked yes)
			(layer "B.Fab")
			(hide yes)
			(effects
				(font
					(size 1 1)
					(thickness 0.15)
				)
				(justify mirror)
			)
		)
		(property "License" "Apache-2.0"
			(at 0 0 270)
			(unlocked yes)
			(layer "B.Fab")
			(hide yes)
			(effects
				(font
					(size 1 1)
					(thickness 0.15)
				)
				(justify mirror)
			)
		)
		(property "Author" "Antmicro"
			(at 0 0 270)
			(unlocked yes)
			(layer "B.Fab")
			(hide yes)
			(effects
				(font
					(size 1 1)
					(thickness 0.15)
				)
				(justify mirror)
			)
		)
		(property "Val" "10u"
			(at 0 0 270)
			(unlocked yes)
			(layer "B.Fab")
			(hide yes)
			(effects
				(font
					(size 1 1)
					(thickness 0.15)
				)
				(justify mirror)
			)
		)
		(property "Voltage" ""
			(at 0 0 270)
			(unlocked yes)
			(layer "B.Fab")
			(hide yes)
			(effects
				(font
					(size 1 1)
					(thickness 0.15)
				)
				(justify mirror)
			)
		)
		(property "Dielectric" ""
			(at 0 0 270)
			(unlocked yes)
			(layer "B.Fab")
			(hide yes)
			(effects
				(font
					(size 1 1)
					(thickness 0.15)
				)
				(justify mirror)
			)
		)
		(sheetname "/USB Debug, PD/")
		(sheetfile "usb_debug_pd.kicad_sch")
		(attr smd)
		(fp_rect
			(start -0.925 0.47)
			(end 0.925 -0.47)
			(stroke
				(width 0.05)
				(type default)
			)
			(fill no)
			(layer "B.CrtYd")
		)
		(fp_line
			(start 0.504 -0.248)
			(end -0.494 -0.248)
			(stroke
				(width 0.15)
				(type solid)
			)
			(layer "B.Fab")
		)
		(fp_line
			(start -0.494 -0.248)
			(end -0.494 0.25)
			(stroke
				(width 0.15)
				(type solid)
			)
			(layer "B.Fab")
		)
		(fp_line
			(start 0.504 0.25)
			(end 0.504 -0.248)
			(stroke
				(width 0.15)
				(type solid)
			)
			(layer "B.Fab")
		)
		(fp_line
			(start -0.494 0.25)
			(end 0.504 0.25)
			(stroke
				(width 0.15)
				(type solid)
			)
			(layer "B.Fab")
		)
		(fp_text user "License: Apache-2.0"
			(at -0.939 -5.799 90)
			(layer "B.Fab")
			(effects
				(font
					(size 0.7 0.7)
					(thickness 0.15)
				)
				(justify right top mirror)
			)
		)
		(fp_text user "${REFERENCE}"
			(at -0.939 -4.599 90)
			(layer "B.Fab")
			(effects
				(font
					(size 0.7 0.7)
					(thickness 0.15)
				)
				(justify right top mirror)
			)
		)
		(fp_text user "Author: Antmicro"
			(at -0.939 -3.399 90)
			(layer "B.Fab")
			(effects
				(font
					(size 0.7 0.7)
					(thickness 0.15)
				)
				(justify right top mirror)
			)
		)
		(pad "1" smd roundrect
			(at -0.48 0 90)
			(size 0.59 0.64)
			(layers "B.Cu" "B.Mask" "B.Paste")
			(roundrect_rratio 0.25)
			(net 1 "GND")
			(pintype "passive")
		)
		(pad "2" smd roundrect
			(at 0.48 0 90)
			(size 0.59 0.64)
			(layers "B.Cu" "B.Mask" "B.Paste")
			(roundrect_rratio 0.25)
			(net 334 "/USB Debug, PD/FTDI_3V3")
			(pintype "passive")
		)
	)
	(footprint "antmicro-footprints:R_0402_1005Metric"
		(layer "B.Cu")
		(at 200.8 124.2 180)
		(descr "Resistor SMD 0402")
		(tags "resistor SMD 0402")
		(property "Reference" "R325"
			(at -3.8 -0.4 0)
			(layer "B.SilkS")
			(effects
				(font
					(size 0.7 0.7)
					(thickness 0.15)
				)
				(justify left bottom mirror)
			)
		)
		(property "Value" "R_100k_0402"
			(at -1.011843 -1.772046 0)
			(layer "B.Fab")
			(effects
				(font
					(size 0.7 0.7)
					(thickness 0.15)
				)
				(justify left bottom mirror)
			)
		)
		(property "Datasheet" "https://www.bourns.com/docs/product-datasheets/cr.pdf"
			(at 0 0 0)
			(layer "B.Fab")
			(hide yes)
			(effects
				(font
					(size 1.27 1.27)
					(thickness 0.15)
				)
				(justify mirror)
			)
		)
		(property "Description" "SMD Chip Resistor, 100 kohm, ± 1%, 62.5 mW, 0402 [1005 Metric], Thick Film, General Purpose"
			(at 0 0 0)
			(layer "B.Fab")
			(hide yes)
			(effects
				(font
					(size 1.27 1.27)
					(thickness 0.15)
				)
				(justify mirror)
			)
		)
		(property "MPN" "CR0402-FX-1003GLF"
			(at 0 0 0)
			(unlocked yes)
			(layer "B.Fab")
			(hide yes)
			(effects
				(font
					(size 1 1)
					(thickness 0.15)
				)
				(justify mirror)
			)
		)
		(property "Manufacturer" "Bourns"
			(at 0 0 0)
			(unlocked yes)
			(layer "B.Fab")
			(hide yes)
			(effects
				(font
					(size 1 1)
					(thickness 0.15)
				)
				(justify mirror)
			)
		)
		(property "License" "Apache-2.0"
			(at 0 0 0)
			(unlocked yes)
			(layer "B.Fab")
			(hide yes)
			(effects
				(font
					(size 1 1)
					(thickness 0.15)
				)
				(justify mirror)
			)
		)
		(property "Author" "Antmicro"
			(at 0 0 0)
			(unlocked yes)
			(layer "B.Fab")
			(hide yes)
			(effects
				(font
					(size 1 1)
					(thickness 0.15)
				)
				(justify mirror)
			)
		)
		(property "Val" "100k"
			(at 0 0 0)
			(unlocked yes)
			(layer "B.Fab")
			(hide yes)
			(effects
				(font
					(size 1 1)
					(thickness 0.15)
				)
				(justify mirror)
			)
		)
		(property "Tolerance" "1%"
			(at 0 0 0)
			(unlocked yes)
			(layer "B.Fab")
			(hide yes)
			(effects
				(font
					(size 1 1)
					(thickness 0.15)
				)
				(justify mirror)
			)
		)
		(sheetname "/USB Hub/")
		(sheetfile "usb_hub.kicad_sch")
		(attr smd)
		(fp_poly
			(pts
				(xy -0.925 0.47) (xy -0.925 -0.47) (xy 0.925 -0.47) (xy 0.925 0.47)
			)
			(stroke
				(width 0.05)
				(type default)
			)
			(fill no)
			(layer "B.CrtYd")
		)
		(fp_poly
			(pts
				(xy -0.5 0.25) (xy -0.5 -0.25) (xy 0.5 -0.25) (xy 0.5 0.25)
			)
			(stroke
				(width 0.15)
				(type solid)
			)
			(fill no)
			(layer "B.Fab")
		)
		(fp_text user "License: Apache-2.0"
			(at -0.949999 -5.169 0)
			(layer "B.Fab")
			(effects
				(font
					(size 0.7 0.7)
					(thickness 0.15)
				)
				(justify left bottom mirror)
			)
		)
		(fp_text user "Author: Antmicro"
			(at -0.95 -4.169 0)
			(layer "B.Fab")
			(effects
				(font
					(size 0.7 0.7)
					(thickness 0.15)
				)
				(justify left bottom mirror)
			)
		)
		(fp_text user "${REFERENCE}"
			(at -0.95 -3.168 0)
			(layer "B.Fab")
			(effects
				(font
					(size 0.7 0.7)
					(thickness 0.15)
				)
				(justify left bottom mirror)
			)
		)
		(pad "1" smd roundrect
			(at -0.48 0 180)
			(size 0.59 0.64)
			(layers "B.Cu" "B.Mask" "B.Paste")
			(roundrect_rratio 0.25)
			(net 1 "GND")
			(pintype "passive")
		)
		(pad "2" smd roundrect
			(at 0.48 0 180)
			(size 0.59 0.64)
			(layers "B.Cu" "B.Mask" "B.Paste")
			(roundrect_rratio 0.25)
			(net 927 "/USB Hub/HUB_SPI_CLK")
			(pintype "passive")
		)
	)
	(footprint "antmicro-footprints:Oscillator_SMD_ECS_2520MV_2.5x2mm"
		(layer "B.Cu")
		(at 128.8 132 90)
		(descr "Miniature Crystal Clock Oscillator ECS 2520MV series")
		(tags "Crystal Clock Oscillator ECS 2520MV SMD")
		(property "Reference" "Y3"
			(at 2.2 0.2 0)
			(layer "B.SilkS")
			(effects
				(font
					(size 0.7 0.7)
					(thickness 0.15)
				)
				(justify right top mirror)
			)
		)
		(property "Value" "Oscillator_32.768kHz_ECS_2520MV"
			(at 0 -2.499 90)
			(layer "B.Fab")
			(effects
				(font
					(size 0.7 0.7)
					(thickness 0.15)
				)
				(justify right top mirror)
			)
		)
		(property "Datasheet" "https://ecsxtal.com/store/pdf/ECS-327MVATX.pdf"
			(at 0 0 90)
			(layer "B.Fab")
			(hide yes)
			(effects
				(font
					(size 1.27 1.27)
					(thickness 0.15)
				)
				(justify mirror)
			)
		)
		(property "Description" "32.768 kHz XO (Standard) CMOS Oscillator 1.6V ~ 3.6V Enable/Disable 4-SMD, No Lead"
			(at 0 0 90)
			(layer "B.Fab")
			(hide yes)
			(effects
				(font
					(size 1.27 1.27)
					(thickness 0.15)
				)
				(justify mirror)
			)
		)
		(property "Manufacturer" "ECS Inc. International"
			(at 0 0 270)
			(unlocked yes)
			(layer "B.Fab")
			(hide yes)
			(effects
				(font
					(size 1 1)
					(thickness 0.15)
				)
				(justify mirror)
			)
		)
		(property "MPN" "ECS-327MVATX-2-CN-TR3"
			(at 0 0 270)
			(unlocked yes)
			(layer "B.Fab")
			(hide yes)
			(effects
				(font
					(size 1 1)
					(thickness 0.15)
				)
				(justify mirror)
			)
		)
		(property "Val" "32.768 kHz"
			(at 0 0 270)
			(unlocked yes)
			(layer "B.Fab")
			(hide yes)
			(effects
				(font
					(size 1 1)
					(thickness 0.15)
				)
				(justify mirror)
			)
		)
		(property "Author" "Antmicro"
			(at 0 0 270)
			(unlocked yes)
			(layer "B.Fab")
			(hide yes)
			(effects
				(font
					(size 1 1)
					(thickness 0.15)
				)
				(justify mirror)
			)
		)
		(property "License" "Apache-2.0"
			(at 0 0 270)
			(unlocked yes)
			(layer "B.Fab")
			(hide yes)
			(effects
				(font
					(size 1 1)
					(thickness 0.15)
				)
				(justify mirror)
			)
		)
		(sheetname "/M.2/")
		(sheetfile "m2.kicad_sch")
		(attr smd)
		(fp_line
			(start -0.172 -1.36)
			(end 0.17 -1.36)
			(stroke
				(width 0.15)
				(type solid)
			)
			(layer "B.SilkS")
		)
		(fp_line
			(start 1.11 -0.32)
			(end 1.11 0.32)
			(stroke
				(width 0.15)
				(type solid)
			)
			(layer "B.SilkS")
		)
		(fp_line
			(start -1.111 -0.32)
			(end -1.111 0.32)
			(stroke
				(width 0.15)
				(type solid)
			)
			(layer "B.SilkS")
		)
		(fp_line
			(start -0.16 1.361)
			(end 0.17 1.361)
			(stroke
				(width 0.15)
				(type solid)
			)
			(layer "B.SilkS")
		)
		(fp_circle
			(center -1.1 1.5)
			(end -1.049 1.5)
			(stroke
				(width 0.15)
				(type solid)
			)
			(fill yes)
			(layer "B.SilkS")
		)
		(fp_rect
			(start -1.25 1.5)
			(end 1.25 -1.5)
			(stroke
				(width 0.05)
				(type solid)
			)
			(fill no)
			(layer "B.CrtYd")
		)
		(fp_line
			(start -1 0.75)
			(end -0.5 1.25)
			(stroke
				(width 0.15)
				(type solid)
			)
			(layer "B.Fab")
		)
		(fp_rect
			(start 1 -1.249)
			(end -1 1.25)
			(stroke
				(width 0.15)
				(type solid)
			)
			(fill no)
			(layer "B.Fab")
		)
		(fp_text user "Author: Antmicro"
			(at -1.25 -5.102 90)
			(layer "B.Fab")
			(effects
				(font
					(size 0.7 0.7)
					(thickness 0.15)
				)
				(justify right top mirror)
			)
		)
		(fp_text user "${REFERENCE}"
			(at -1.25 -3.9 90)
			(layer "B.Fab")
			(effects
				(font
					(size 0.7 0.7)
					(thickness 0.15)
				)
				(justify right top mirror)
			)
		)
		(fp_text user "License: Apache-2.0"
			(at -1.25 -6.302 90)
			(layer "B.Fab")
			(effects
				(font
					(size 0.7 0.7)
					(thickness 0.15)
				)
				(justify right top mirror)
			)
		)
		(pad "1" smd roundrect
			(at -0.725 0.927 90)
			(size 0.8 0.9)
			(layers "B.Cu" "B.Mask" "B.Paste")
			(roundrect_rratio 0.25)
			(net 2 "+3V3")
			(pinfunction "EN")
			(pintype "input")
		)
		(pad "2" smd roundrect
			(at -0.725 -0.925 90)
			(size 0.8 0.9)
			(layers "B.Cu" "B.Mask" "B.Paste")
			(roundrect_rratio 0.25)
			(net 1 "GND")
			(pinfunction "GND")
			(pintype "power_in")
		)
		(pad "3" smd roundrect
			(at 0.723 -0.925 90)
			(size 0.8 0.9)
			(layers "B.Cu" "B.Mask" "B.Paste")
			(roundrect_rratio 0.25)
			(net 1005 "/M.2/SUSCLK")
			(pinfunction "OUT")
			(pintype "output")
		)
		(pad "4" smd roundrect
			(at 0.723 0.927 90)
			(size 0.8 0.9)
			(layers "B.Cu" "B.Mask" "B.Paste")
			(roundrect_rratio 0.25)
			(net 2 "+3V3")
			(pinfunction "VDD")
			(pintype "power_in")
		)
	)
	(footprint "antmicro-footprints:TP_SMD_0.75mm"
		(layer "B.Cu")
		(at 126.8 69.4 90)
		(property "Reference" "TP31"
			(at 0.5 -0.3 90)
			(layer "B.SilkS")
			(effects
				(font
					(size 0.7 0.7)
					(thickness 0.15)
				)
				(justify right top mirror)
			)
		)
		(property "Value" "TP_0.75mm_SMD"
			(at 0 -1.2 90)
			(layer "B.Fab")
			(effects
				(font
					(size 0.7 0.7)
					(thickness 0.15)
				)
				(justify right top mirror)
			)
		)
		(property "Description" "SMT test point"
			(at 0 0 90)
			(layer "B.Fab")
			(hide yes)
			(effects
				(font
					(size 1.27 1.27)
					(thickness 0.15)
				)
				(justify mirror)
			)
		)
		(property "MPN" ""
			(at 0 0 270)
			(unlocked yes)
			(layer "B.Fab")
			(hide yes)
			(effects
				(font
					(size 1 1)
					(thickness 0.15)
				)
				(justify mirror)
			)
		)
		(property "Manufacturer" ""
			(at 0 0 270)
			(unlocked yes)
			(layer "B.Fab")
			(hide yes)
			(effects
				(font
					(size 1 1)
					(thickness 0.15)
				)
				(justify mirror)
			)
		)
		(property "Author" "Antmicro"
			(at 0 0 270)
			(unlocked yes)
			(layer "B.Fab")
			(hide yes)
			(effects
				(font
					(size 1 1)
					(thickness 0.15)
				)
				(justify mirror)
			)
		)
		(property "License" "Apache-2.0"
			(at 0 0 270)
			(unlocked yes)
			(layer "B.Fab")
			(hide yes)
			(effects
				(font
					(size 1 1)
					(thickness 0.15)
				)
				(justify mirror)
			)
		)
		(sheetname "/SoM_Power/")
		(sheetfile "som_power.kicad_sch")
		(attr exclude_from_pos_files exclude_from_bom)
		(fp_circle
			(center 0 0)
			(end 0.475 0)
			(stroke
				(width 0.05)
				(type default)
			)
			(fill no)
			(layer "B.CrtYd")
		)
		(fp_text user "License: Apache-2.0"
			(at -0.4 -5.101 90)
			(layer "B.Fab")
			(effects
				(font
					(size 0.7 0.7)
					(thickness 0.15)
				)
				(justify right top mirror)
			)
		)
		(fp_text user "${REFERENCE}"
			(at -0.4 -2.7 90)
			(layer "B.Fab")
			(effects
				(font
					(size 0.7 0.7)
					(thickness 0.15)
				)
				(justify right top mirror)
			)
		)
		(fp_text user "Author: Antmicro"
			(at -0.4 -3.901 90)
			(layer "B.Fab")
			(effects
				(font
					(size 0.7 0.7)
					(thickness 0.15)
				)
				(justify right top mirror)
			)
		)
		(pad "1" smd circle
			(at 0 0 90)
			(size 0.75 0.75)
			(layers "B.Cu" "B.Mask")
			(net 700 "Net-(J1A-MV_LSW_MON)")
			(pinfunction "1")
			(pintype "passive")
		)
	)
	(footprint "antmicro-footprints:R_0402_1005Metric"
		(layer "B.Cu")
		(at 203.4 104.8)
		(descr "Resistor SMD 0402")
		(tags "resistor SMD 0402")
		(property "Reference" "R282"
			(at 2.9 -0.35 0)
			(layer "B.SilkS")
			(effects
				(font
					(size 0.7 0.7)
					(thickness 0.15)
				)
				(justify right top mirror)
			)
		)
		(property "Value" "R_0R_0402"
			(at -1.011843 -1.772046 0)
			(layer "B.Fab")
			(effects
				(font
					(size 0.7 0.7)
					(thickness 0.15)
				)
				(justify right top mirror)
			)
		)
		(property "Datasheet" "https://industrial.panasonic.com/cdbs/www-data/pdf/RDA0000/AOA0000C301.pdf"
			(at 0 0 0)
			(layer "B.Fab")
			(hide yes)
			(effects
				(font
					(size 1.27 1.27)
					(thickness 0.15)
				)
				(justify mirror)
			)
		)
		(property "Description" "SMD Chip Resistor, Jumper, 0 ohm, 100 mW, 0402 [1005 Metric], Thick Film, General Purpose"
			(at 0 0 0)
			(layer "B.Fab")
			(hide yes)
			(effects
				(font
					(size 1.27 1.27)
					(thickness 0.15)
				)
				(justify mirror)
			)
		)
		(property "Manufacturer" "Panasonic"
			(at 0 0 180)
			(unlocked yes)
			(layer "B.Fab")
			(hide yes)
			(effects
				(font
					(size 1 1)
					(thickness 0.15)
				)
				(justify mirror)
			)
		)
		(property "MPN" "ERJ2GE0R00X"
			(at 0 0 180)
			(unlocked yes)
			(layer "B.Fab")
			(hide yes)
			(effects
				(font
					(size 1 1)
					(thickness 0.15)
				)
				(justify mirror)
			)
		)
		(property "Val" "0R"
			(at 0 0 180)
			(unlocked yes)
			(layer "B.Fab")
			(hide yes)
			(effects
				(font
					(size 1 1)
					(thickness 0.15)
				)
				(justify mirror)
			)
		)
		(property "License" "Apache-2.0"
			(at 0 0 180)
			(unlocked yes)
			(layer "B.Fab")
			(hide yes)
			(effects
				(font
					(size 1 1)
					(thickness 0.15)
				)
				(justify mirror)
			)
		)
		(property "Author" "Antmicro"
			(at 0 0 180)
			(unlocked yes)
			(layer "B.Fab")
			(hide yes)
			(effects
				(font
					(size 1 1)
					(thickness 0.15)
				)
				(justify mirror)
			)
		)
		(property "Tolerance" "~"
			(at 0 0 180)
			(unlocked yes)
			(layer "B.Fab")
			(hide yes)
			(effects
				(font
					(size 1 1)
					(thickness 0.15)
				)
				(justify mirror)
			)
		)
		(property "Current" "1A"
			(at 0 0 180)
			(unlocked yes)
			(layer "B.Fab")
			(hide yes)
			(effects
				(font
					(size 1 1)
					(thickness 0.15)
				)
				(justify mirror)
			)
		)
		(sheetname "/Recovery USB/")
		(sheetfile "recovery_usb.kicad_sch")
		(attr smd exclude_from_pos_files exclude_from_bom dnp)
		(fp_poly
			(pts
				(xy -0.925 0.47) (xy -0.925 -0.47) (xy 0.925 -0.47) (xy 0.925 0.47)
			)
			(stroke
				(width 0.05)
				(type default)
			)
			(fill no)
			(layer "B.CrtYd")
		)
		(fp_poly
			(pts
				(xy -0.5 0.25) (xy -0.5 -0.25) (xy 0.5 -0.25) (xy 0.5 0.25)
			)
			(stroke
				(width 0.15)
				(type solid)
			)
			(fill no)
			(layer "B.Fab")
		)
		(fp_text user "Author: Antmicro"
			(at -0.95 -4.169 0)
			(layer "B.Fab")
			(effects
				(font
					(size 0.7 0.7)
					(thickness 0.15)
				)
				(justify right top mirror)
			)
		)
		(fp_text user "${REFERENCE}"
			(at -0.95 -3.168 0)
			(layer "B.Fab")
			(effects
				(font
					(size 0.7 0.7)
					(thickness 0.15)
				)
				(justify right top mirror)
			)
		)
		(fp_text user "License: Apache-2.0"
			(at -0.949999 -5.169 0)
			(layer "B.Fab")
			(effects
				(font
					(size 0.7 0.7)
					(thickness 0.15)
				)
				(justify right top mirror)
			)
		)
		(pad "1" smd roundrect
			(at -0.48 0)
			(size 0.59 0.64)
			(layers "B.Cu" "B.Mask" "B.Paste")
			(roundrect_rratio 0.25)
			(net 853 "/I2C_{SYS}.SCL")
			(pintype "passive")
		)
		(pad "2" smd roundrect
			(at 0.48 0)
			(size 0.59 0.64)
			(layers "B.Cu" "B.Mask" "B.Paste")
			(roundrect_rratio 0.25)
			(net 1025 "/Recovery USB/USBC2_I2C_SCL")
			(pintype "passive")
		)
	)
	(footprint "antmicro-footprints:R_0402_1005Metric"
		(layer "B.Cu")
		(at 235.2 63.8)
		(descr "Resistor SMD 0402")
		(tags "resistor SMD 0402")
		(property "Reference" "R407"
			(at 1.3 -0.5 0)
			(layer "B.SilkS")
			(effects
				(font
					(size 0.7 0.7)
					(thickness 0.15)
				)
				(justify right top mirror)
			)
		)
		(property "Value" "R_470R_0402"
			(at -1.011843 -1.772046 0)
			(layer "B.Fab")
			(effects
				(font
					(size 0.7 0.7)
					(thickness 0.15)
				)
				(justify right top mirror)
			)
		)
		(property "Datasheet" "https://www.bourns.com/docs/product-datasheets/cr.pdf"
			(at 0 0 0)
			(layer "B.Fab")
			(hide yes)
			(effects
				(font
					(size 1.27 1.27)
					(thickness 0.15)
				)
				(justify mirror)
			)
		)
		(property "Description" "SMD Chip Resistor, 470 ohm, ± 1%, 62.5 mW, 0402 [1005 Metric], Thick Film, General Purpose"
			(at 0 0 0)
			(layer "B.Fab")
			(hide yes)
			(effects
				(font
					(size 1.27 1.27)
					(thickness 0.15)
				)
				(justify mirror)
			)
		)
		(property "Manufacturer" "Bourns"
			(at 0 0 180)
			(unlocked yes)
			(layer "B.Fab")
			(hide yes)
			(effects
				(font
					(size 1 1)
					(thickness 0.15)
				)
				(justify mirror)
			)
		)
		(property "MPN" "CR0402-FX-4700GLF"
			(at 0 0 180)
			(unlocked yes)
			(layer "B.Fab")
			(hide yes)
			(effects
				(font
					(size 1 1)
					(thickness 0.15)
				)
				(justify mirror)
			)
		)
		(property "Val" "470R"
			(at 0 0 180)
			(unlocked yes)
			(layer "B.Fab")
			(hide yes)
			(effects
				(font
					(size 1 1)
					(thickness 0.15)
				)
				(justify mirror)
			)
		)
		(property "License" "Apache-2.0"
			(at 0 0 180)
			(unlocked yes)
			(layer "B.Fab")
			(hide yes)
			(effects
				(font
					(size 1 1)
					(thickness 0.15)
				)
				(justify mirror)
			)
		)
		(property "Author" "Antmicro"
			(at 0 0 180)
			(unlocked yes)
			(layer "B.Fab")
			(hide yes)
			(effects
				(font
					(size 1 1)
					(thickness 0.15)
				)
				(justify mirror)
			)
		)
		(property "Tolerance" "1%"
			(at 0 0 180)
			(unlocked yes)
			(layer "B.Fab")
			(hide yes)
			(effects
				(font
					(size 1 1)
					(thickness 0.15)
				)
				(justify mirror)
			)
		)
		(sheetname "/SoM_Power/")
		(sheetfile "som_power.kicad_sch")
		(attr smd)
		(fp_poly
			(pts
				(xy -0.925 0.47) (xy 0.925 0.47) (xy 0.925 -0.47) (xy -0.925 -0.47)
			)
			(stroke
				(width 0.05)
				(type default)
			)
			(fill no)
			(layer "B.CrtYd")
		)
		(fp_poly
			(pts
				(xy -0.5 0.25) (xy 0.5 0.25) (xy 0.5 -0.25) (xy -0.5 -0.25)
			)
			(stroke
				(width 0.15)
				(type solid)
			)
			(fill no)
			(layer "B.Fab")
		)
		(fp_text user "Author: Antmicro"
			(at -0.95 -4.169 0)
			(layer "B.Fab")
			(effects
				(font
					(size 0.7 0.7)
					(thickness 0.15)
				)
				(justify right top mirror)
			)
		)
		(fp_text user "License: Apache-2.0"
			(at -0.949999 -5.169 0)
			(layer "B.Fab")
			(effects
				(font
					(size 0.7 0.7)
					(thickness 0.15)
				)
				(justify right top mirror)
			)
		)
		(fp_text user "${REFERENCE}"
			(at -0.95 -3.168 0)
			(layer "B.Fab")
			(effects
				(font
					(size 0.7 0.7)
					(thickness 0.15)
				)
				(justify right top mirror)
			)
		)
		(pad "1" smd roundrect
			(at -0.48 0)
			(size 0.59 0.64)
			(layers "B.Cu" "B.Mask" "B.Paste")
			(roundrect_rratio 0.25)
			(net 1394 "Net-(D65-A)")
			(pintype "passive")
		)
		(pad "2" smd roundrect
			(at 0.48 0)
			(size 0.59 0.64)
			(layers "B.Cu" "B.Mask" "B.Paste")
			(roundrect_rratio 0.25)
			(net 5 "+5V")
			(pintype "passive")
		)
	)
	(footprint "antmicro-footprints:LED_0603_1608Metric_G"
		(layer "B.Cu")
		(at 113.47 116.59)
		(descr "LED SMD 0603 Green")
		(tags "LED SMD 0603 Green")
		(property "Reference" "D32"
			(at 3.33 -0.39 0)
			(layer "B.SilkS")
			(effects
				(font
					(size 0.7 0.7)
					(thickness 0.15)
				)
				(justify right top mirror)
			)
		)
		(property "Value" "LED_G_0603_LTST-C190GKT"
			(at -0.001 -1.599 0)
			(layer "B.Fab")
			(effects
				(font
					(size 0.7 0.7)
					(thickness 0.15)
				)
				(justify right top mirror)
			)
		)
		(property "Datasheet" "https://media.digikey.com/pdf/Data%20Sheets/Lite-On%20PDFs/LTST-C190GKT.pdf"
			(at 0 0 0)
			(layer "B.Fab")
			(hide yes)
			(effects
				(font
					(size 1.27 1.27)
					(thickness 0.15)
				)
				(justify mirror)
			)
		)
		(property "Description" "LED, Green, SMD, 0603, 20 mA, 2.1 V, 569 nm"
			(at 0 0 0)
			(layer "B.Fab")
			(hide yes)
			(effects
				(font
					(size 1.27 1.27)
					(thickness 0.15)
				)
				(justify mirror)
			)
		)
		(property "MPN" "LTST-C190GKT"
			(at 0 0 180)
			(unlocked yes)
			(layer "B.Fab")
			(hide yes)
			(effects
				(font
					(size 1 1)
					(thickness 0.15)
				)
				(justify mirror)
			)
		)
		(property "Manufacturer" "Lite-On"
			(at 0 0 180)
			(unlocked yes)
			(layer "B.Fab")
			(hide yes)
			(effects
				(font
					(size 1 1)
					(thickness 0.15)
				)
				(justify mirror)
			)
		)
		(property "Author" "Antmicro"
			(at 0 0 180)
			(unlocked yes)
			(layer "B.Fab")
			(hide yes)
			(effects
				(font
					(size 1 1)
					(thickness 0.15)
				)
				(justify mirror)
			)
		)
		(property "License" "Apache-2.0"
			(at 0 0 180)
			(unlocked yes)
			(layer "B.Fab")
			(hide yes)
			(effects
				(font
					(size 1 1)
					(thickness 0.15)
				)
				(justify mirror)
			)
		)
		(property "Color" "Green"
			(at 0 0 180)
			(unlocked yes)
			(layer "B.Fab")
			(hide yes)
			(effects
				(font
					(size 1 1)
					(thickness 0.15)
				)
				(justify mirror)
			)
		)
		(sheetname "/M.2/")
		(sheetfile "m2.kicad_sch")
		(attr smd)
		(fp_line
			(start -1.18 0.319)
			(end -1.18 -0.321)
			(stroke
				(width 0.15)
				(type solid)
			)
			(layer "B.SilkS")
		)
		(fp_line
			(start -0.094672 -0.201008)
			(end -0.094672 0.198992)
			(stroke
				(width 0.1)
				(type solid)
			)
			(layer "B.SilkS")
		)
		(fp_line
			(start -0.094672 -0.001008)
			(end -0.24 -0.001008)
			(stroke
				(width 0.1)
				(type solid)
			)
			(layer "B.SilkS")
		)
		(fp_line
			(start -0.094672 -0.001008)
			(end 0.105328 0.198992)
			(stroke
				(width 0.1)
				(type solid)
			)
			(layer "B.SilkS")
		)
		(fp_line
			(start 0.105328 -0.201008)
			(end -0.094672 -0.001008)
			(stroke
				(width 0.1)
				(type solid)
			)
			(layer "B.SilkS")
		)
		(fp_line
			(start 0.105328 -0.201008)
			(end 0.105328 0.198992)
			(stroke
				(width 0.1)
				(type solid)
			)
			(layer "B.SilkS")
		)
		(fp_line
			(start 0.105328 -0.001008)
			(end 0.24 -0.001)
			(stroke
				(width 0.1)
				(type solid)
			)
			(layer "B.SilkS")
		)
		(fp_line
			(start 0.22 -0.35)
			(end -0.22 -0.35)
			(stroke
				(width 0.15)
				(type solid)
			)
			(layer "B.SilkS")
		)
		(fp_line
			(start 0.22 0.35)
			(end -0.22 0.35)
			(stroke
				(width 0.15)
				(type solid)
			)
			(layer "B.SilkS")
		)
		(fp_rect
			(start 1.25 -0.65)
			(end -1.25 0.65)
			(stroke
				(width 0.05)
				(type solid)
			)
			(fill no)
			(layer "B.CrtYd")
		)
		(fp_line
			(start -0.199 -0.2)
			(end -0.199 -0.1)
			(stroke
				(width 0.15)
				(type solid)
			)
			(layer "B.Fab")
		)
		(fp_line
			(start -0.199 0)
			(end -0.597 0)
			(stroke
				(width 0.15)
				(type solid)
			)
			(layer "B.Fab")
		)
		(fp_line
			(start -0.199 0.202)
			(end -0.199 -0.1)
			(stroke
				(width 0.15)
				(type solid)
			)
			(layer "B.Fab")
		)
		(fp_line
			(start -0.101 0)
			(end 0.201 -0.2)
			(stroke
				(width 0.15)
				(type solid)
			)
			(layer "B.Fab")
		)
		(fp_line
			(start 0.201 -0.2)
			(end 0.201 0)
			(stroke
				(width 0.15)
				(type solid)
			)
			(layer "B.Fab")
		)
		(fp_line
			(start 0.201 0)
			(end 0.201 0.202)
			(stroke
				(width 0.15)
				(type solid)
			)
			(layer "B.Fab")
		)
		(fp_line
			(start 0.201 0.202)
			(end -0.101 0)
			(stroke
				(width 0.15)
				(type solid)
			)
			(layer "B.Fab")
		)
		(fp_line
			(start 0.599 0)
			(end 0.201 0)
			(stroke
				(width 0.15)
				(type solid)
			)
			(layer "B.Fab")
		)
		(fp_rect
			(start 0.848 -0.4)
			(end -0.85 0.402)
			(stroke
				(width 0.15)
				(type solid)
			)
			(fill no)
			(layer "B.Fab")
		)
		(fp_text user "License: Apache-2.0"
			(at -1.4224 -3.599 0)
			(layer "B.Fab")
			(effects
				(font
					(size 0.7 0.7)
					(thickness 0.15)
				)
				(justify right top mirror)
			)
		)
		(fp_text user "${REFERENCE}"
			(at -1.4224 -5.999 0)
			(layer "B.Fab")
			(effects
				(font
					(size 0.7 0.7)
					(thickness 0.15)
				)
				(justify right top mirror)
			)
		)
		(fp_text user "Author: Antmicro"
			(at -1.4224 -4.799 0)
			(layer "B.Fab")
			(effects
				(font
					(size 0.7 0.7)
					(thickness 0.15)
				)
				(justify right top mirror)
			)
		)
		(pad "1" smd roundrect
			(at -0.7 0 180)
			(size 0.8 1)
			(layers "B.Cu" "B.Mask" "B.Paste")
			(roundrect_rratio 0.2)
			(net 33 "Net-(D32-C)")
			(pinfunction "C")
			(pintype "passive")
		)
		(pad "2" smd roundrect
			(at 0.7 0 180)
			(size 0.8 1)
			(layers "B.Cu" "B.Mask" "B.Paste")
			(roundrect_rratio 0.2)
			(net 544 "Net-(D32-A)")
			(pinfunction "A")
			(pintype "passive")
		)
	)
	(footprint "antmicro-footprints:R_0402_1005Metric"
		(layer "B.Cu")
		(at 238.1 81.45 180)
		(descr "Resistor SMD 0402")
		(tags "resistor SMD 0402")
		(property "Reference" "R151"
			(at -1.535 2.745 0)
			(layer "B.SilkS")
			(effects
				(font
					(size 0.7 0.7)
					(thickness 0.15)
				)
				(justify left bottom mirror)
			)
		)
		(property "Value" "R_0R_0402"
			(at -1.011843 -1.772046 0)
			(layer "B.Fab")
			(effects
				(font
					(size 0.7 0.7)
					(thickness 0.15)
				)
				(justify left bottom mirror)
			)
		)
		(property "Datasheet" "https://industrial.panasonic.com/cdbs/www-data/pdf/RDA0000/AOA0000C301.pdf"
			(at 0 0 0)
			(layer "B.Fab")
			(hide yes)
			(effects
				(font
					(size 1.27 1.27)
					(thickness 0.15)
				)
				(justify mirror)
			)
		)
		(property "Description" "SMD Chip Resistor, Jumper, 0 ohm, 100 mW, 0402 [1005 Metric], Thick Film, General Purpose"
			(at 0 0 0)
			(layer "B.Fab")
			(hide yes)
			(effects
				(font
					(size 1.27 1.27)
					(thickness 0.15)
				)
				(justify mirror)
			)
		)
		(property "Manufacturer" "Panasonic"
			(at 0 0 0)
			(unlocked yes)
			(layer "B.Fab")
			(hide yes)
			(effects
				(font
					(size 1 1)
					(thickness 0.15)
				)
				(justify mirror)
			)
		)
		(property "MPN" "ERJ2GE0R00X"
			(at 0 0 0)
			(unlocked yes)
			(layer "B.Fab")
			(hide yes)
			(effects
				(font
					(size 1 1)
					(thickness 0.15)
				)
				(justify mirror)
			)
		)
		(property "Val" "0R"
			(at 0 0 0)
			(unlocked yes)
			(layer "B.Fab")
			(hide yes)
			(effects
				(font
					(size 1 1)
					(thickness 0.15)
				)
				(justify mirror)
			)
		)
		(property "License" "Apache-2.0"
			(at 0 0 0)
			(unlocked yes)
			(layer "B.Fab")
			(hide yes)
			(effects
				(font
					(size 1 1)
					(thickness 0.15)
				)
				(justify mirror)
			)
		)
		(property "Author" "Antmicro"
			(at 0 0 0)
			(unlocked yes)
			(layer "B.Fab")
			(hide yes)
			(effects
				(font
					(size 1 1)
					(thickness 0.15)
				)
				(justify mirror)
			)
		)
		(property "Tolerance" "~"
			(at 0 0 0)
			(unlocked yes)
			(layer "B.Fab")
			(hide yes)
			(effects
				(font
					(size 1 1)
					(thickness 0.15)
				)
				(justify mirror)
			)
		)
		(property "Current" "1A"
			(at 0 0 0)
			(unlocked yes)
			(layer "B.Fab")
			(hide yes)
			(effects
				(font
					(size 1 1)
					(thickness 0.15)
				)
				(justify mirror)
			)
		)
		(sheetname "/USB Debug, PD/")
		(sheetfile "usb_debug_pd.kicad_sch")
		(attr smd)
		(fp_poly
			(pts
				(xy -0.925 0.47) (xy -0.925 -0.47) (xy 0.925 -0.47) (xy 0.925 0.47)
			)
			(stroke
				(width 0.05)
				(type default)
			)
			(fill no)
			(layer "B.CrtYd")
		)
		(fp_poly
			(pts
				(xy -0.5 0.25) (xy -0.5 -0.25) (xy 0.5 -0.25) (xy 0.5 0.25)
			)
			(stroke
				(width 0.15)
				(type solid)
			)
			(fill no)
			(layer "B.Fab")
		)
		(fp_text user "Author: Antmicro"
			(at -0.95 -4.169 0)
			(layer "B.Fab")
			(effects
				(font
					(size 0.7 0.7)
					(thickness 0.15)
				)
				(justify left bottom mirror)
			)
		)
		(fp_text user "${REFERENCE}"
			(at -0.95 -3.168 0)
			(layer "B.Fab")
			(effects
				(font
					(size 0.7 0.7)
					(thickness 0.15)
				)
				(justify left bottom mirror)
			)
		)
		(fp_text user "License: Apache-2.0"
			(at -0.949999 -5.169 0)
			(layer "B.Fab")
			(effects
				(font
					(size 0.7 0.7)
					(thickness 0.15)
				)
				(justify left bottom mirror)
			)
		)
		(pad "1" smd roundrect
			(at -0.48 0 180)
			(size 0.59 0.64)
			(layers "B.Cu" "B.Mask" "B.Paste")
			(roundrect_rratio 0.25)
			(net 975 "/USB Debug, PD/USBC0_5V_PEN")
			(pintype "passive")
		)
		(pad "2" smd roundrect
			(at 0.48 0 180)
			(size 0.59 0.64)
			(layers "B.Cu" "B.Mask" "B.Paste")
			(roundrect_rratio 0.25)
			(net 977 "Net-(U40-EN)")
			(pintype "passive")
		)
	)
	(footprint "antmicro-footprints:SOT-523"
		(layer "B.Cu")
		(at 213.798 78.007 -90)
		(property "Reference" "Q3"
			(at -0.807 -2.102 90)
			(layer "B.SilkS")
			(effects
				(font
					(size 0.7 0.7)
					(thickness 0.15)
				)
				(justify left bottom mirror)
			)
		)
		(property "Value" "DMG1012T-7"
			(at 0.1 -1.824 90)
			(layer "B.Fab")
			(effects
				(font
					(size 0.7 0.7)
					(thickness 0.15)
				)
				(justify left bottom mirror)
			)
		)
		(property "Datasheet" "https://www.diodes.com/assets/Datasheets/ds31783.pdf"
			(at 0 0 90)
			(layer "B.Fab")
			(hide yes)
			(effects
				(font
					(size 1.27 1.27)
					(thickness 0.15)
				)
				(justify mirror)
			)
		)
		(property "Description" "Power MOSFET, N Channel, 20 V, 630 mA, 0.3 ohm, SOT-523, Surface Mount"
			(at 0 0 90)
			(layer "B.Fab")
			(hide yes)
			(effects
				(font
					(size 1.27 1.27)
					(thickness 0.15)
				)
				(justify mirror)
			)
		)
		(property "MPN" "DMG1012T-7"
			(at 0 0 90)
			(unlocked yes)
			(layer "B.Fab")
			(hide yes)
			(effects
				(font
					(size 1 1)
					(thickness 0.15)
				)
				(justify mirror)
			)
		)
		(property "Manufacturer" "Diodes Incorporated"
			(at 0 0 90)
			(unlocked yes)
			(layer "B.Fab")
			(hide yes)
			(effects
				(font
					(size 1 1)
					(thickness 0.15)
				)
				(justify mirror)
			)
		)
		(property "Author" "Antmicro"
			(at 0 0 90)
			(unlocked yes)
			(layer "B.Fab")
			(hide yes)
			(effects
				(font
					(size 1 1)
					(thickness 0.15)
				)
				(justify mirror)
			)
		)
		(property "License" "Apache-2.0"
			(at 0 0 90)
			(unlocked yes)
			(layer "B.Fab")
			(hide yes)
			(effects
				(font
					(size 1 1)
					(thickness 0.15)
				)
				(justify mirror)
			)
		)
		(sheetname "/USB Debug, PD/")
		(sheetfile "usb_debug_pd.kicad_sch")
		(attr smd)
		(fp_line
			(start -0.725 0.551)
			(end -0.277 0.551)
			(stroke
				(width 0.15)
				(type solid)
			)
			(layer "B.SilkS")
		)
		(fp_line
			(start -0.277 0.551)
			(end -0.277 0.75)
			(stroke
				(width 0.15)
				(type solid)
			)
			(layer "B.SilkS")
		)
		(fp_line
			(start -0.927 0.351)
			(end -0.725 0.551)
			(stroke
				(width 0.15)
				(type solid)
			)
			(layer "B.SilkS")
		)
		(fp_line
			(start -0.927 0.051)
			(end -0.927 0.351)
			(stroke
				(width 0.15)
				(type solid)
			)
			(layer "B.SilkS")
		)
		(fp_circle
			(center -0.9652 -0.9652)
			(end -0.9152 -0.9652)
			(stroke
				(width 0.15)
				(type solid)
			)
			(fill yes)
			(layer "B.SilkS")
		)
		(fp_line
			(start -1.12 1.16)
			(end 1.1 1.16)
			(stroke
				(width 0.05)
				(type solid)
			)
			(layer "B.CrtYd")
		)
		(fp_line
			(start -1.12 1.16)
			(end -1.12 -1.15)
			(stroke
				(width 0.05)
				(type solid)
			)
			(layer "B.CrtYd")
		)
		(fp_line
			(start 1.1 1.16)
			(end 1.1 -1.15)
			(stroke
				(width 0.05)
				(type solid)
			)
			(layer "B.CrtYd")
		)
		(fp_line
			(start -1.12 -1.15)
			(end 1.1 -1.15)
			(stroke
				(width 0.05)
				(type solid)
			)
			(layer "B.CrtYd")
		)
		(fp_line
			(start -0.652 0.425)
			(end -0.802 0.276)
			(stroke
				(width 0.15)
				(type solid)
			)
			(layer "B.Fab")
		)
		(fp_line
			(start 0.8 0.425)
			(end -0.652 0.425)
			(stroke
				(width 0.15)
				(type solid)
			)
			(layer "B.Fab")
		)
		(fp_line
			(start 0.8 0.425)
			(end 0.8 -0.424)
			(stroke
				(width 0.15)
				(type solid)
			)
			(layer "B.Fab")
		)
		(fp_line
			(start -0.802 0.276)
			(end -0.802 -0.424)
			(stroke
				(width 0.15)
				(type solid)
			)
			(layer "B.Fab")
		)
		(fp_line
			(start 0.8 -0.424)
			(end -0.802 -0.424)
			(stroke
				(width 0.15)
				(type solid)
			)
			(layer "B.Fab")
		)
		(fp_circle
			(center -0.9652 -0.9652)
			(end -0.9144 -0.9652)
			(stroke
				(width 0.15)
				(type solid)
			)
			(fill no)
			(layer "B.Fab")
		)
		(fp_text user "Author: Antmicro"
			(at -1.12 -6.224 90)
			(layer "B.Fab")
			(effects
				(font
					(size 0.7 0.7)
					(thickness 0.15)
				)
				(justify left bottom mirror)
			)
		)
		(fp_text user "License: Apache-2.0"
			(at -1.12 -5.024 90)
			(layer "B.Fab")
			(effects
				(font
					(size 0.7 0.7)
					(thickness 0.15)
				)
				(justify left bottom mirror)
			)
		)
		(fp_text user "${REFERENCE}"
			(at -1.12 -3.824 90)
			(layer "B.Fab")
			(effects
				(font
					(size 0.7 0.7)
					(thickness 0.15)
				)
				(justify left bottom mirror)
			)
		)
		(pad "1" smd rect
			(at -0.5 -0.65 270)
			(size 0.4 0.51)
			(layers "B.Cu" "B.Mask" "B.Paste")
			(net 104 "/M.2/~{PEWAKE}")
			(pinfunction "G")
			(pintype "input")
		)
		(pad "2" smd rect
			(at 0.498 -0.65 270)
			(size 0.4 0.51)
			(layers "B.Cu" "B.Mask" "B.Paste")
			(net 1 "GND")
			(pinfunction "S")
			(pintype "passive")
		)
		(pad "3" smd rect
			(at 0 0.652 270)
			(size 0.4 0.51)
			(layers "B.Cu" "B.Mask" "B.Paste")
			(net 881 "/USB Debug, PD/FTDI_CBUS_EN")
			(pinfunction "D")
			(pintype "passive")
		)
	)
	(footprint "antmicro-footprints:C_0402_1005Metric"
		(layer "B.Cu")
		(at 198.476 144 -90)
		(descr "Capacitor SMD 0402")
		(tags "capacitor SMD 0402")
		(property "Reference" "C180"
			(at -1.8 0.65 90)
			(layer "B.SilkS")
			(effects
				(font
					(size 0.7 0.7)
					(thickness 0.15)
				)
				(justify left bottom mirror)
			)
		)
		(property "Value" "C_100n_0402"
			(at -1.022927 -2.155213 90)
			(layer "B.Fab")
			(effects
				(font
					(size 0.7 0.7)
					(thickness 0.15)
				)
				(justify left bottom mirror)
			)
		)
		(property "Datasheet" "https://www.murata.com/products/productdetail?partno=GRM155R61H104KE14%23"
			(at 0 0 90)
			(layer "B.Fab")
			(hide yes)
			(effects
				(font
					(size 1.27 1.27)
					(thickness 0.15)
				)
				(justify mirror)
			)
		)
		(property "Description" "SMD Multilayer Ceramic Capacitor, 0.1 µF, 50 V, 0402 [1005 Metric], ± 10%, X5R, GRM Series"
			(at 0 0 90)
			(layer "B.Fab")
			(hide yes)
			(effects
				(font
					(size 1.27 1.27)
					(thickness 0.15)
				)
				(justify mirror)
			)
		)
		(property "MPN" "GRM155R61H104KE14D"
			(at 0 0 90)
			(unlocked yes)
			(layer "B.Fab")
			(hide yes)
			(effects
				(font
					(size 1 1)
					(thickness 0.15)
				)
				(justify mirror)
			)
		)
		(property "Manufacturer" "Murata"
			(at 0 0 90)
			(unlocked yes)
			(layer "B.Fab")
			(hide yes)
			(effects
				(font
					(size 1 1)
					(thickness 0.15)
				)
				(justify mirror)
			)
		)
		(property "License" "Apache-2.0"
			(at 0 0 90)
			(unlocked yes)
			(layer "B.Fab")
			(hide yes)
			(effects
				(font
					(size 1 1)
					(thickness 0.15)
				)
				(justify mirror)
			)
		)
		(property "Author" "Antmicro"
			(at 0 0 90)
			(unlocked yes)
			(layer "B.Fab")
			(hide yes)
			(effects
				(font
					(size 1 1)
					(thickness 0.15)
				)
				(justify mirror)
			)
		)
		(property "Val" "100n"
			(at 0 0 90)
			(unlocked yes)
			(layer "B.Fab")
			(hide yes)
			(effects
				(font
					(size 1 1)
					(thickness 0.15)
				)
				(justify mirror)
			)
		)
		(property "Voltage" "50V"
			(at 0 0 90)
			(unlocked yes)
			(layer "B.Fab")
			(hide yes)
			(effects
				(font
					(size 1 1)
					(thickness 0.15)
				)
				(justify mirror)
			)
		)
		(property "Dielectric" "X5R"
			(at 0 0 90)
			(unlocked yes)
			(layer "B.Fab")
			(hide yes)
			(effects
				(font
					(size 1 1)
					(thickness 0.15)
				)
				(justify mirror)
			)
		)
		(sheetname "/SFP/")
		(sheetfile "sfp.kicad_sch")
		(attr smd)
		(fp_poly
			(pts
				(xy -0.925 0.47) (xy 0.925 0.47) (xy 0.925 -0.47) (xy -0.925 -0.47)
			)
			(stroke
				(width 0.05)
				(type default)
			)
			(fill no)
			(layer "B.CrtYd")
		)
		(fp_line
			(start -0.494 0.25)
			(end 0.504 0.25)
			(stroke
				(width 0.15)
				(type solid)
			)
			(layer "B.Fab")
		)
		(fp_line
			(start 0.504 0.25)
			(end 0.504 -0.248)
			(stroke
				(width 0.15)
				(type solid)
			)
			(layer "B.Fab")
		)
		(fp_line
			(start -0.494 -0.248)
			(end -0.494 0.25)
			(stroke
				(width 0.15)
				(type solid)
			)
			(layer "B.Fab")
		)
		(fp_line
			(start 0.504 -0.248)
			(end -0.494 -0.248)
			(stroke
				(width 0.15)
				(type solid)
			)
			(layer "B.Fab")
		)
		(fp_text user "License: Apache-2.0"
			(at -0.939 -5.799 90)
			(layer "B.Fab")
			(effects
				(font
					(size 0.7 0.7)
					(thickness 0.15)
				)
				(justify left bottom mirror)
			)
		)
		(fp_text user "Author: Antmicro"
			(at -0.939 -3.399 90)
			(layer "B.Fab")
			(effects
				(font
					(size 0.7 0.7)
					(thickness 0.15)
				)
				(justify left bottom mirror)
			)
		)
		(fp_text user "${REFERENCE}"
			(at -0.939 -4.599 90)
			(layer "B.Fab")
			(effects
				(font
					(size 0.7 0.7)
					(thickness 0.15)
				)
				(justify left bottom mirror)
			)
		)
		(pad "1" smd roundrect
			(at -0.48 0 270)
			(size 0.59 0.64)
			(layers "B.Cu" "B.Mask" "B.Paste")
			(roundrect_rratio 0.25)
			(net 1 "GND")
			(pintype "passive")
		)
		(pad "2" smd roundrect
			(at 0.48 0 270)
			(size 0.59 0.64)
			(layers "B.Cu" "B.Mask" "B.Paste")
			(roundrect_rratio 0.25)
			(net 2 "+3V3")
			(pintype "passive")
		)
	)
	(footprint "antmicro-footprints:R_0402_1005Metric"
		(layer "B.Cu")
		(at 157.15 67.53 180)
		(descr "Resistor SMD 0402")
		(tags "resistor SMD 0402")
		(property "Reference" "R292"
			(at -1.07 -4.17 0)
			(layer "B.SilkS")
			(effects
				(font
					(size 0.7 0.7)
					(thickness 0.15)
				)
				(justify left bottom mirror)
			)
		)
		(property "Value" "R_0R_0402"
			(at -1.011843 -1.772047 0)
			(layer "B.Fab")
			(effects
				(font
					(size 0.7 0.7)
					(thickness 0.15)
				)
				(justify left bottom mirror)
			)
		)
		(property "Datasheet" "https://industrial.panasonic.com/cdbs/www-data/pdf/RDA0000/AOA0000C301.pdf"
			(at 0 0 0)
			(layer "B.Fab")
			(hide yes)
			(effects
				(font
					(size 1.27 1.27)
					(thickness 0.15)
				)
				(justify mirror)
			)
		)
		(property "Description" "SMD Chip Resistor, Jumper, 0 ohm, 100 mW, 0402 [1005 Metric], Thick Film, General Purpose"
			(at 0 0 0)
			(layer "B.Fab")
			(hide yes)
			(effects
				(font
					(size 1.27 1.27)
					(thickness 0.15)
				)
				(justify mirror)
			)
		)
		(property "MPN" "ERJ2GE0R00X"
			(at 0 0 0)
			(unlocked yes)
			(layer "B.Fab")
			(hide yes)
			(effects
				(font
					(size 1 1)
					(thickness 0.15)
				)
				(justify mirror)
			)
		)
		(property "Manufacturer" "Panasonic"
			(at 0 0 0)
			(unlocked yes)
			(layer "B.Fab")
			(hide yes)
			(effects
				(font
					(size 1 1)
					(thickness 0.15)
				)
				(justify mirror)
			)
		)
		(property "License" "Apache-2.0"
			(at 0 0 0)
			(unlocked yes)
			(layer "B.Fab")
			(hide yes)
			(effects
				(font
					(size 1 1)
					(thickness 0.15)
				)
				(justify mirror)
			)
		)
		(property "Author" "Antmicro"
			(at 0 0 0)
			(unlocked yes)
			(layer "B.Fab")
			(hide yes)
			(effects
				(font
					(size 1 1)
					(thickness 0.15)
				)
				(justify mirror)
			)
		)
		(property "Val" "0R"
			(at 0 0 0)
			(unlocked yes)
			(layer "B.Fab")
			(hide yes)
			(effects
				(font
					(size 1 1)
					(thickness 0.15)
				)
				(justify mirror)
			)
		)
		(property "Tolerance" "~"
			(at 0 0 0)
			(unlocked yes)
			(layer "B.Fab")
			(hide yes)
			(effects
				(font
					(size 1 1)
					(thickness 0.15)
				)
				(justify mirror)
			)
		)
		(property "Current" "1A"
			(at 0 0 0)
			(unlocked yes)
			(layer "B.Fab")
			(hide yes)
			(effects
				(font
					(size 1 1)
					(thickness 0.15)
				)
				(justify mirror)
			)
		)
		(sheetname "/SoM_IO2/")
		(sheetfile "som_io2.kicad_sch")
		(attr smd exclude_from_pos_files exclude_from_bom dnp)
		(fp_rect
			(start -0.925 0.47)
			(end 0.925 -0.47)
			(stroke
				(width 0.05)
				(type default)
			)
			(fill no)
			(layer "B.CrtYd")
		)
		(fp_rect
			(start -0.5 0.25)
			(end 0.5 -0.25)
			(stroke
				(width 0.15)
				(type solid)
			)
			(fill no)
			(layer "B.Fab")
		)
		(fp_text user "Author: Antmicro"
			(at -0.95 -4.169 0)
			(layer "B.Fab")
			(effects
				(font
					(size 0.7 0.7)
					(thickness 0.15)
				)
				(justify left bottom mirror)
			)
		)
		(fp_text user "${REFERENCE}"
			(at -0.95 -3.168 0)
			(layer "B.Fab")
			(effects
				(font
					(size 0.7 0.7)
					(thickness 0.15)
				)
				(justify left bottom mirror)
			)
		)
		(fp_text user "License: Apache-2.0"
			(at -0.95 -5.169 0)
			(layer "B.Fab")
			(effects
				(font
					(size 0.7 0.7)
					(thickness 0.15)
				)
				(justify left bottom mirror)
			)
		)
		(pad "1" smd roundrect
			(at -0.48 0 180)
			(size 0.59 0.64)
			(layers "B.Cu" "B.Mask" "B.Paste")
			(roundrect_rratio 0.25)
			(net 1028 "Net-(U59-B3Y)")
			(pintype "passive")
		)
		(pad "2" smd roundrect
			(at 0.48 0 180)
			(size 0.59 0.64)
			(layers "B.Cu" "B.Mask" "B.Paste")
			(roundrect_rratio 0.25)
			(net 743 "/SoM_IO2/JTAG_TCK")
			(pintype "passive")
		)
	)
	(footprint "antmicro-footprints:Fiducial_1mm_Mask3mm"
		(layer "B.Cu")
		(at 237.74 55.81 180)
		(descr "Circular Fiducial, 1.5mm bare copper, 3mm soldermask opening")
		(tags "fiducial")
		(property "Reference" "FD5"
			(at 1.57 -0.43 0)
			(layer "B.SilkS")
			(effects
				(font
					(size 0.7 0.7)
					(thickness 0.15)
				)
				(justify left bottom mirror)
			)
		)
		(property "Value" "Fiducial_1mm_Mask3mm"
			(at 0 -2.603 0)
			(layer "B.Fab")
			(effects
				(font
					(size 0.7 0.7)
					(thickness 0.15)
				)
				(justify left bottom mirror)
			)
		)
		(property "Description" "Fiducial mask"
			(at 0 0 0)
			(layer "B.Fab")
			(hide yes)
			(effects
				(font
					(size 1.27 1.27)
					(thickness 0.15)
				)
				(justify mirror)
			)
		)
		(property "Author" "Antmicro"
			(at 0 0 0)
			(unlocked yes)
			(layer "B.Fab")
			(hide yes)
			(effects
				(font
					(size 1 1)
					(thickness 0.15)
				)
				(justify mirror)
			)
		)
		(property "License" "Apache-2.0"
			(at 0 0 0)
			(unlocked yes)
			(layer "B.Fab")
			(hide yes)
			(effects
				(font
					(size 1 1)
					(thickness 0.15)
				)
				(justify mirror)
			)
		)
		(sheetname "/")
		(sheetfile "jetson-agx-thor-baseboard.kicad_sch")
		(attr exclude_from_pos_files exclude_from_bom)
		(fp_circle
			(center 0 0)
			(end 1.5 0)
			(stroke
				(width 0.05)
				(type solid)
			)
			(fill no)
			(layer "B.CrtYd")
		)
		(fp_circle
			(center 0 0)
			(end 1.5 0)
			(stroke
				(width 0.15)
				(type solid)
			)
			(fill no)
			(layer "B.Fab")
		)
		(fp_text user "${REFERENCE}"
			(at -1.25 -4.603 0)
			(layer "B.Fab")
			(effects
				(font
					(size 0.7 0.7)
					(thickness 0.15)
				)
				(justify left bottom mirror)
			)
		)
		(fp_text user "License: Apache-2.0"
			(at -1.25 -7.003 0)
			(layer "B.Fab")
			(effects
				(font
					(size 0.7 0.7)
					(thickness 0.15)
				)
				(justify left bottom mirror)
			)
		)
		(fp_text user "Author: Antmicro"
			(at -1.25 -5.803 0)
			(layer "B.Fab")
			(effects
				(font
					(size 0.7 0.7)
					(thickness 0.15)
				)
				(justify left bottom mirror)
			)
		)
		(pad "" smd circle
			(at 0 0 180)
			(size 1 1)
			(layers "B.Cu" "B.Mask")
			(solder_mask_margin 1)
			(clearance 1)
		)
	)
	(footprint "antmicro-footprints:R_0402_1005Metric"
		(layer "B.Cu")
		(at 175.568 60.063002 90)
		(descr "Resistor SMD 0402")
		(tags "resistor SMD 0402")
		(property "Reference" "R229"
			(at -1.536998 0.632 90)
			(layer "B.SilkS")
			(effects
				(font
					(size 0.7 0.7)
					(thickness 0.15)
				)
				(justify right top mirror)
			)
		)
		(property "Value" "R_100k_0402"
			(at -1.011843 -1.772047 90)
			(layer "B.Fab")
			(effects
				(font
					(size 0.7 0.7)
					(thickness 0.15)
				)
				(justify right top mirror)
			)
		)
		(property "Datasheet" "https://www.bourns.com/docs/product-datasheets/cr.pdf"
			(at 0 0 90)
			(layer "B.Fab")
			(hide yes)
			(effects
				(font
					(size 1.27 1.27)
					(thickness 0.15)
				)
				(justify mirror)
			)
		)
		(property "Description" "SMD Chip Resistor, 100 kohm, ± 1%, 62.5 mW, 0402 [1005 Metric], Thick Film, General Purpose"
			(at 0 0 90)
			(layer "B.Fab")
			(hide yes)
			(effects
				(font
					(size 1.27 1.27)
					(thickness 0.15)
				)
				(justify mirror)
			)
		)
		(property "Manufacturer" "Bourns"
			(at 0 0 270)
			(unlocked yes)
			(layer "B.Fab")
			(hide yes)
			(effects
				(font
					(size 1 1)
					(thickness 0.15)
				)
				(justify mirror)
			)
		)
		(property "MPN" "CR0402-FX-1003GLF"
			(at 0 0 270)
			(unlocked yes)
			(layer "B.Fab")
			(hide yes)
			(effects
				(font
					(size 1 1)
					(thickness 0.15)
				)
				(justify mirror)
			)
		)
		(property "Val" "100k"
			(at 0 0 270)
			(unlocked yes)
			(layer "B.Fab")
			(hide yes)
			(effects
				(font
					(size 1 1)
					(thickness 0.15)
				)
				(justify mirror)
			)
		)
		(property "License" "Apache-2.0"
			(at 0 0 270)
			(unlocked yes)
			(layer "B.Fab")
			(hide yes)
			(effects
				(font
					(size 1 1)
					(thickness 0.15)
				)
				(justify mirror)
			)
		)
		(property "Author" "Antmicro"
			(at 0 0 270)
			(unlocked yes)
			(layer "B.Fab")
			(hide yes)
			(effects
				(font
					(size 1 1)
					(thickness 0.15)
				)
				(justify mirror)
			)
		)
		(property "Tolerance" "1%"
			(at 0 0 270)
			(unlocked yes)
			(layer "B.Fab")
			(hide yes)
			(effects
				(font
					(size 1 1)
					(thickness 0.15)
				)
				(justify mirror)
			)
		)
		(sheetname "/Peripherals/")
		(sheetfile "peripherals.kicad_sch")
		(attr smd)
		(fp_rect
			(start -0.925 0.47)
			(end 0.925 -0.47)
			(stroke
				(width 0.05)
				(type default)
			)
			(fill no)
			(layer "B.CrtYd")
		)
		(fp_rect
			(start -0.5 0.25)
			(end 0.5 -0.25)
			(stroke
				(width 0.15)
				(type solid)
			)
			(fill no)
			(layer "B.Fab")
		)
		(fp_text user "License: Apache-2.0"
			(at -0.95 -5.169 90)
			(layer "B.Fab")
			(effects
				(font
					(size 0.7 0.7)
					(thickness 0.15)
				)
				(justify right top mirror)
			)
		)
		(fp_text user "Author: Antmicro"
			(at -0.95 -4.169 90)
			(layer "B.Fab")
			(effects
				(font
					(size 0.7 0.7)
					(thickness 0.15)
				)
				(justify right top mirror)
			)
		)
		(fp_text user "${REFERENCE}"
			(at -0.95 -3.168 90)
			(layer "B.Fab")
			(effects
				(font
					(size 0.7 0.7)
					(thickness 0.15)
				)
				(justify right top mirror)
			)
		)
		(pad "1" smd roundrect
			(at -0.48 0 90)
			(size 0.59 0.64)
			(layers "B.Cu" "B.Mask" "B.Paste")
			(roundrect_rratio 0.25)
			(net 1 "GND")
			(pintype "passive")
		)
		(pad "2" smd roundrect
			(at 0.48 0 90)
			(size 0.59 0.64)
			(layers "B.Cu" "B.Mask" "B.Paste")
			(roundrect_rratio 0.25)
			(net 487 "/Expansion connector/GPIO.USER_LED0")
			(pintype "passive")
		)
	)
	(footprint "antmicro-footprints:C_0402_1005Metric"
		(layer "B.Cu")
		(at 110.25 101.5)
		(descr "Capacitor SMD 0402")
		(tags "capacitor SMD 0402")
		(property "Reference" "C187"
			(at -0.95 -0.301 0)
			(layer "B.SilkS")
			(effects
				(font
					(size 0.7 0.7)
					(thickness 0.15)
				)
				(justify left top mirror)
			)
		)
		(property "Value" "C_220n_0402"
			(at -1.022927 -2.155213 0)
			(layer "B.Fab")
			(effects
				(font
					(size 0.7 0.7)
					(thickness 0.15)
				)
				(justify right top mirror)
			)
		)
		(property "Datasheet" "https://www.yageo.com/en/Chart/Download/pdf/CC0402KRX5R6BB224"
			(at 0 0 0)
			(layer "B.Fab")
			(hide yes)
			(effects
				(font
					(size 1.27 1.27)
					(thickness 0.15)
				)
				(justify mirror)
			)
		)
		(property "Description" "SMD Multilayer Ceramic Capacitor, 0.22 µF, 10 V, 0402 [1005 Metric], ± 10%, X5R, CC Series"
			(at 0 0 0)
			(layer "B.Fab")
			(hide yes)
			(effects
				(font
					(size 1.27 1.27)
					(thickness 0.15)
				)
				(justify mirror)
			)
		)
		(property "MPN" "CC0402KRX5R6BB224"
			(at 0 0 0)
			(unlocked yes)
			(layer "B.Fab")
			(hide yes)
			(effects
				(font
					(size 1 1)
					(thickness 0.15)
				)
				(justify mirror)
			)
		)
		(property "Val" "220n"
			(at 0 0 0)
			(unlocked yes)
			(layer "B.Fab")
			(hide yes)
			(effects
				(font
					(size 1 1)
					(thickness 0.15)
				)
				(justify mirror)
			)
		)
		(property "Voltage" "25V"
			(at 0 0 0)
			(unlocked yes)
			(layer "B.Fab")
			(hide yes)
			(effects
				(font
					(size 1 1)
					(thickness 0.15)
				)
				(justify mirror)
			)
		)
		(property "Dielectric" "X7R"
			(at 0 0 0)
			(unlocked yes)
			(layer "B.Fab")
			(hide yes)
			(effects
				(font
					(size 1 1)
					(thickness 0.15)
				)
				(justify mirror)
			)
		)
		(property "Manufacturer" "YAGEO"
			(at 0 0 0)
			(unlocked yes)
			(layer "B.Fab")
			(hide yes)
			(effects
				(font
					(size 1 1)
					(thickness 0.15)
				)
				(justify mirror)
			)
		)
		(property "License" "Apache-2.0"
			(at 0 0 0)
			(unlocked yes)
			(layer "B.Fab")
			(hide yes)
			(effects
				(font
					(size 1 1)
					(thickness 0.15)
				)
				(justify mirror)
			)
		)
		(property "Author" "Antmicro"
			(at 0 0 0)
			(unlocked yes)
			(layer "B.Fab")
			(hide yes)
			(effects
				(font
					(size 1 1)
					(thickness 0.15)
				)
				(justify mirror)
			)
		)
		(property "Public" "False"
			(at 0 0 0)
			(unlocked yes)
			(layer "B.Fab")
			(hide yes)
			(effects
				(font
					(size 1 1)
					(thickness 0.15)
				)
				(justify mirror)
			)
		)
		(sheetname "/M.2/")
		(sheetfile "m2.kicad_sch")
		(attr smd)
		(fp_poly
			(pts
				(xy -0.925 0.47) (xy -0.925 -0.47) (xy 0.925 -0.47) (xy 0.925 0.47)
			)
			(stroke
				(width 0.05)
				(type default)
			)
			(fill no)
			(layer "B.CrtYd")
		)
		(fp_line
			(start -0.494 -0.248)
			(end -0.494 0.25)
			(stroke
				(width 0.15)
				(type solid)
			)
			(layer "B.Fab")
		)
		(fp_line
			(start -0.494 0.25)
			(end 0.504 0.25)
			(stroke
				(width 0.15)
				(type solid)
			)
			(layer "B.Fab")
		)
		(fp_line
			(start 0.504 -0.248)
			(end -0.494 -0.248)
			(stroke
				(width 0.15)
				(type solid)
			)
			(layer "B.Fab")
		)
		(fp_line
			(start 0.504 0.25)
			(end 0.504 -0.248)
			(stroke
				(width 0.15)
				(type solid)
			)
			(layer "B.Fab")
		)
		(fp_text user "License: Apache-2.0"
			(at -0.939 -5.799 0)
			(layer "B.Fab")
			(effects
				(font
					(size 0.7 0.7)
					(thickness 0.15)
				)
				(justify right top mirror)
			)
		)
		(fp_text user "${REFERENCE}"
			(at -0.939 -4.599 0)
			(layer "B.Fab")
			(effects
				(font
					(size 0.7 0.7)
					(thickness 0.15)
				)
				(justify right top mirror)
			)
		)
		(fp_text user "Author: Antmicro"
			(at -0.939 -3.399 0)
			(layer "B.Fab")
			(effects
				(font
					(size 0.7 0.7)
					(thickness 0.15)
				)
				(justify right top mirror)
			)
		)
		(pad "1" smd roundrect
			(at -0.48 0)
			(size 0.59 0.64)
			(layers "B.Cu" "B.Mask" "B.Paste")
			(roundrect_rratio 0.25)
			(net 435 "/M.2/PCIe_{C5x4}.TX2-")
			(pintype "passive")
		)
		(pad "2" smd roundrect
			(at 0.48 0)
			(size 0.59 0.64)
			(layers "B.Cu" "B.Mask" "B.Paste")
			(roundrect_rratio 0.25)
			(net 423 "/M.2/M2_M_PET2_N")
			(pintype "passive")
		)
	)
	(footprint "antmicro-footprints:Bus_M.2_Socket_Key_M_TE_1-2199230-6"
		(locked yes)
		(layer "B.Cu")
		(at 117.46 104.501 -90)
		(property "Reference" "J13"
			(at 4.83 -5.49 90)
			(layer "B.SilkS")
			(effects
				(font
					(size 0.7 0.7)
					(thickness 0.15)
				)
				(justify right top mirror)
			)
		)
		(property "Value" "Bus_M.2_1-2199230-6"
			(at -11.25 -6.124 90)
			(layer "B.Fab")
			(effects
				(font
					(size 0.7 0.7)
					(thickness 0.15)
				)
				(justify left bottom mirror)
			)
		)
		(property "Datasheet" "https://www.te.com/commerce/DocumentDelivery/DDEController?Action=srchrtrv&DocNm=2199230&DocType=Customer+Drawing&DocLang=English"
			(at 0 0 90)
			(layer "B.Fab")
			(hide yes)
			(effects
				(font
					(size 1.27 1.27)
					(thickness 0.15)
				)
				(justify mirror)
			)
		)
		(property "Description" "Key M Card Edge Connector, 0, Dual Side, 67 Contacts, Surface Mount, Right Angle, Solder"
			(at 0 0 90)
			(layer "B.Fab")
			(hide yes)
			(effects
				(font
					(size 1.27 1.27)
					(thickness 0.15)
				)
				(justify mirror)
			)
		)
		(property "Manufacturer" "TE Connectivity"
			(at 0 0 90)
			(unlocked yes)
			(layer "B.Fab")
			(hide yes)
			(effects
				(font
					(size 1 1)
					(thickness 0.15)
				)
				(justify mirror)
			)
		)
		(property "MPN" "1-2199230-6"
			(at 0 0 90)
			(unlocked yes)
			(layer "B.Fab")
			(hide yes)
			(effects
				(font
					(size 1 1)
					(thickness 0.15)
				)
				(justify mirror)
			)
		)
		(property "Author" "Antmicro"
			(at 0 0 90)
			(unlocked yes)
			(layer "B.Fab")
			(hide yes)
			(effects
				(font
					(size 1 1)
					(thickness 0.15)
				)
				(justify mirror)
			)
		)
		(property "License" "Apache-2.0"
			(at 0 0 90)
			(unlocked yes)
			(layer "B.Fab")
			(hide yes)
			(effects
				(font
					(size 1 1)
					(thickness 0.15)
				)
				(justify mirror)
			)
		)
		(sheetname "/M.2/")
		(sheetfile "m2.kicad_sch")
		(attr smd)
		(fp_line
			(start 5.097 3.75)
			(end 6.898 3.75)
			(stroke
				(width 0.15)
				(type solid)
			)
			(layer "B.SilkS")
		)
		(fp_line
			(start -10.951 1.401)
			(end -10.951 -0.55)
			(stroke
				(width 0.15)
				(type solid)
			)
			(layer "B.SilkS")
		)
		(fp_line
			(start 10.948 -0.449)
			(end 10.948 1.301)
			(stroke
				(width 0.15)
				(type solid)
			)
			(layer "B.SilkS")
		)
		(fp_line
			(start -10.951 -2.7)
			(end -10.951 -3.999)
			(stroke
				(width 0.15)
				(type solid)
			)
			(layer "B.SilkS")
		)
		(fp_line
			(start -10.951 -3.999)
			(end -9.352 -3.999)
			(stroke
				(width 0.15)
				(type solid)
			)
			(layer "B.SilkS")
		)
		(fp_line
			(start 5.347 -3.999)
			(end 7.148 -3.999)
			(stroke
				(width 0.15)
				(type solid)
			)
			(layer "B.SilkS")
		)
		(fp_line
			(start 9.448 -3.999)
			(end 10.948 -3.999)
			(stroke
				(width 0.15)
				(type solid)
			)
			(layer "B.SilkS")
		)
		(fp_line
			(start 10.948 -3.999)
			(end 10.948 -2.3)
			(stroke
				(width 0.15)
				(type solid)
			)
			(layer "B.SilkS")
		)
		(fp_circle
			(center -9.25 5.651)
			(end -9.2 5.651)
			(stroke
				(width 0.15)
				(type solid)
			)
			(fill yes)
			(layer "B.SilkS")
		)
		(fp_circle
			(center -9.25 4.875)
			(end -9.201 4.826)
			(stroke
				(width 0.15)
				(type solid)
			)
			(fill yes)
			(layer "B.SilkS")
		)
		(fp_line
			(start -11.16 4.83)
			(end -11.16 -4.78)
			(stroke
				(width 0.05)
				(type solid)
			)
			(layer "B.CrtYd")
		)
		(fp_line
			(start 11.15 4.83)
			(end -11.16 4.83)
			(stroke
				(width 0.05)
				(type solid)
			)
			(layer "B.CrtYd")
		)
		(fp_line
			(start -11.16 -4.78)
			(end 11.15 -4.78)
			(stroke
				(width 0.05)
				(type solid)
			)
			(layer "B.CrtYd")
		)
		(fp_line
			(start 11.15 -4.78)
			(end 11.15 4.83)
			(stroke
				(width 0.05)
				(type solid)
			)
			(layer "B.CrtYd")
		)
		(fp_line
			(start -10.4 4.1)
			(end 10.95 4.1)
			(stroke
				(width 0.15)
				(type solid)
			)
			(layer "B.Fab")
		)
		(fp_line
			(start 10.95 4.1)
			(end 10.95 -4.2)
			(stroke
				(width 0.15)
				(type solid)
			)
			(layer "B.Fab")
		)
		(fp_line
			(start -10.949 3.55)
			(end -10.4 4.1)
			(stroke
				(width 0.15)
				(type solid)
			)
			(layer "B.Fab")
		)
		(fp_line
			(start -10.949 -4.2)
			(end -10.949 3.55)
			(stroke
				(width 0.15)
				(type solid)
			)
			(layer "B.Fab")
		)
		(fp_line
			(start 10.95 -4.2)
			(end -10.949 -4.2)
			(stroke
				(width 0.15)
				(type solid)
			)
			(layer "B.Fab")
		)
		(fp_text user "License: Apache-2.0"
			(at -11.35 -10.525 90)
			(layer "B.Fab")
			(effects
				(font
					(size 0.7 0.7)
					(thickness 0.15)
				)
				(justify left bottom mirror)
			)
		)
		(fp_text user "${REFERENCE}"
			(at -11.35 -8.124 90)
			(layer "B.Fab")
			(effects
				(font
					(size 0.7 0.7)
					(thickness 0.15)
				)
				(justify left bottom mirror)
			)
		)
		(fp_text user "Author: Antmicro"
			(at -11.35 -9.325 90)
			(layer "B.Fab")
			(effects
				(font
					(size 0.7 0.7)
					(thickness 0.15)
				)
				(justify left bottom mirror)
			)
		)
		(pad "" np_thru_hole circle
			(at -10 -1.499 270)
			(size 1.1 1.1)
			(drill 1.1)
			(layers "*.Mask")
		)
		(pad "" np_thru_hole circle
			(at 9.997 -1.499 270)
			(size 1.6 1.6)
			(drill 1.6)
			(layers "*.Mask")
		)
		(pad "1" smd rect
			(at -9.25 3.775 270)
			(size 0.3 1.55)
			(layers "B.Cu" "B.Mask" "B.Paste")
			(net 1 "GND")
			(pinfunction "GND")
			(pintype "power_in")
		)
		(pad "2" smd rect
			(at -9.003 -3.773 270)
			(size 0.3 1.55)
			(layers "B.Cu" "B.Mask" "B.Paste")
			(net 14 "/M.2/3V3_M2")
			(pinfunction "3V3")
			(pintype "passive")
		)
		(pad "3" smd rect
			(at -8.753 3.775 270)
			(size 0.3 1.55)
			(layers "B.Cu" "B.Mask" "B.Paste")
			(net 1 "GND")
			(pinfunction "GND")
			(pintype "passive")
		)
		(pad "4" smd rect
			(at -8.503 -3.773 270)
			(size 0.3 1.55)
			(layers "B.Cu" "B.Mask" "B.Paste")
			(net 14 "/M.2/3V3_M2")
			(pinfunction "3V3")
			(pintype "passive")
		)
		(pad "5" smd rect
			(at -8.253 3.775 270)
			(size 0.3 1.55)
			(layers "B.Cu" "B.Mask" "B.Paste")
			(net 564 "/M.2/PCIe_{C5x4}.RX3-")
			(pinfunction "PER3_N")
			(pintype "output")
		)
		(pad "6" smd rect
			(at -8.001 -3.773 270)
			(size 0.3 1.55)
			(layers "B.Cu" "B.Mask" "B.Paste")
			(net 226 "unconnected-(J13-NC-Pad6)")
			(pinfunction "NC")
			(pintype "no_connect")
		)
		(pad "7" smd rect
			(at -7.752 3.775 270)
			(size 0.3 1.55)
			(layers "B.Cu" "B.Mask" "B.Paste")
			(net 681 "/M.2/PCIe_{C5x4}.RX3+")
			(pinfunction "PER3_P")
			(pintype "output")
		)
		(pad "8" smd rect
			(at -7.502 -3.773 270)
			(size 0.3 1.55)
			(layers "B.Cu" "B.Mask" "B.Paste")
			(net 223 "unconnected-(J13-NC-Pad8)")
			(pinfunction "NC")
			(pintype "no_connect")
		)
		(pad "9" smd rect
			(at -7.252 3.775 270)
			(size 0.3 1.55)
			(layers "B.Cu" "B.Mask" "B.Paste")
			(net 1 "GND")
			(pinfunction "GND")
			(pintype "passive")
		)
		(pad "10" smd rect
			(at -7.002 -3.773 270)
			(size 0.3 1.55)
			(layers "B.Cu" "B.Mask" "B.Paste")
			(net 33 "Net-(D32-C)")
			(pinfunction "LED")
			(pintype "passive")
		)
		(pad "11" smd rect
			(at -6.752 3.775 270)
			(size 0.3 1.55)
			(layers "B.Cu" "B.Mask" "B.Paste")
			(net 436 "/M.2/M2_M_PET3_N")
			(pinfunction "PET3_N")
			(pintype "input")
		)
		(pad "12" smd rect
			(at -6.502 -3.773 270)
			(size 0.3 1.55)
			(layers "B.Cu" "B.Mask" "B.Paste")
			(net 14 "/M.2/3V3_M2")
			(pinfunction "3V3")
			(pintype "passive")
		)
		(pad "13" smd rect
			(at -6.252 3.775 270)
			(size 0.3 1.55)
			(layers "B.Cu" "B.Mask" "B.Paste")
			(net 408 "/M.2/M2_M_PET3_P")
			(pinfunction "PET3_P")
			(pintype "input")
		)
		(pad "14" smd rect
			(at -6.002 -3.773 270)
			(size 0.3 1.55)
			(layers "B.Cu" "B.Mask" "B.Paste")
			(net 14 "/M.2/3V3_M2")
			(pinfunction "3V3")
			(pintype "passive")
		)
		(pad "15" smd rect
			(at -5.752 3.775 270)
			(size 0.3 1.55)
			(layers "B.Cu" "B.Mask" "B.Paste")
			(net 1 "GND")
			(pinfunction "GND")
			(pintype "passive")
		)
		(pad "16" smd rect
			(at -5.502 -3.773 270)
			(size 0.3 1.55)
			(layers "B.Cu" "B.Mask" "B.Paste")
			(net 14 "/M.2/3V3_M2")
			(pinfunction "3V3")
			(pintype "passive")
		)
		(pad "17" smd rect
			(at -5.252 3.775 270)
			(size 0.3 1.55)
			(layers "B.Cu" "B.Mask" "B.Paste")
			(net 731 "/M.2/PCIe_{C5x4}.RX2+")
			(pinfunction "PER2_N")
			(pintype "output")
		)
		(pad "18" smd rect
			(at -5.002 -3.773 270)
			(size 0.3 1.55)
			(layers "B.Cu" "B.Mask" "B.Paste")
			(net 14 "/M.2/3V3_M2")
			(pinfunction "3V3")
			(pintype "passive")
		)
		(pad "19" smd rect
			(at -4.752 3.775 270)
			(size 0.3 1.55)
			(layers "B.Cu" "B.Mask" "B.Paste")
			(net 552 "/M.2/PCIe_{C5x4}.RX2-")
			(pinfunction "PER2_P")
			(pintype "output")
		)
		(pad "20" smd rect
			(at -4.502 -3.773 270)
			(size 0.3 1.55)
			(layers "B.Cu" "B.Mask" "B.Paste")
			(net 232 "unconnected-(J13-NC-Pad20)")
			(pinfunction "NC")
			(pintype "no_connect")
		)
		(pad "21" smd rect
			(at -4.252 3.775 270)
			(size 0.3 1.55)
			(layers "B.Cu" "B.Mask" "B.Paste")
			(net 1 "GND")
			(pinfunction "GND")
			(pintype "passive")
		)
		(pad "22" smd rect
			(at -4.002 -3.773 270)
			(size 0.3 1.55)
			(layers "B.Cu" "B.Mask" "B.Paste")
			(net 216 "unconnected-(J13-NC-Pad22)")
			(pinfunction "NC")
			(pintype "no_connect")
		)
		(pad "23" smd rect
			(at -3.751 3.775 270)
			(size 0.3 1.55)
			(layers "B.Cu" "B.Mask" "B.Paste")
			(net 399 "/M.2/M2_M_PET2_P")
			(pinfunction "PET2_N")
			(pintype "input")
		)
		(pad "24" smd rect
			(at -3.501 -3.773 270)
			(size 0.3 1.55)
			(layers "B.Cu" "B.Mask" "B.Paste")
			(net 218 "unconnected-(J13-NC-Pad24)")
			(pinfunction "NC")
			(pintype "no_connect")
		)
		(pad "25" smd rect
			(at -3.251 3.775 270)
			(size 0.3 1.55)
			(layers "B.Cu" "B.Mask" "B.Paste")
			(net 423 "/M.2/M2_M_PET2_N")
			(pinfunction "PET2_P")
			(pintype "input")
		)
		(pad "26" smd rect
			(at -3.001 -3.773 270)
			(size 0.3 1.55)
			(layers "B.Cu" "B.Mask" "B.Paste")
			(net 230 "unconnected-(J13-NC-Pad26)")
			(pinfunction "NC")
			(pintype "no_connect")
		)
		(pad "27" smd rect
			(at -2.751 3.775 270)
			(size 0.3 1.55)
			(layers "B.Cu" "B.Mask" "B.Paste")
			(net 1 "GND")
			(pinfunction "GND")
			(pintype "passive")
		)
		(pad "28" smd rect
			(at -2.501 -3.773 270)
			(size 0.3 1.55)
			(layers "B.Cu" "B.Mask" "B.Paste")
			(net 222 "unconnected-(J13-NC-Pad28)")
			(pinfunction "NC")
			(pintype "no_connect")
		)
		(pad "29" smd rect
			(at -2.251 3.775 270)
			(size 0.3 1.55)
			(layers "B.Cu" "B.Mask" "B.Paste")
			(net 674 "/M.2/PCIe_{C5x4}.RX1+")
			(pinfunction "PER1_N")
			(pintype "output")
		)
		(pad "30" smd rect
			(at -2.001 -3.773 270)
			(size 0.3 1.55)
			(layers "B.Cu" "B.Mask" "B.Paste")
			(net 228 "unconnected-(J13-NC-Pad30)")
			(pinfunction "NC")
			(pintype "no_connect")
		)
		(pad "31" smd rect
			(at -1.752 3.775 270)
			(size 0.3 1.55)
			(layers "B.Cu" "B.Mask" "B.Paste")
			(net 620 "/M.2/PCIe_{C5x4}.RX1-")
			(pinfunction "PER1_P")
			(pintype "output")
		)
		(pad "32" smd rect
			(at -1.502 -3.773 270)
			(size 0.3 1.55)
			(layers "B.Cu" "B.Mask" "B.Paste")
			(net 229 "unconnected-(J13-NC-Pad32)")
			(pinfunction "NC")
			(pintype "no_connect")
		)
		(pad "33" smd rect
			(at -1.252 3.775 270)
			(size 0.3 1.55)
			(layers "B.Cu" "B.Mask" "B.Paste")
			(net 1 "GND")
			(pinfunction "GND")
			(pintype "passive")
		)
		(pad "34" smd rect
			(at -1.002 -3.773 270)
			(size 0.3 1.55)
			(layers "B.Cu" "B.Mask" "B.Paste")
			(net 227 "unconnected-(J13-NC-Pad34)")
			(pinfunction "NC")
			(pintype "no_connect")
		)
		(pad "35" smd rect
			(at -0.751 3.775 270)
			(size 0.3 1.55)
			(layers "B.Cu" "B.Mask" "B.Paste")
			(net 391 "/M.2/M2_M_PET1_P")
			(pinfunction "PET1_N")
			(pintype "input")
		)
		(pad "36" smd rect
			(at -0.501 -3.773 270)
			(size 0.3 1.55)
			(layers "B.Cu" "B.Mask" "B.Paste")
			(net 219 "unconnected-(J13-NC-Pad36)")
			(pinfunction "NC")
			(pintype "no_connect")
		)
		(pad "37" smd rect
			(at -0.251 3.775 270)
			(size 0.3 1.55)
			(layers "B.Cu" "B.Mask" "B.Paste")
			(net 417 "/M.2/M2_M_PET1_N")
			(pinfunction "PET1_P")
			(pintype "input")
		)
		(pad "38" smd rect
			(at -0.001 -3.773 270)
			(size 0.3 1.55)
			(layers "B.Cu" "B.Mask" "B.Paste")
			(net 233 "unconnected-(J13-NC-Pad38)")
			(pinfunction "NC")
			(pintype "no_connect")
		)
		(pad "39" smd rect
			(at 0.248 3.775 270)
			(size 0.3 1.55)
			(layers "B.Cu" "B.Mask" "B.Paste")
			(net 1 "GND")
			(pinfunction "GND")
			(pintype "passive")
		)
		(pad "40" smd rect
			(at 0.498 -3.773 270)
			(size 0.3 1.55)
			(layers "B.Cu" "B.Mask" "B.Paste")
			(net 235 "/M.2/M2_M_SMB_CLK")
			(pinfunction "SMB_CLK")
			(pintype "input")
		)
		(pad "41" smd rect
			(at 0.748 3.775 270)
			(size 0.3 1.55)
			(layers "B.Cu" "B.Mask" "B.Paste")
			(net 669 "/M.2/PCIe_{C5x4}.RX0-")
			(pinfunction "PER0_N")
			(pintype "output")
		)
		(pad "42" smd rect
			(at 0.998 -3.773 270)
			(size 0.3 1.55)
			(layers "B.Cu" "B.Mask" "B.Paste")
			(net 217 "/M.2/M2_M_SMB_DATA")
			(pinfunction "SMB_DATA")
			(pintype "bidirectional")
		)
		(pad "43" smd rect
			(at 1.249 3.775 270)
			(size 0.3 1.55)
			(layers "B.Cu" "B.Mask" "B.Paste")
			(net 725 "/M.2/PCIe_{C5x4}.RX0+")
			(pinfunction "PER0_P")
			(pintype "output")
		)
		(pad "44" smd rect
			(at 1.499 -3.773 270)
			(size 0.3 1.55)
			(layers "B.Cu" "B.Mask" "B.Paste")
			(net 236 "/M.2/~{M2_M_ALERT}")
			(pinfunction "ALERT")
			(pintype "output")
		)
		(pad "45" smd rect
			(at 1.749 3.775 270)
			(size 0.3 1.55)
			(layers "B.Cu" "B.Mask" "B.Paste")
			(net 1 "GND")
			(pinfunction "GND")
			(pintype "passive")
		)
		(pad "46" smd rect
			(at 1.999 -3.773 270)
			(size 0.3 1.55)
			(layers "B.Cu" "B.Mask" "B.Paste")
			(net 238 "unconnected-(J13-NC-Pad46)")
			(pinfunction "NC")
			(pintype "no_connect")
		)
		(pad "47" smd rect
			(at 2.249 3.775 270)
			(size 0.3 1.55)
			(layers "B.Cu" "B.Mask" "B.Paste")
			(net 415 "/M.2/M2_M_PET0_N")
			(pinfunction "PET0_N")
			(pintype "input")
		)
		(pad "48" smd rect
			(at 2.499 -3.773 270)
			(size 0.3 1.55)
			(layers "B.Cu" "B.Mask" "B.Paste")
			(net 225 "unconnected-(J13-NC-Pad48)")
			(pinfunction "NC")
			(pintype "no_connect")
		)
		(pad "49" smd rect
			(at 2.749 3.775 270)
			(size 0.3 1.55)
			(layers "B.Cu" "B.Mask" "B.Paste")
			(net 386 "/M.2/M2_M_PET0_P")
			(pinfunction "PET0_P")
			(pintype "input")
		)
		(pad "50" smd rect
			(at 2.999 -3.773 270)
			(size 0.3 1.55)
			(layers "B.Cu" "B.Mask" "B.Paste")
			(net 827 "/M.2/~{PERST_M}")
			(pinfunction "~{PERST}")
			(pintype "input")
		)
		(pad "51" smd rect
			(at 3.249 3.775 270)
			(size 0.3 1.55)
			(layers "B.Cu" "B.Mask" "B.Paste")
			(net 1 "GND")
			(pinfunction "GND")
			(pintype "passive")
		)
		(pad "52" smd rect
			(at 3.499 -3.773 270)
			(size 0.3 1.55)
			(layers "B.Cu" "B.Mask" "B.Paste")
			(net 825 "/M.2/~{CLKREQ_M}")
			(pinfunction "~{CLKREQ}")
			(pintype "output")
		)
		(pad "53" smd rect
			(at 3.749 3.775 270)
			(size 0.3 1.55)
			(layers "B.Cu" "B.Mask" "B.Paste")
			(net 584 "/M.2/PCIe_{C5x4}.CLK+")
			(pinfunction "REFCLK_N")
			(pintype "input")
		)
		(pad "54" smd rect
			(at 3.999 -3.773 270)
			(size 0.3 1.55)
			(layers "B.Cu" "B.Mask" "B.Paste")
			(net 826 "/M.2/~{PEWAKE_M}")
			(pinfunction "~{PEWAKE}")
			(pintype "input")
		)
		(pad "55" smd rect
			(at 4.248 3.775 270)
			(size 0.3 1.55)
			(layers "B.Cu" "B.Mask" "B.Paste")
			(net 592 "/M.2/PCIe_{C5x4}.CLK-")
			(pinfunction "REFCLK_P")
			(pintype "input")
		)
		(pad "56" smd rect
			(at 4.498 -3.773 270)
			(size 0.3 1.55)
			(layers "B.Cu" "B.Mask" "B.Paste")
			(net 239 "unconnected-(J13-NC-Pad56)")
			(pinfunction "NC")
			(pintype "no_connect")
		)
		(pad "57" smd rect
			(at 4.748 3.775 270)
			(size 0.3 1.55)
			(layers "B.Cu" "B.Mask" "B.Paste")
			(net 1 "GND")
			(pinfunction "GND")
			(pintype "passive")
		)
		(pad "58" smd rect
			(at 4.998 -3.773 270)
			(size 0.3 1.55)
			(layers "B.Cu" "B.Mask" "B.Paste")
			(net 220 "unconnected-(J13-NC-Pad58)")
			(pinfunction "NC")
			(pintype "no_connect")
		)
		(pad "67" smd rect
			(at 7.248 3.775 270)
			(size 0.3 1.55)
			(layers "B.Cu" "B.Mask" "B.Paste")
			(net 231 "unconnected-(J13-NC-Pad67)")
			(pinfunction "NC")
			(pintype "no_connect")
		)
		(pad "68" smd rect
			(at 7.498 -3.773 270)
			(size 0.3 1.55)
			(layers "B.Cu" "B.Mask" "B.Paste")
			(net 224 "/M.2/M2_M_SUSCLK")
			(pinfunction "SUSCLK")
			(pintype "input")
		)
		(pad "69" smd rect
			(at 7.748 3.775 270)
			(size 0.3 1.55)
			(layers "B.Cu" "B.Mask" "B.Paste")
			(net 221 "unconnected-(J13-NC-Pad69)")
			(pinfunction "NC")
			(pintype "no_connect")
		)
		(pad "70" smd rect
			(at 7.998 -3.773 270)
			(size 0.3 1.55)
			(layers "B.Cu" "B.Mask" "B.Paste")
			(net 14 "/M.2/3V3_M2")
			(pinfunction "3V3")
			(pintype "passive")
		)
		(pad "71" smd rect
			(at 8.247 3.775 270)
			(size 0.3 1.55)
			(layers "B.Cu" "B.Mask" "B.Paste")
			(net 1 "GND")
			(pinfunction "GND")
			(pintype "passive")
		)
		(pad "72" smd rect
			(at 8.497 -3.773 270)
			(size 0.3 1.55)
			(layers "B.Cu" "B.Mask" "B.Paste")
			(net 14 "/M.2/3V3_M2")
			(pinfunction "3V3")
			(pintype "passive")
		)
		(pad "73" smd rect
			(at 8.747 3.775 270)
			(size 0.3 1.55)
			(layers "B.Cu" "B.Mask" "B.Paste")
			(net 1 "GND")
			(pinfunction "GND")
			(pintype "passive")
		)
		(pad "74" smd rect
			(at 8.997 -3.773 270)
			(size 0.3 1.55)
			(layers "B.Cu" "B.Mask" "B.Paste")
			(net 14 "/M.2/3V3_M2")
			(pinfunction "3V3")
			(pintype "passive")
		)
		(pad "75" smd rect
			(at 9.247 3.775 270)
			(size 0.3 1.55)
			(layers "B.Cu" "B.Mask" "B.Paste")
			(net 1 "GND")
			(pinfunction "GND")
			(pintype "passive")
		)
		(pad "MP1" smd rect
			(at -10.352 3 270)
			(size 1.2 2.75)
			(layers "B.Cu" "B.Mask" "B.Paste")
			(net 1 "GND")
			(pinfunction "MP")
			(pintype "passive")
		)
		(pad "MP2" smd rect
			(at 10.349 3 270)
			(size 1.2 2.75)
			(layers "B.Cu" "B.Mask" "B.Paste")
			(net 1 "GND")
			(pinfunction "MP")
			(pintype "passive")
		)
	)
	(footprint "antmicro-footprints:R_0402_1005Metric"
		(layer "B.Cu")
		(at 217.04 109.48)
		(descr "Resistor SMD 0402")
		(tags "resistor SMD 0402")
		(property "Reference" "R303"
			(at -1.34 -1.38 0)
			(layer "B.SilkS")
			(effects
				(font
					(size 0.7 0.7)
					(thickness 0.15)
				)
				(justify right top mirror)
			)
		)
		(property "Value" "R_10k_0402"
			(at -1.011843 -1.772047 0)
			(layer "B.Fab")
			(effects
				(font
					(size 0.7 0.7)
					(thickness 0.15)
				)
				(justify right top mirror)
			)
		)
		(property "Datasheet" "https://www.bourns.com/docs/product-datasheets/cr.pdf"
			(at 0 0 0)
			(layer "B.Fab")
			(hide yes)
			(effects
				(font
					(size 1.27 1.27)
					(thickness 0.15)
				)
				(justify mirror)
			)
		)
		(property "Description" "SMD Chip Resistor, 10 kohm, ± 1%, 62.5 mW, 0402 [1005 Metric], Thick Film, General Purpose"
			(at 0 0 0)
			(layer "B.Fab")
			(hide yes)
			(effects
				(font
					(size 1.27 1.27)
					(thickness 0.15)
				)
				(justify mirror)
			)
		)
		(property "MPN" "CR0402-FX-1002GLF"
			(at 0 0 180)
			(unlocked yes)
			(layer "B.Fab")
			(hide yes)
			(effects
				(font
					(size 1 1)
					(thickness 0.15)
				)
				(justify mirror)
			)
		)
		(property "Manufacturer" "Bourns"
			(at 0 0 180)
			(unlocked yes)
			(layer "B.Fab")
			(hide yes)
			(effects
				(font
					(size 1 1)
					(thickness 0.15)
				)
				(justify mirror)
			)
		)
		(property "License" "Apache-2.0"
			(at 0 0 180)
			(unlocked yes)
			(layer "B.Fab")
			(hide yes)
			(effects
				(font
					(size 1 1)
					(thickness 0.15)
				)
				(justify mirror)
			)
		)
		(property "Author" "Antmicro"
			(at 0 0 180)
			(unlocked yes)
			(layer "B.Fab")
			(hide yes)
			(effects
				(font
					(size 1 1)
					(thickness 0.15)
				)
				(justify mirror)
			)
		)
		(property "Val" "10k"
			(at 0 0 180)
			(unlocked yes)
			(layer "B.Fab")
			(hide yes)
			(effects
				(font
					(size 1 1)
					(thickness 0.15)
				)
				(justify mirror)
			)
		)
		(property "Tolerance" "1%"
			(at 0 0 180)
			(unlocked yes)
			(layer "B.Fab")
			(hide yes)
			(effects
				(font
					(size 1 1)
					(thickness 0.15)
				)
				(justify mirror)
			)
		)
		(sheetname "/USB Hub/")
		(sheetfile "usb_hub.kicad_sch")
		(attr smd)
		(fp_rect
			(start -0.925 0.47)
			(end 0.925 -0.47)
			(stroke
				(width 0.05)
				(type default)
			)
			(fill no)
			(layer "B.CrtYd")
		)
		(fp_rect
			(start -0.5 0.25)
			(end 0.5 -0.25)
			(stroke
				(width 0.15)
				(type solid)
			)
			(fill no)
			(layer "B.Fab")
		)
		(fp_text user "License: Apache-2.0"
			(at -0.95 -5.169 0)
			(layer "B.Fab")
			(effects
				(font
					(size 0.7 0.7)
					(thickness 0.15)
				)
				(justify right top mirror)
			)
		)
		(fp_text user "${REFERENCE}"
			(at -0.95 -3.168 0)
			(layer "B.Fab")
			(effects
				(font
					(size 0.7 0.7)
					(thickness 0.15)
				)
				(justify right top mirror)
			)
		)
		(fp_text user "Author: Antmicro"
			(at -0.95 -4.169 0)
			(layer "B.Fab")
			(effects
				(font
					(size 0.7 0.7)
					(thickness 0.15)
				)
				(justify right top mirror)
			)
		)
		(pad "1" smd roundrect
			(at -0.48 0)
			(size 0.59 0.64)
			(layers "B.Cu" "B.Mask" "B.Paste")
			(roundrect_rratio 0.25)
			(net 5 "+5V")
			(pintype "passive")
		)
		(pad "2" smd roundrect
			(at 0.48 0)
			(size 0.59 0.64)
			(layers "B.Cu" "B.Mask" "B.Paste")
			(roundrect_rratio 0.25)
			(net 1331 "Net-(Q26-D1)")
			(pintype "passive")
		)
	)
	(footprint "antmicro-footprints:TP_SMD_0.75mm"
		(layer "B.Cu")
		(at 185.39 58 180)
		(property "Reference" "TP128"
			(at -0.45 4.02 270)
			(layer "B.SilkS")
			(effects
				(font
					(size 0.7 0.7)
					(thickness 0.15)
				)
				(justify left bottom mirror)
			)
		)
		(property "Value" "TP_0.75mm_SMD"
			(at 0 -1.2 0)
			(layer "B.Fab")
			(effects
				(font
					(size 0.7 0.7)
					(thickness 0.15)
				)
				(justify left bottom mirror)
			)
		)
		(property "Description" "SMT test point"
			(at 0 0 0)
			(layer "B.Fab")
			(hide yes)
			(effects
				(font
					(size 1.27 1.27)
					(thickness 0.15)
				)
				(justify mirror)
			)
		)
		(property "MPN" ""
			(at 0 0 0)
			(unlocked yes)
			(layer "B.Fab")
			(hide yes)
			(effects
				(font
					(size 1 1)
					(thickness 0.15)
				)
				(justify mirror)
			)
		)
		(property "Manufacturer" ""
			(at 0 0 0)
			(unlocked yes)
			(layer "B.Fab")
			(hide yes)
			(effects
				(font
					(size 1 1)
					(thickness 0.15)
				)
				(justify mirror)
			)
		)
		(property "Author" "Antmicro"
			(at 0 0 0)
			(unlocked yes)
			(layer "B.Fab")
			(hide yes)
			(effects
				(font
					(size 1 1)
					(thickness 0.15)
				)
				(justify mirror)
			)
		)
		(property "License" "Apache-2.0"
			(at 0 0 0)
			(unlocked yes)
			(layer "B.Fab")
			(hide yes)
			(effects
				(font
					(size 1 1)
					(thickness 0.15)
				)
				(justify mirror)
			)
		)
		(sheetname "/Power/")
		(sheetfile "power.kicad_sch")
		(attr exclude_from_pos_files exclude_from_bom)
		(fp_circle
			(center 0 0)
			(end 0.475 0)
			(stroke
				(width 0.05)
				(type default)
			)
			(fill no)
			(layer "B.CrtYd")
		)
		(fp_text user "Author: Antmicro"
			(at -0.4 -3.901 0)
			(layer "B.Fab")
			(effects
				(font
					(size 0.7 0.7)
					(thickness 0.15)
				)
				(justify left bottom mirror)
			)
		)
		(fp_text user "${REFERENCE}"
			(at -0.4 -2.7 0)
			(layer "B.Fab")
			(effects
				(font
					(size 0.7 0.7)
					(thickness 0.15)
				)
				(justify left bottom mirror)
			)
		)
		(fp_text user "License: Apache-2.0"
			(at -0.4 -5.101 0)
			(layer "B.Fab")
			(effects
				(font
					(size 0.7 0.7)
					(thickness 0.15)
				)
				(justify left bottom mirror)
			)
		)
		(pad "1" smd circle
			(at 0 0 180)
			(size 0.75 0.75)
			(layers "B.Cu" "B.Mask")
			(net 13 "VCC")
			(pinfunction "1")
			(pintype "passive")
		)
	)
	(footprint "antmicro-footprints:R_0402_1005Metric"
		(layer "B.Cu")
		(at 178.3 67.4 180)
		(descr "Resistor SMD 0402")
		(tags "resistor SMD 0402")
		(property "Reference" "R34"
			(at -1.1 -1.4 0)
			(layer "B.SilkS")
			(effects
				(font
					(size 0.7 0.7)
					(thickness 0.15)
				)
				(justify left bottom mirror)
			)
		)
		(property "Value" "R_49k9_0402"
			(at -1.011843 -1.772047 0)
			(layer "B.Fab")
			(effects
				(font
					(size 0.7 0.7)
					(thickness 0.15)
				)
				(justify left bottom mirror)
			)
		)
		(property "Datasheet" "https://www.bourns.com/docs/product-datasheets/cr.pdf"
			(at 0 0 0)
			(layer "B.Fab")
			(hide yes)
			(effects
				(font
					(size 1.27 1.27)
					(thickness 0.15)
				)
				(justify mirror)
			)
		)
		(property "Description" "SMD Chip Resistor, 49.9 kohm, ± 1%, 63 mW, 0402 [1005 Metric], Thick Film, General Purpose"
			(at 0 0 0)
			(layer "B.Fab")
			(hide yes)
			(effects
				(font
					(size 1.27 1.27)
					(thickness 0.15)
				)
				(justify mirror)
			)
		)
		(property "MPN" "CR0402-FX-4992GLF"
			(at 0 0 0)
			(unlocked yes)
			(layer "B.Fab")
			(hide yes)
			(effects
				(font
					(size 1 1)
					(thickness 0.15)
				)
				(justify mirror)
			)
		)
		(property "Manufacturer" "Bourns"
			(at 0 0 0)
			(unlocked yes)
			(layer "B.Fab")
			(hide yes)
			(effects
				(font
					(size 1 1)
					(thickness 0.15)
				)
				(justify mirror)
			)
		)
		(property "License" "Apache-2.0"
			(at 0 0 0)
			(unlocked yes)
			(layer "B.Fab")
			(hide yes)
			(effects
				(font
					(size 1 1)
					(thickness 0.15)
				)
				(justify mirror)
			)
		)
		(property "Author" "Antmicro"
			(at 0 0 0)
			(unlocked yes)
			(layer "B.Fab")
			(hide yes)
			(effects
				(font
					(size 1 1)
					(thickness 0.15)
				)
				(justify mirror)
			)
		)
		(property "Val" "49k9"
			(at 0 0 0)
			(unlocked yes)
			(layer "B.Fab")
			(hide yes)
			(effects
				(font
					(size 1 1)
					(thickness 0.15)
				)
				(justify mirror)
			)
		)
		(property "Tolerance" "1%"
			(at 0 0 0)
			(unlocked yes)
			(layer "B.Fab")
			(hide yes)
			(effects
				(font
					(size 1 1)
					(thickness 0.15)
				)
				(justify mirror)
			)
		)
		(component_classes
			(class "DCDC_20V")
		)
		(sheetname "/DCDC/")
		(sheetfile "dcdc.kicad_sch")
		(attr smd exclude_from_pos_files exclude_from_bom dnp)
		(fp_rect
			(start -0.925 0.47)
			(end 0.925 -0.47)
			(stroke
				(width 0.05)
				(type default)
			)
			(fill no)
			(layer "B.CrtYd")
		)
		(fp_rect
			(start -0.5 0.25)
			(end 0.5 -0.25)
			(stroke
				(width 0.15)
				(type solid)
			)
			(fill no)
			(layer "B.Fab")
		)
		(fp_text user "${REFERENCE}"
			(at -0.95 -3.168 0)
			(layer "B.Fab")
			(effects
				(font
					(size 0.7 0.7)
					(thickness 0.15)
				)
				(justify left bottom mirror)
			)
		)
		(fp_text user "License: Apache-2.0"
			(at -0.95 -5.169 0)
			(layer "B.Fab")
			(effects
				(font
					(size 0.7 0.7)
					(thickness 0.15)
				)
				(justify left bottom mirror)
			)
		)
		(fp_text user "Author: Antmicro"
			(at -0.95 -4.169 0)
			(layer "B.Fab")
			(effects
				(font
					(size 0.7 0.7)
					(thickness 0.15)
				)
				(justify left bottom mirror)
			)
		)
		(pad "1" smd roundrect
			(at -0.48 0 180)
			(size 0.59 0.64)
			(layers "B.Cu" "B.Mask" "B.Paste")
			(roundrect_rratio 0.25)
			(net 1211 "/DCDC/20V_EN")
			(pintype "passive")
		)
		(pad "2" smd roundrect
			(at 0.48 0 180)
			(size 0.59 0.64)
			(layers "B.Cu" "B.Mask" "B.Paste")
			(roundrect_rratio 0.25)
			(net 4 "+3V3_AON")
			(pintype "passive")
		)
	)
	(footprint "antmicro-footprints:R_0402_1005Metric"
		(layer "B.Cu")
		(at 205.4 105.800001 180)
		(descr "Resistor SMD 0402")
		(tags "resistor SMD 0402")
		(property "Reference" "R279"
			(at -6.5 -0.399999 0)
			(layer "B.SilkS")
			(effects
				(font
					(size 0.7 0.7)
					(thickness 0.15)
				)
				(justify left bottom mirror)
			)
		)
		(property "Value" "R_200k_0402"
			(at -1.011843 -1.772046 0)
			(layer "B.Fab")
			(effects
				(font
					(size 0.7 0.7)
					(thickness 0.15)
				)
				(justify left bottom mirror)
			)
		)
		(property "Datasheet" "https://www.bourns.com/docs/product-datasheets/cr.pdf"
			(at 0 0 0)
			(layer "B.Fab")
			(hide yes)
			(effects
				(font
					(size 1.27 1.27)
					(thickness 0.15)
				)
				(justify mirror)
			)
		)
		(property "Description" "SMD Chip Resistor, 200 kohm, ± 1%, 62.5 mW, 0402 [1005 Metric], Thick Film, General Purpose"
			(at 0 0 0)
			(layer "B.Fab")
			(hide yes)
			(effects
				(font
					(size 1.27 1.27)
					(thickness 0.15)
				)
				(justify mirror)
			)
		)
		(property "Manufacturer" "Bourns"
			(at 0 0 0)
			(unlocked yes)
			(layer "B.Fab")
			(hide yes)
			(effects
				(font
					(size 1 1)
					(thickness 0.15)
				)
				(justify mirror)
			)
		)
		(property "MPN" "CR0402-FX-2003GLF"
			(at 0 0 0)
			(unlocked yes)
			(layer "B.Fab")
			(hide yes)
			(effects
				(font
					(size 1 1)
					(thickness 0.15)
				)
				(justify mirror)
			)
		)
		(property "Val" "200k"
			(at 0 0 0)
			(unlocked yes)
			(layer "B.Fab")
			(hide yes)
			(effects
				(font
					(size 1 1)
					(thickness 0.15)
				)
				(justify mirror)
			)
		)
		(property "License" "Apache-2.0"
			(at 0 0 0)
			(unlocked yes)
			(layer "B.Fab")
			(hide yes)
			(effects
				(font
					(size 1 1)
					(thickness 0.15)
				)
				(justify mirror)
			)
		)
		(property "Author" "Antmicro"
			(at 0 0 0)
			(unlocked yes)
			(layer "B.Fab")
			(hide yes)
			(effects
				(font
					(size 1 1)
					(thickness 0.15)
				)
				(justify mirror)
			)
		)
		(property "Tolerance" "1%"
			(at 0 0 0)
			(unlocked yes)
			(layer "B.Fab")
			(hide yes)
			(effects
				(font
					(size 1 1)
					(thickness 0.15)
				)
				(justify mirror)
			)
		)
		(sheetname "/Recovery USB/")
		(sheetfile "recovery_usb.kicad_sch")
		(attr smd)
		(fp_poly
			(pts
				(xy -0.925 0.47) (xy -0.925 -0.47) (xy 0.925 -0.47) (xy 0.925 0.47)
			)
			(stroke
				(width 0.05)
				(type default)
			)
			(fill no)
			(layer "B.CrtYd")
		)
		(fp_poly
			(pts
				(xy -0.5 0.25) (xy -0.5 -0.25) (xy 0.5 -0.25) (xy 0.5 0.25)
			)
			(stroke
				(width 0.15)
				(type solid)
			)
			(fill no)
			(layer "B.Fab")
		)
		(fp_text user "License: Apache-2.0"
			(at -0.949999 -5.169 0)
			(layer "B.Fab")
			(effects
				(font
					(size 0.7 0.7)
					(thickness 0.15)
				)
				(justify left bottom mirror)
			)
		)
		(fp_text user "Author: Antmicro"
			(at -0.95 -4.169 0)
			(layer "B.Fab")
			(effects
				(font
					(size 0.7 0.7)
					(thickness 0.15)
				)
				(justify left bottom mirror)
			)
		)
		(fp_text user "${REFERENCE}"
			(at -0.95 -3.168 0)
			(layer "B.Fab")
			(effects
				(font
					(size 0.7 0.7)
					(thickness 0.15)
				)
				(justify left bottom mirror)
			)
		)
		(pad "1" smd roundrect
			(at -0.48 0 180)
			(size 0.59 0.64)
			(layers "B.Cu" "B.Mask" "B.Paste")
			(roundrect_rratio 0.25)
			(net 2 "+3V3")
			(pintype "passive")
		)
		(pad "2" smd roundrect
			(at 0.48 0 180)
			(size 0.59 0.64)
			(layers "B.Cu" "B.Mask" "B.Paste")
			(roundrect_rratio 0.25)
			(net 1024 "/Recovery USB/USBC2_I2C_SDA")
			(pintype "passive")
		)
	)
	(footprint "antmicro-footprints:R_0402_1005Metric"
		(layer "B.Cu")
		(at 199.6 70.6 -90)
		(descr "Resistor SMD 0402")
		(tags "resistor SMD 0402")
		(property "Reference" "R111"
			(at -1.2 -1.5 90)
			(layer "B.SilkS")
			(effects
				(font
					(size 0.7 0.7)
					(thickness 0.15)
				)
				(justify left bottom mirror)
			)
		)
		(property "Value" "R_0R_0402"
			(at -1.011843 -1.772046 90)
			(layer "B.Fab")
			(effects
				(font
					(size 0.7 0.7)
					(thickness 0.15)
				)
				(justify left bottom mirror)
			)
		)
		(property "Datasheet" "https://industrial.panasonic.com/cdbs/www-data/pdf/RDA0000/AOA0000C301.pdf"
			(at 0 0 90)
			(layer "B.Fab")
			(hide yes)
			(effects
				(font
					(size 1.27 1.27)
					(thickness 0.15)
				)
				(justify mirror)
			)
		)
		(property "Description" "SMD Chip Resistor, Jumper, 0 ohm, 100 mW, 0402 [1005 Metric], Thick Film, General Purpose"
			(at 0 0 90)
			(layer "B.Fab")
			(hide yes)
			(effects
				(font
					(size 1.27 1.27)
					(thickness 0.15)
				)
				(justify mirror)
			)
		)
		(property "Manufacturer" "Panasonic"
			(at 0 0 90)
			(unlocked yes)
			(layer "B.Fab")
			(hide yes)
			(effects
				(font
					(size 1 1)
					(thickness 0.15)
				)
				(justify mirror)
			)
		)
		(property "MPN" "ERJ2GE0R00X"
			(at 0 0 90)
			(unlocked yes)
			(layer "B.Fab")
			(hide yes)
			(effects
				(font
					(size 1 1)
					(thickness 0.15)
				)
				(justify mirror)
			)
		)
		(property "Val" "0R"
			(at 0 0 90)
			(unlocked yes)
			(layer "B.Fab")
			(hide yes)
			(effects
				(font
					(size 1 1)
					(thickness 0.15)
				)
				(justify mirror)
			)
		)
		(property "License" "Apache-2.0"
			(at 0 0 90)
			(unlocked yes)
			(layer "B.Fab")
			(hide yes)
			(effects
				(font
					(size 1 1)
					(thickness 0.15)
				)
				(justify mirror)
			)
		)
		(property "Author" "Antmicro"
			(at 0 0 90)
			(unlocked yes)
			(layer "B.Fab")
			(hide yes)
			(effects
				(font
					(size 1 1)
					(thickness 0.15)
				)
				(justify mirror)
			)
		)
		(property "Tolerance" "~"
			(at 0 0 90)
			(unlocked yes)
			(layer "B.Fab")
			(hide yes)
			(effects
				(font
					(size 1 1)
					(thickness 0.15)
				)
				(justify mirror)
			)
		)
		(property "Current" "1A"
			(at 0 0 90)
			(unlocked yes)
			(layer "B.Fab")
			(hide yes)
			(effects
				(font
					(size 1 1)
					(thickness 0.15)
				)
				(justify mirror)
			)
		)
		(sheetname "/USB Debug, PD/")
		(sheetfile "usb_debug_pd.kicad_sch")
		(attr smd)
		(fp_poly
			(pts
				(xy -0.925 0.47) (xy 0.925 0.47) (xy 0.925 -0.47) (xy -0.925 -0.47)
			)
			(stroke
				(width 0.05)
				(type default)
			)
			(fill no)
			(layer "B.CrtYd")
		)
		(fp_poly
			(pts
				(xy -0.5 0.25) (xy 0.5 0.25) (xy 0.5 -0.25) (xy -0.5 -0.25)
			)
			(stroke
				(width 0.15)
				(type solid)
			)
			(fill no)
			(layer "B.Fab")
		)
		(fp_text user "Author: Antmicro"
			(at -0.95 -4.169 90)
			(layer "B.Fab")
			(effects
				(font
					(size 0.7 0.7)
					(thickness 0.15)
				)
				(justify left bottom mirror)
			)
		)
		(fp_text user "License: Apache-2.0"
			(at -0.949999 -5.169 90)
			(layer "B.Fab")
			(effects
				(font
					(size 0.7 0.7)
					(thickness 0.15)
				)
				(justify left bottom mirror)
			)
		)
		(fp_text user "${REFERENCE}"
			(at -0.95 -3.168 90)
			(layer "B.Fab")
			(effects
				(font
					(size 0.7 0.7)
					(thickness 0.15)
				)
				(justify left bottom mirror)
			)
		)
		(pad "1" smd roundrect
			(at -0.48 0 270)
			(size 0.59 0.64)
			(layers "B.Cu" "B.Mask" "B.Paste")
			(roundrect_rratio 0.25)
			(net 853 "/I2C_{SYS}.SCL")
			(pintype "passive")
		)
		(pad "2" smd roundrect
			(at 0.48 0 270)
			(size 0.59 0.64)
			(layers "B.Cu" "B.Mask" "B.Paste")
			(roundrect_rratio 0.25)
			(net 945 "/USB Debug, PD/DEBUG_SCL")
			(pintype "passive")
		)
	)
	(footprint "antmicro-footprints:SOD-523"
		(layer "B.Cu")
		(at 230.069 129.6 180)
		(property "Reference" "D48"
			(at 0.999 -0.4 0)
			(layer "B.SilkS")
			(effects
				(font
					(size 0.7 0.7)
					(thickness 0.15)
				)
				(justify left bottom mirror)
			)
		)
		(property "Value" "PESD5Z5.0F"
			(at 0 -1.499 0)
			(layer "B.Fab")
			(effects
				(font
					(size 0.7 0.7)
					(thickness 0.15)
				)
				(justify left bottom mirror)
			)
		)
		(property "Datasheet" "https://assets.nexperia.com/documents/data-sheet/PESD5Z5_0.pdf"
			(at 0 0 0)
			(layer "B.Fab")
			(hide yes)
			(effects
				(font
					(size 1.27 1.27)
					(thickness 0.15)
				)
				(justify mirror)
			)
		)
		(property "Description" "Unidirectional TVS, 30 kV,  SOD-523, 5 V, 89 pF"
			(at 0 0 0)
			(layer "B.Fab")
			(hide yes)
			(effects
				(font
					(size 1.27 1.27)
					(thickness 0.15)
				)
				(justify mirror)
			)
		)
		(property "Manufacturer" "Nexperia"
			(at 0 0 180)
			(unlocked yes)
			(layer "B.Fab")
			(hide yes)
			(effects
				(font
					(size 1 1)
					(thickness 0.15)
				)
				(justify mirror)
			)
		)
		(property "MPN" "PESD5Z5.0F"
			(at 0 0 180)
			(unlocked yes)
			(layer "B.Fab")
			(hide yes)
			(effects
				(font
					(size 1 1)
					(thickness 0.15)
				)
				(justify mirror)
			)
		)
		(property "Author" "Antmicro"
			(at 0 0 180)
			(unlocked yes)
			(layer "B.Fab")
			(hide yes)
			(effects
				(font
					(size 1 1)
					(thickness 0.15)
				)
				(justify mirror)
			)
		)
		(property "License" "Apache-2.0"
			(at 0 0 180)
			(unlocked yes)
			(layer "B.Fab")
			(hide yes)
			(effects
				(font
					(size 1 1)
					(thickness 0.15)
				)
				(justify mirror)
			)
		)
		(sheetname "/USB Hub/")
		(sheetfile "usb_hub.kicad_sch")
		(attr smd)
		(fp_line
			(start -0.35 0.5)
			(end -0.35 -0.5)
			(stroke
				(width 0.15)
				(type solid)
			)
			(layer "B.SilkS")
		)
		(fp_rect
			(start -1 0.6)
			(end 1 -0.6)
			(stroke
				(width 0.05)
				(type solid)
			)
			(fill no)
			(layer "B.CrtYd")
		)
		(fp_line
			(start 0.65 0.425)
			(end 0.65 -0.423)
			(stroke
				(width 0.15)
				(type solid)
			)
			(layer "B.Fab")
		)
		(fp_line
			(start -0.35 0.4)
			(end -0.35 -0.4)
			(stroke
				(width 0.15)
				(type solid)
			)
			(layer "B.Fab")
		)
		(fp_line
			(start -0.652 0.425)
			(end 0.65 0.425)
			(stroke
				(width 0.15)
				(type solid)
			)
			(layer "B.Fab")
		)
		(fp_line
			(start -0.652 -0.423)
			(end 0.65 -0.423)
			(stroke
				(width 0.15)
				(type solid)
			)
			(layer "B.Fab")
		)
		(fp_line
			(start -0.652 -0.423)
			(end -0.652 0.425)
			(stroke
				(width 0.15)
				(type solid)
			)
			(layer "B.Fab")
		)
		(fp_text user "Author: Antmicro"
			(at -1.276 -4.7 0)
			(layer "B.Fab")
			(effects
				(font
					(size 0.7 0.7)
					(thickness 0.15)
				)
				(justify left bottom mirror)
			)
		)
		(fp_text user "License: Apache-2.0"
			(at -1.276 -5.9 0)
			(layer "B.Fab")
			(effects
				(font
					(size 0.7 0.7)
					(thickness 0.15)
				)
				(justify left bottom mirror)
			)
		)
		(fp_text user "${REFERENCE}"
			(at -1.276 -3.499 0)
			(layer "B.Fab")
			(effects
				(font
					(size 0.7 0.7)
					(thickness 0.15)
				)
				(justify left bottom mirror)
			)
		)
		(pad "1" smd roundrect
			(at -0.701 0 180)
			(size 0.5 0.6)
			(layers "B.Cu" "B.Mask" "B.Paste")
			(roundrect_rratio 0.25)
			(net 115 "/USB Hub/USBC4_VBUS")
			(pinfunction "C")
			(pintype "passive")
		)
		(pad "2" smd roundrect
			(at 0.699 0 180)
			(size 0.5 0.6)
			(layers "B.Cu" "B.Mask" "B.Paste")
			(roundrect_rratio 0.25)
			(net 1 "GND")
			(pinfunction "A")
			(pintype "passive")
		)
	)
	(footprint "antmicro-footprints:C_0402_1005Metric"
		(layer "B.Cu")
		(at 93.680001 105.5 -90)
		(descr "Capacitor SMD 0402")
		(tags "capacitor SMD 0402")
		(property "Reference" "C324"
			(at 0.9 -0.4 90)
			(layer "B.SilkS")
			(effects
				(font
					(size 0.7 0.7)
					(thickness 0.15)
				)
				(justify left bottom mirror)
			)
		)
		(property "Value" "C_100n_0402"
			(at -1.022927 -2.155213 90)
			(layer "B.Fab")
			(effects
				(font
					(size 0.7 0.7)
					(thickness 0.15)
				)
				(justify left bottom mirror)
			)
		)
		(property "Datasheet" "https://www.murata.com/products/productdetail?partno=GRM155R61H104KE14%23"
			(at 0 0 90)
			(layer "B.Fab")
			(hide yes)
			(effects
				(font
					(size 1.27 1.27)
					(thickness 0.15)
				)
				(justify mirror)
			)
		)
		(property "Description" "SMD Multilayer Ceramic Capacitor, 0.1 µF, 50 V, 0402 [1005 Metric], ± 10%, X5R, GRM Series"
			(at 0 0 90)
			(layer "B.Fab")
			(hide yes)
			(effects
				(font
					(size 1.27 1.27)
					(thickness 0.15)
				)
				(justify mirror)
			)
		)
		(property "Manufacturer" "Murata"
			(at 0 0 90)
			(unlocked yes)
			(layer "B.Fab")
			(hide yes)
			(effects
				(font
					(size 1 1)
					(thickness 0.15)
				)
				(justify mirror)
			)
		)
		(property "MPN" "GRM155R61H104KE14D"
			(at 0 0 90)
			(unlocked yes)
			(layer "B.Fab")
			(hide yes)
			(effects
				(font
					(size 1 1)
					(thickness 0.15)
				)
				(justify mirror)
			)
		)
		(property "Val" "100n"
			(at 0 0 90)
			(unlocked yes)
			(layer "B.Fab")
			(hide yes)
			(effects
				(font
					(size 1 1)
					(thickness 0.15)
				)
				(justify mirror)
			)
		)
		(property "License" "Apache-2.0"
			(at 0 0 90)
			(unlocked yes)
			(layer "B.Fab")
			(hide yes)
			(effects
				(font
					(size 1 1)
					(thickness 0.15)
				)
				(justify mirror)
			)
		)
		(property "Author" "Antmicro"
			(at 0 0 90)
			(unlocked yes)
			(layer "B.Fab")
			(hide yes)
			(effects
				(font
					(size 1 1)
					(thickness 0.15)
				)
				(justify mirror)
			)
		)
		(property "Voltage" "50V"
			(at 0 0 90)
			(unlocked yes)
			(layer "B.Fab")
			(hide yes)
			(effects
				(font
					(size 1 1)
					(thickness 0.15)
				)
				(justify mirror)
			)
		)
		(property "Dielectric" "X5R"
			(at 0 0 90)
			(unlocked yes)
			(layer "B.Fab")
			(hide yes)
			(effects
				(font
					(size 1 1)
					(thickness 0.15)
				)
				(justify mirror)
			)
		)
		(sheetname "/SoM_IO2/")
		(sheetfile "som_io2.kicad_sch")
		(attr smd)
		(fp_poly
			(pts
				(xy -0.925 0.47) (xy 0.925 0.47) (xy 0.925 -0.47) (xy -0.925 -0.47)
			)
			(stroke
				(width 0.05)
				(type default)
			)
			(fill no)
			(layer "B.CrtYd")
		)
		(fp_line
			(start -0.494 0.25)
			(end 0.504 0.25)
			(stroke
				(width 0.15)
				(type solid)
			)
			(layer "B.Fab")
		)
		(fp_line
			(start 0.504 0.25)
			(end 0.504 -0.248)
			(stroke
				(width 0.15)
				(type solid)
			)
			(layer "B.Fab")
		)
		(fp_line
			(start -0.494 -0.248)
			(end -0.494 0.25)
			(stroke
				(width 0.15)
				(type solid)
			)
			(layer "B.Fab")
		)
		(fp_line
			(start 0.504 -0.248)
			(end -0.494 -0.248)
			(stroke
				(width 0.15)
				(type solid)
			)
			(layer "B.Fab")
		)
		(fp_text user "License: Apache-2.0"
			(at -0.939 -5.799 90)
			(layer "B.Fab")
			(effects
				(font
					(size 0.7 0.7)
					(thickness 0.15)
				)
				(justify left bottom mirror)
			)
		)
		(fp_text user "Author: Antmicro"
			(at -0.939 -3.399 90)
			(layer "B.Fab")
			(effects
				(font
					(size 0.7 0.7)
					(thickness 0.15)
				)
				(justify left bottom mirror)
			)
		)
		(fp_text user "${REFERENCE}"
			(at -0.939 -4.599 90)
			(layer "B.Fab")
			(effects
				(font
					(size 0.7 0.7)
					(thickness 0.15)
				)
				(justify left bottom mirror)
			)
		)
		(pad "1" smd roundrect
			(at -0.48 0 270)
			(size 0.59 0.64)
			(layers "B.Cu" "B.Mask" "B.Paste")
			(roundrect_rratio 0.25)
			(net 707 "/Expansion connector/DP1.TX0+")
			(pintype "passive")
		)
		(pad "2" smd roundrect
			(at 0.48 0 270)
			(size 0.59 0.64)
			(layers "B.Cu" "B.Mask" "B.Paste")
			(roundrect_rratio 0.25)
			(net 1191 "/SoM_IO2/DP1.TX0_C+")
			(pintype "passive")
		)
	)
	(footprint "antmicro-footprints:R_0402_1005Metric"
		(layer "B.Cu")
		(at 200.8 126.2 180)
		(descr "Resistor SMD 0402")
		(tags "resistor SMD 0402")
		(property "Reference" "R327"
			(at -3.76 -0.358196 0)
			(layer "B.SilkS")
			(effects
				(font
					(size 0.7 0.7)
					(thickness 0.15)
				)
				(justify left bottom mirror)
			)
		)
		(property "Value" "R_100k_0402"
			(at -1.011843 -1.772046 0)
			(layer "B.Fab")
			(effects
				(font
					(size 0.7 0.7)
					(thickness 0.15)
				)
				(justify left bottom mirror)
			)
		)
		(property "Datasheet" "https://www.bourns.com/docs/product-datasheets/cr.pdf"
			(at 0 0 0)
			(layer "B.Fab")
			(hide yes)
			(effects
				(font
					(size 1.27 1.27)
					(thickness 0.15)
				)
				(justify mirror)
			)
		)
		(property "Description" "SMD Chip Resistor, 100 kohm, ± 1%, 62.5 mW, 0402 [1005 Metric], Thick Film, General Purpose"
			(at 0 0 0)
			(layer "B.Fab")
			(hide yes)
			(effects
				(font
					(size 1.27 1.27)
					(thickness 0.15)
				)
				(justify mirror)
			)
		)
		(property "MPN" "CR0402-FX-1003GLF"
			(at 0 0 0)
			(unlocked yes)
			(layer "B.Fab")
			(hide yes)
			(effects
				(font
					(size 1 1)
					(thickness 0.15)
				)
				(justify mirror)
			)
		)
		(property "Manufacturer" "Bourns"
			(at 0 0 0)
			(unlocked yes)
			(layer "B.Fab")
			(hide yes)
			(effects
				(font
					(size 1 1)
					(thickness 0.15)
				)
				(justify mirror)
			)
		)
		(property "License" "Apache-2.0"
			(at 0 0 0)
			(unlocked yes)
			(layer "B.Fab")
			(hide yes)
			(effects
				(font
					(size 1 1)
					(thickness 0.15)
				)
				(justify mirror)
			)
		)
		(property "Author" "Antmicro"
			(at 0 0 0)
			(unlocked yes)
			(layer "B.Fab")
			(hide yes)
			(effects
				(font
					(size 1 1)
					(thickness 0.15)
				)
				(justify mirror)
			)
		)
		(property "Val" "100k"
			(at 0 0 0)
			(unlocked yes)
			(layer "B.Fab")
			(hide yes)
			(effects
				(font
					(size 1 1)
					(thickness 0.15)
				)
				(justify mirror)
			)
		)
		(property "Tolerance" "1%"
			(at 0 0 0)
			(unlocked yes)
			(layer "B.Fab")
			(hide yes)
			(effects
				(font
					(size 1 1)
					(thickness 0.15)
				)
				(justify mirror)
			)
		)
		(sheetname "/USB Hub/")
		(sheetfile "usb_hub.kicad_sch")
		(attr smd)
		(fp_poly
			(pts
				(xy -0.925 0.47) (xy -0.925 -0.47) (xy 0.925 -0.47) (xy 0.925 0.47)
			)
			(stroke
				(width 0.05)
				(type default)
			)
			(fill no)
			(layer "B.CrtYd")
		)
		(fp_poly
			(pts
				(xy -0.5 0.25) (xy -0.5 -0.25) (xy 0.5 -0.25) (xy 0.5 0.25)
			)
			(stroke
				(width 0.15)
				(type solid)
			)
			(fill no)
			(layer "B.Fab")
		)
		(fp_text user "License: Apache-2.0"
			(at -0.949999 -5.169 0)
			(layer "B.Fab")
			(effects
				(font
					(size 0.7 0.7)
					(thickness 0.15)
				)
				(justify left bottom mirror)
			)
		)
		(fp_text user "${REFERENCE}"
			(at -0.95 -3.168 0)
			(layer "B.Fab")
			(effects
				(font
					(size 0.7 0.7)
					(thickness 0.15)
				)
				(justify left bottom mirror)
			)
		)
		(fp_text user "Author: Antmicro"
			(at -0.95 -4.169 0)
			(layer "B.Fab")
			(effects
				(font
					(size 0.7 0.7)
					(thickness 0.15)
				)
				(justify left bottom mirror)
			)
		)
		(pad "1" smd roundrect
			(at -0.48 0 180)
			(size 0.59 0.64)
			(layers "B.Cu" "B.Mask" "B.Paste")
			(roundrect_rratio 0.25)
			(net 1 "GND")
			(pintype "passive")
		)
		(pad "2" smd roundrect
			(at 0.48 0 180)
			(size 0.59 0.64)
			(layers "B.Cu" "B.Mask" "B.Paste")
			(roundrect_rratio 0.25)
			(net 922 "/USB Hub/HUB_SPI_D1")
			(pintype "passive")
		)
	)
	(footprint "antmicro-footprints:R_0402_1005Metric"
		(layer "B.Cu")
		(at 68.4 65.7 -90)
		(descr "Resistor SMD 0402")
		(tags "resistor SMD 0402")
		(property "Reference" "R394"
			(at 0.9 -0.5 90)
			(layer "B.SilkS")
			(effects
				(font
					(size 0.7 0.7)
					(thickness 0.15)
				)
				(justify left bottom mirror)
			)
		)
		(property "Value" "R_2k2_0402"
			(at -1.011843 -1.772047 90)
			(layer "B.Fab")
			(effects
				(font
					(size 0.7 0.7)
					(thickness 0.15)
				)
				(justify left bottom mirror)
			)
		)
		(property "Datasheet" "https://www.bourns.com/docs/product-datasheets/cr.pdf"
			(at 0 0 90)
			(layer "B.Fab")
			(hide yes)
			(effects
				(font
					(size 1.27 1.27)
					(thickness 0.15)
				)
				(justify mirror)
			)
		)
		(property "Description" "SMD Chip Resistor, 2.2 kohm, ± 1%, 62.5 mW, 0402 [1005 Metric], Thick Film, General Purpose"
			(at 0 0 90)
			(layer "B.Fab")
			(hide yes)
			(effects
				(font
					(size 1.27 1.27)
					(thickness 0.15)
				)
				(justify mirror)
			)
		)
		(property "MPN" "CR0402-FX-2201GLF"
			(at 0 0 90)
			(unlocked yes)
			(layer "B.Fab")
			(hide yes)
			(effects
				(font
					(size 1 1)
					(thickness 0.15)
				)
				(justify mirror)
			)
		)
		(property "Manufacturer" "Bourns"
			(at 0 0 90)
			(unlocked yes)
			(layer "B.Fab")
			(hide yes)
			(effects
				(font
					(size 1 1)
					(thickness 0.15)
				)
				(justify mirror)
			)
		)
		(property "License" "Apache-2.0"
			(at 0 0 90)
			(unlocked yes)
			(layer "B.Fab")
			(hide yes)
			(effects
				(font
					(size 1 1)
					(thickness 0.15)
				)
				(justify mirror)
			)
		)
		(property "Author" "Antmicro"
			(at 0 0 90)
			(unlocked yes)
			(layer "B.Fab")
			(hide yes)
			(effects
				(font
					(size 1 1)
					(thickness 0.15)
				)
				(justify mirror)
			)
		)
		(property "Val" "2k2"
			(at 0 0 90)
			(unlocked yes)
			(layer "B.Fab")
			(hide yes)
			(effects
				(font
					(size 1 1)
					(thickness 0.15)
				)
				(justify mirror)
			)
		)
		(property "Tolerance" "1%"
			(at 0 0 90)
			(unlocked yes)
			(layer "B.Fab")
			(hide yes)
			(effects
				(font
					(size 1 1)
					(thickness 0.15)
				)
				(justify mirror)
			)
		)
		(sheetname "/CSI/")
		(sheetfile "csi.kicad_sch")
		(attr smd)
		(fp_rect
			(start -0.925 0.47)
			(end 0.925 -0.47)
			(stroke
				(width 0.05)
				(type default)
			)
			(fill no)
			(layer "B.CrtYd")
		)
		(fp_rect
			(start -0.5 0.25)
			(end 0.5 -0.25)
			(stroke
				(width 0.15)
				(type solid)
			)
			(fill no)
			(layer "B.Fab")
		)
		(fp_text user "${REFERENCE}"
			(at -0.95 -3.168 90)
			(layer "B.Fab")
			(effects
				(font
					(size 0.7 0.7)
					(thickness 0.15)
				)
				(justify left bottom mirror)
			)
		)
		(fp_text user "License: Apache-2.0"
			(at -0.95 -5.169 90)
			(layer "B.Fab")
			(effects
				(font
					(size 0.7 0.7)
					(thickness 0.15)
				)
				(justify left bottom mirror)
			)
		)
		(fp_text user "Author: Antmicro"
			(at -0.95 -4.169 90)
			(layer "B.Fab")
			(effects
				(font
					(size 0.7 0.7)
					(thickness 0.15)
				)
				(justify left bottom mirror)
			)
		)
		(pad "1" smd roundrect
			(at -0.48 0 270)
			(size 0.59 0.64)
			(layers "B.Cu" "B.Mask" "B.Paste")
			(roundrect_rratio 0.25)
			(net 990 "/CSI/CSIB_I2C_VCC")
			(pintype "passive")
		)
		(pad "2" smd roundrect
			(at 0.48 0 270)
			(size 0.59 0.64)
			(layers "B.Cu" "B.Mask" "B.Paste")
			(roundrect_rratio 0.25)
			(net 992 "/CSI/SCL_CAM3")
			(pintype "passive")
		)
	)
	(footprint "antmicro-footprints:R_0402_1005Metric"
		(layer "B.Cu")
		(at 208.726 146 180)
		(descr "Resistor SMD 0402")
		(tags "resistor SMD 0402")
		(property "Reference" "R185"
			(at -3.8 -0.5 0)
			(layer "B.SilkS")
			(effects
				(font
					(size 0.7 0.7)
					(thickness 0.15)
				)
				(justify left bottom mirror)
			)
		)
		(property "Value" "R_0R_0402"
			(at -1.011843 -1.772046 0)
			(layer "B.Fab")
			(effects
				(font
					(size 0.7 0.7)
					(thickness 0.15)
				)
				(justify left bottom mirror)
			)
		)
		(property "Datasheet" "https://industrial.panasonic.com/cdbs/www-data/pdf/RDA0000/AOA0000C301.pdf"
			(at 0 0 0)
			(layer "B.Fab")
			(hide yes)
			(effects
				(font
					(size 1.27 1.27)
					(thickness 0.15)
				)
				(justify mirror)
			)
		)
		(property "Description" "SMD Chip Resistor, Jumper, 0 ohm, 100 mW, 0402 [1005 Metric], Thick Film, General Purpose"
			(at 0 0 0)
			(layer "B.Fab")
			(hide yes)
			(effects
				(font
					(size 1.27 1.27)
					(thickness 0.15)
				)
				(justify mirror)
			)
		)
		(property "MPN" "ERJ2GE0R00X"
			(at 0 0 0)
			(unlocked yes)
			(layer "B.Fab")
			(hide yes)
			(effects
				(font
					(size 1 1)
					(thickness 0.15)
				)
				(justify mirror)
			)
		)
		(property "Manufacturer" "Panasonic"
			(at 0 0 0)
			(unlocked yes)
			(layer "B.Fab")
			(hide yes)
			(effects
				(font
					(size 1 1)
					(thickness 0.15)
				)
				(justify mirror)
			)
		)
		(property "License" "Apache-2.0"
			(at 0 0 0)
			(unlocked yes)
			(layer "B.Fab")
			(hide yes)
			(effects
				(font
					(size 1 1)
					(thickness 0.15)
				)
				(justify mirror)
			)
		)
		(property "Author" "Antmicro"
			(at 0 0 0)
			(unlocked yes)
			(layer "B.Fab")
			(hide yes)
			(effects
				(font
					(size 1 1)
					(thickness 0.15)
				)
				(justify mirror)
			)
		)
		(property "Val" "0R"
			(at 0 0 0)
			(unlocked yes)
			(layer "B.Fab")
			(hide yes)
			(effects
				(font
					(size 1 1)
					(thickness 0.15)
				)
				(justify mirror)
			)
		)
		(property "Tolerance" "~"
			(at 0 0 0)
			(unlocked yes)
			(layer "B.Fab")
			(hide yes)
			(effects
				(font
					(size 1 1)
					(thickness 0.15)
				)
				(justify mirror)
			)
		)
		(property "Current" "1A"
			(at 0 0 0)
			(unlocked yes)
			(layer "B.Fab")
			(hide yes)
			(effects
				(font
					(size 1 1)
					(thickness 0.15)
				)
				(justify mirror)
			)
		)
		(sheetname "/SFP/")
		(sheetfile "sfp.kicad_sch")
		(attr smd)
		(fp_poly
			(pts
				(xy -0.925 0.47) (xy 0.925 0.47) (xy 0.925 -0.47) (xy -0.925 -0.47)
			)
			(stroke
				(width 0.05)
				(type default)
			)
			(fill no)
			(layer "B.CrtYd")
		)
		(fp_poly
			(pts
				(xy -0.5 0.25) (xy 0.5 0.25) (xy 0.5 -0.25) (xy -0.5 -0.25)
			)
			(stroke
				(width 0.15)
				(type solid)
			)
			(fill no)
			(layer "B.Fab")
		)
		(fp_text user "${REFERENCE}"
			(at -0.95 -3.168 0)
			(layer "B.Fab")
			(effects
				(font
					(size 0.7 0.7)
					(thickness 0.15)
				)
				(justify left bottom mirror)
			)
		)
		(fp_text user "Author: Antmicro"
			(at -0.95 -4.169 0)
			(layer "B.Fab")
			(effects
				(font
					(size 0.7 0.7)
					(thickness 0.15)
				)
				(justify left bottom mirror)
			)
		)
		(fp_text user "License: Apache-2.0"
			(at -0.949999 -5.169 0)
			(layer "B.Fab")
			(effects
				(font
					(size 0.7 0.7)
					(thickness 0.15)
				)
				(justify left bottom mirror)
			)
		)
		(pad "1" smd roundrect
			(at -0.48 0 180)
			(size 0.59 0.64)
			(layers "B.Cu" "B.Mask" "B.Paste")
			(roundrect_rratio 0.25)
			(net 999 "/SFP/I2C_{SFP}.SDA")
			(pintype "passive")
		)
		(pad "2" smd roundrect
			(at 0.48 0 180)
			(size 0.59 0.64)
			(layers "B.Cu" "B.Mask" "B.Paste")
			(roundrect_rratio 0.25)
			(net 824 "/SFP/SDA_SFP")
			(pintype "passive")
		)
	)
	(footprint "antmicro-footprints:R_0402_1005Metric"
		(layer "B.Cu")
		(at 61.6 86 -90)
		(descr "Resistor SMD 0402")
		(tags "resistor SMD 0402")
		(property "Reference" "R183"
			(at -1.73 -2.65 90)
			(layer "B.SilkS")
			(effects
				(font
					(size 0.7 0.7)
					(thickness 0.15)
				)
				(justify left bottom mirror)
			)
		)
		(property "Value" "R_470R_0402"
			(at -1.011843 -1.772046 90)
			(layer "B.Fab")
			(effects
				(font
					(size 0.7 0.7)
					(thickness 0.15)
				)
				(justify left bottom mirror)
			)
		)
		(property "Datasheet" "https://www.bourns.com/docs/product-datasheets/cr.pdf"
			(at 0 0 90)
			(layer "B.Fab")
			(hide yes)
			(effects
				(font
					(size 1.27 1.27)
					(thickness 0.15)
				)
				(justify mirror)
			)
		)
		(property "Description" "SMD Chip Resistor, 470 ohm, ± 1%, 62.5 mW, 0402 [1005 Metric], Thick Film, General Purpose"
			(at 0 0 90)
			(layer "B.Fab")
			(hide yes)
			(effects
				(font
					(size 1.27 1.27)
					(thickness 0.15)
				)
				(justify mirror)
			)
		)
		(property "Manufacturer" "Bourns"
			(at 0 0 90)
			(unlocked yes)
			(layer "B.Fab")
			(hide yes)
			(effects
				(font
					(size 1 1)
					(thickness 0.15)
				)
				(justify mirror)
			)
		)
		(property "MPN" "CR0402-FX-4700GLF"
			(at 0 0 90)
			(unlocked yes)
			(layer "B.Fab")
			(hide yes)
			(effects
				(font
					(size 1 1)
					(thickness 0.15)
				)
				(justify mirror)
			)
		)
		(property "Val" "470R"
			(at 0 0 90)
			(unlocked yes)
			(layer "B.Fab")
			(hide yes)
			(effects
				(font
					(size 1 1)
					(thickness 0.15)
				)
				(justify mirror)
			)
		)
		(property "License" "Apache-2.0"
			(at 0 0 90)
			(unlocked yes)
			(layer "B.Fab")
			(hide yes)
			(effects
				(font
					(size 1 1)
					(thickness 0.15)
				)
				(justify mirror)
			)
		)
		(property "Author" "Antmicro"
			(at 0 0 90)
			(unlocked yes)
			(layer "B.Fab")
			(hide yes)
			(effects
				(font
					(size 1 1)
					(thickness 0.15)
				)
				(justify mirror)
			)
		)
		(property "Tolerance" "1%"
			(at 0 0 90)
			(unlocked yes)
			(layer "B.Fab")
			(hide yes)
			(effects
				(font
					(size 1 1)
					(thickness 0.15)
				)
				(justify mirror)
			)
		)
		(sheetname "/CSI/")
		(sheetfile "csi.kicad_sch")
		(attr smd)
		(fp_poly
			(pts
				(xy -0.925 0.47) (xy 0.925 0.47) (xy 0.925 -0.47) (xy -0.925 -0.47)
			)
			(stroke
				(width 0.05)
				(type default)
			)
			(fill no)
			(layer "B.CrtYd")
		)
		(fp_poly
			(pts
				(xy -0.5 0.25) (xy 0.5 0.25) (xy 0.5 -0.25) (xy -0.5 -0.25)
			)
			(stroke
				(width 0.15)
				(type solid)
			)
			(fill no)
			(layer "B.Fab")
		)
		(fp_text user "License: Apache-2.0"
			(at -0.949999 -5.169 90)
			(layer "B.Fab")
			(effects
				(font
					(size 0.7 0.7)
					(thickness 0.15)
				)
				(justify left bottom mirror)
			)
		)
		(fp_text user "Author: Antmicro"
			(at -0.95 -4.169 90)
			(layer "B.Fab")
			(effects
				(font
					(size 0.7 0.7)
					(thickness 0.15)
				)
				(justify left bottom mirror)
			)
		)
		(fp_text user "${REFERENCE}"
			(at -0.95 -3.168 90)
			(layer "B.Fab")
			(effects
				(font
					(size 0.7 0.7)
					(thickness 0.15)
				)
				(justify left bottom mirror)
			)
		)
		(pad "1" smd roundrect
			(at -0.48 0 270)
			(size 0.59 0.64)
			(layers "B.Cu" "B.Mask" "B.Paste")
			(roundrect_rratio 0.25)
			(net 542 "Net-(D29-A)")
			(pintype "passive")
		)
		(pad "2" smd roundrect
			(at 0.48 0 270)
			(size 0.59 0.64)
			(layers "B.Cu" "B.Mask" "B.Paste")
			(roundrect_rratio 0.25)
			(net 7 "/CSI/CSIA_5V")
			(pintype "passive")
		)
	)
	(footprint "antmicro-footprints:SOT-523"
		(layer "B.Cu")
		(at 160.21 62.79 -90)
		(property "Reference" "Q28"
			(at 4.21 6.91 270)
			(layer "B.SilkS")
			(effects
				(font
					(size 0.7 0.7)
					(thickness 0.15)
				)
				(justify left bottom mirror)
			)
		)
		(property "Value" "DMG1012T-7"
			(at 0.1 -1.824 90)
			(layer "B.Fab")
			(effects
				(font
					(size 0.7 0.7)
					(thickness 0.15)
				)
				(justify left bottom mirror)
			)
		)
		(property "Datasheet" "https://www.diodes.com/assets/Datasheets/ds31783.pdf"
			(at 0 0 90)
			(layer "B.Fab")
			(hide yes)
			(effects
				(font
					(size 1.27 1.27)
					(thickness 0.15)
				)
				(justify mirror)
			)
		)
		(property "Description" "Power MOSFET, N Channel, 20 V, 630 mA, 0.3 ohm, SOT-523, Surface Mount"
			(at 0 0 90)
			(layer "B.Fab")
			(hide yes)
			(effects
				(font
					(size 1.27 1.27)
					(thickness 0.15)
				)
				(justify mirror)
			)
		)
		(property "MPN" "DMG1012T-7"
			(at 0 0 90)
			(unlocked yes)
			(layer "B.Fab")
			(hide yes)
			(effects
				(font
					(size 1 1)
					(thickness 0.15)
				)
				(justify mirror)
			)
		)
		(property "Manufacturer" "Diodes Incorporated"
			(at 0 0 90)
			(unlocked yes)
			(layer "B.Fab")
			(hide yes)
			(effects
				(font
					(size 1 1)
					(thickness 0.15)
				)
				(justify mirror)
			)
		)
		(property "Author" "Antmicro"
			(at 0 0 90)
			(unlocked yes)
			(layer "B.Fab")
			(hide yes)
			(effects
				(font
					(size 1 1)
					(thickness 0.15)
				)
				(justify mirror)
			)
		)
		(property "License" "Apache-2.0"
			(at 0 0 90)
			(unlocked yes)
			(layer "B.Fab")
			(hide yes)
			(effects
				(font
					(size 1 1)
					(thickness 0.15)
				)
				(justify mirror)
			)
		)
		(sheetname "/SoM_IO2/")
		(sheetfile "som_io2.kicad_sch")
		(attr smd exclude_from_pos_files exclude_from_bom dnp)
		(fp_line
			(start -0.725 0.551)
			(end -0.277 0.551)
			(stroke
				(width 0.15)
				(type solid)
			)
			(layer "B.SilkS")
		)
		(fp_line
			(start -0.277 0.551)
			(end -0.277 0.75)
			(stroke
				(width 0.15)
				(type solid)
			)
			(layer "B.SilkS")
		)
		(fp_line
			(start -0.927 0.351)
			(end -0.725 0.551)
			(stroke
				(width 0.15)
				(type solid)
			)
			(layer "B.SilkS")
		)
		(fp_line
			(start -0.927 0.051)
			(end -0.927 0.351)
			(stroke
				(width 0.15)
				(type solid)
			)
			(layer "B.SilkS")
		)
		(fp_circle
			(center -0.9652 -0.9652)
			(end -0.9152 -0.9652)
			(stroke
				(width 0.15)
				(type solid)
			)
			(fill yes)
			(layer "B.SilkS")
		)
		(fp_line
			(start -1.12 1.16)
			(end 1.1 1.16)
			(stroke
				(width 0.05)
				(type solid)
			)
			(layer "B.CrtYd")
		)
		(fp_line
			(start -1.12 1.16)
			(end -1.12 -1.15)
			(stroke
				(width 0.05)
				(type solid)
			)
			(layer "B.CrtYd")
		)
		(fp_line
			(start 1.1 1.16)
			(end 1.1 -1.15)
			(stroke
				(width 0.05)
				(type solid)
			)
			(layer "B.CrtYd")
		)
		(fp_line
			(start -1.12 -1.15)
			(end 1.1 -1.15)
			(stroke
				(width 0.05)
				(type solid)
			)
			(layer "B.CrtYd")
		)
		(fp_line
			(start -0.652 0.425)
			(end -0.802 0.276)
			(stroke
				(width 0.15)
				(type solid)
			)
			(layer "B.Fab")
		)
		(fp_line
			(start 0.8 0.425)
			(end -0.652 0.425)
			(stroke
				(width 0.15)
				(type solid)
			)
			(layer "B.Fab")
		)
		(fp_line
			(start 0.8 0.425)
			(end 0.8 -0.424)
			(stroke
				(width 0.15)
				(type solid)
			)
			(layer "B.Fab")
		)
		(fp_line
			(start -0.802 0.276)
			(end -0.802 -0.424)
			(stroke
				(width 0.15)
				(type solid)
			)
			(layer "B.Fab")
		)
		(fp_line
			(start 0.8 -0.424)
			(end -0.802 -0.424)
			(stroke
				(width 0.15)
				(type solid)
			)
			(layer "B.Fab")
		)
		(fp_circle
			(center -0.9652 -0.9652)
			(end -0.9144 -0.9652)
			(stroke
				(width 0.15)
				(type solid)
			)
			(fill no)
			(layer "B.Fab")
		)
		(fp_text user "Author: Antmicro"
			(at -1.12 -6.224 90)
			(layer "B.Fab")
			(effects
				(font
					(size 0.7 0.7)
					(thickness 0.15)
				)
				(justify left bottom mirror)
			)
		)
		(fp_text user "License: Apache-2.0"
			(at -1.12 -5.024 90)
			(layer "B.Fab")
			(effects
				(font
					(size 0.7 0.7)
					(thickness 0.15)
				)
				(justify left bottom mirror)
			)
		)
		(fp_text user "${REFERENCE}"
			(at -1.12 -3.824 90)
			(layer "B.Fab")
			(effects
				(font
					(size 0.7 0.7)
					(thickness 0.15)
				)
				(justify left bottom mirror)
			)
		)
		(pad "1" smd rect
			(at -0.5 -0.65 270)
			(size 0.4 0.51)
			(layers "B.Cu" "B.Mask" "B.Paste")
			(net 1299 "Net-(Q28-G)")
			(pinfunction "G")
			(pintype "input")
		)
		(pad "2" smd rect
			(at 0.498 -0.65 270)
			(size 0.4 0.51)
			(layers "B.Cu" "B.Mask" "B.Paste")
			(net 1 "GND")
			(pinfunction "S")
			(pintype "passive")
		)
		(pad "3" smd rect
			(at 0 0.652 270)
			(size 0.4 0.51)
			(layers "B.Cu" "B.Mask" "B.Paste")
			(net 627 "/SoM_IO2/JTAG_TRST_N")
			(pinfunction "D")
			(pintype "passive")
		)
	)
	(footprint "antmicro-footprints:TSOT23-6"
		(layer "B.Cu")
		(at 233.8 81.8)
		(property "Reference" "U40"
			(at 2.9 -1.229 90)
			(layer "B.SilkS")
			(effects
				(font
					(size 0.7 0.7)
					(thickness 0.15)
				)
				(justify left bottom mirror)
			)
		)
		(property "Value" "AP22615A_TSOT26"
			(at 0 -2.600001 0)
			(layer "B.Fab")
			(effects
				(font
					(size 0.7 0.7)
					(thickness 0.15)
				)
				(justify right top mirror)
			)
		)
		(property "Datasheet" "https://www.mouser.com/datasheet/2/115/DIOD_S_A0008958405_1-2543193.pdf"
			(at 0 0 0)
			(layer "B.Fab")
			(hide yes)
			(effects
				(font
					(size 1.27 1.27)
					(thickness 0.15)
				)
				(justify mirror)
			)
		)
		(property "Description" "Power Load Distribution Switch, High Side, Active High, 1 Output, 5.5 V, 3.6 A, 0.04 ohm, TSOT-26-6"
			(at 0 0 0)
			(layer "B.Fab")
			(hide yes)
			(effects
				(font
					(size 1.27 1.27)
					(thickness 0.15)
				)
				(justify mirror)
			)
		)
		(property "MPN" "AP22615AWU-7"
			(at 0 0 180)
			(unlocked yes)
			(layer "B.Fab")
			(hide yes)
			(effects
				(font
					(size 1 1)
					(thickness 0.15)
				)
				(justify mirror)
			)
		)
		(property "Manufacturer" "Diodes Incorporated"
			(at 0 0 180)
			(unlocked yes)
			(layer "B.Fab")
			(hide yes)
			(effects
				(font
					(size 1 1)
					(thickness 0.15)
				)
				(justify mirror)
			)
		)
		(property "Author" "Antmicro"
			(at 0 0 180)
			(unlocked yes)
			(layer "B.Fab")
			(hide yes)
			(effects
				(font
					(size 1 1)
					(thickness 0.15)
				)
				(justify mirror)
			)
		)
		(property "License" "Apache-2.0"
			(at 0 0 180)
			(unlocked yes)
			(layer "B.Fab")
			(hide yes)
			(effects
				(font
					(size 1 1)
					(thickness 0.15)
				)
				(justify mirror)
			)
		)
		(sheetname "/USB Debug, PD/")
		(sheetfile "usb_debug_pd.kicad_sch")
		(attr smd)
		(fp_line
			(start -1 -1.55)
			(end -1 -1.4)
			(stroke
				(width 0.15)
				(type solid)
			)
			(layer "B.SilkS")
		)
		(fp_line
			(start -1 1.5)
			(end -1 1.375)
			(stroke
				(width 0.15)
				(type solid)
			)
			(layer "B.SilkS")
		)
		(fp_line
			(start 1 -1.55)
			(end -1 -1.55)
			(stroke
				(width 0.15)
				(type solid)
			)
			(layer "B.SilkS")
		)
		(fp_line
			(start 1 -1.55)
			(end 1 -1.4)
			(stroke
				(width 0.15)
				(type solid)
			)
			(layer "B.SilkS")
		)
		(fp_line
			(start 1 1.497)
			(end -1 1.5)
			(stroke
				(width 0.15)
				(type solid)
			)
			(layer "B.SilkS")
		)
		(fp_line
			(start 1 1.497)
			(end 1 1.375)
			(stroke
				(width 0.15)
				(type solid)
			)
			(layer "B.SilkS")
		)
		(fp_circle
			(center -1.44 1.5)
			(end -1.39 1.5)
			(stroke
				(width 0.15)
				(type solid)
			)
			(fill yes)
			(layer "B.SilkS")
		)
		(fp_poly
			(pts
				(xy 1.930001 1.7) (xy 1.930001 -1.7) (xy -1.930001 -1.7) (xy -1.930001 1.7)
			)
			(stroke
				(width 0.05)
				(type solid)
			)
			(fill no)
			(layer "B.CrtYd")
		)
		(fp_line
			(start -0.45 1.520999)
			(end -0.876001 1.096)
			(stroke
				(width 0.15)
				(type solid)
			)
			(layer "B.Fab")
		)
		(fp_poly
			(pts
				(xy 0.875 -1.528) (xy 0.875 1.525) (xy -0.875 1.525) (xy -0.875 -1.528)
			)
			(stroke
				(width 0.15)
				(type solid)
			)
			(fill no)
			(layer "B.Fab")
		)
		(fp_text user "${REFERENCE}"
			(at -1.93 -3.8 0)
			(layer "B.Fab")
			(effects
				(font
					(size 0.7 0.7)
					(thickness 0.15)
				)
				(justify right top mirror)
			)
		)
		(fp_text user "License: Apache-2.0"
			(at -1.93 -6.199 0)
			(layer "B.Fab")
			(effects
				(font
					(size 0.7 0.7)
					(thickness 0.15)
				)
				(justify right top mirror)
			)
		)
		(fp_text user "Author: Antmicro"
			(at -1.93 -5 0)
			(layer "B.Fab")
			(effects
				(font
					(size 0.7 0.7)
					(thickness 0.15)
				)
				(justify right top mirror)
			)
		)
		(pad "1" smd rect
			(at -1.301 0.947 90)
			(size 0.7 1.2)
			(layers "B.Cu" "B.Mask" "B.Paste")
			(net 176 "/USB Debug, PD/USBC0_VBUS")
			(pinfunction "OUT")
			(pintype "power_out")
		)
		(pad "2" smd rect
			(at -1.300999 -0.004 90)
			(size 0.7 1.2)
			(layers "B.Cu" "B.Mask" "B.Paste")
			(net 1 "GND")
			(pinfunction "GND")
			(pintype "power_in")
		)
		(pad "3" smd rect
			(at -1.301 -0.954 90)
			(size 0.7 1.2)
			(layers "B.Cu" "B.Mask" "B.Paste")
			(net 976 "/USB Debug, PD/USBC0_FLG")
			(pinfunction "FLG")
			(pintype "output")
		)
		(pad "4" smd rect
			(at 1.299 -0.954 90)
			(size 0.7 1.2)
			(layers "B.Cu" "B.Mask" "B.Paste")
			(net 977 "Net-(U40-EN)")
			(pinfunction "EN")
			(pintype "input")
		)
		(pad "5" smd rect
			(at 1.299 -0.004 90)
			(size 0.7 1.2)
			(layers "B.Cu" "B.Mask" "B.Paste")
			(net 978 "/USB Debug, PD/USBC0_ISET")
			(pinfunction "ISET")
			(pintype "passive")
		)
		(pad "6" smd rect
			(at 1.299 0.947 90)
			(size 0.7 1.2)
			(layers "B.Cu" "B.Mask" "B.Paste")
			(net 5 "+5V")
			(pinfunction "IN")
			(pintype "power_in")
		)
	)
	(footprint "antmicro-footprints:C_0402_1005Metric"
		(layer "B.Cu")
		(at 91.180001 103.6 -90)
		(descr "Capacitor SMD 0402")
		(tags "capacitor SMD 0402")
		(property "Reference" "C331"
			(at -3.8 -0.419999 90)
			(layer "B.SilkS")
			(effects
				(font
					(size 0.7 0.7)
					(thickness 0.15)
				)
				(justify left bottom mirror)
			)
		)
		(property "Value" "C_100n_0402"
			(at -1.022927 -2.155213 90)
			(layer "B.Fab")
			(effects
				(font
					(size 0.7 0.7)
					(thickness 0.15)
				)
				(justify left bottom mirror)
			)
		)
		(property "Datasheet" "https://www.murata.com/products/productdetail?partno=GRM155R61H104KE14%23"
			(at 0 0 90)
			(layer "B.Fab")
			(hide yes)
			(effects
				(font
					(size 1.27 1.27)
					(thickness 0.15)
				)
				(justify mirror)
			)
		)
		(property "Description" "SMD Multilayer Ceramic Capacitor, 0.1 µF, 50 V, 0402 [1005 Metric], ± 10%, X5R, GRM Series"
			(at 0 0 90)
			(layer "B.Fab")
			(hide yes)
			(effects
				(font
					(size 1.27 1.27)
					(thickness 0.15)
				)
				(justify mirror)
			)
		)
		(property "Manufacturer" "Murata"
			(at 0 0 90)
			(unlocked yes)
			(layer "B.Fab")
			(hide yes)
			(effects
				(font
					(size 1 1)
					(thickness 0.15)
				)
				(justify mirror)
			)
		)
		(property "MPN" "GRM155R61H104KE14D"
			(at 0 0 90)
			(unlocked yes)
			(layer "B.Fab")
			(hide yes)
			(effects
				(font
					(size 1 1)
					(thickness 0.15)
				)
				(justify mirror)
			)
		)
		(property "Val" "100n"
			(at 0 0 90)
			(unlocked yes)
			(layer "B.Fab")
			(hide yes)
			(effects
				(font
					(size 1 1)
					(thickness 0.15)
				)
				(justify mirror)
			)
		)
		(property "License" "Apache-2.0"
			(at 0 0 90)
			(unlocked yes)
			(layer "B.Fab")
			(hide yes)
			(effects
				(font
					(size 1 1)
					(thickness 0.15)
				)
				(justify mirror)
			)
		)
		(property "Author" "Antmicro"
			(at 0 0 90)
			(unlocked yes)
			(layer "B.Fab")
			(hide yes)
			(effects
				(font
					(size 1 1)
					(thickness 0.15)
				)
				(justify mirror)
			)
		)
		(property "Voltage" "50V"
			(at 0 0 90)
			(unlocked yes)
			(layer "B.Fab")
			(hide yes)
			(effects
				(font
					(size 1 1)
					(thickness 0.15)
				)
				(justify mirror)
			)
		)
		(property "Dielectric" "X5R"
			(at 0 0 90)
			(unlocked yes)
			(layer "B.Fab")
			(hide yes)
			(effects
				(font
					(size 1 1)
					(thickness 0.15)
				)
				(justify mirror)
			)
		)
		(sheetname "/SoM_IO2/")
		(sheetfile "som_io2.kicad_sch")
		(attr smd)
		(fp_poly
			(pts
				(xy -0.925 0.47) (xy 0.925 0.47) (xy 0.925 -0.47) (xy -0.925 -0.47)
			)
			(stroke
				(width 0.05)
				(type default)
			)
			(fill no)
			(layer "B.CrtYd")
		)
		(fp_line
			(start -0.494 0.25)
			(end 0.504 0.25)
			(stroke
				(width 0.15)
				(type solid)
			)
			(layer "B.Fab")
		)
		(fp_line
			(start 0.504 0.25)
			(end 0.504 -0.248)
			(stroke
				(width 0.15)
				(type solid)
			)
			(layer "B.Fab")
		)
		(fp_line
			(start -0.494 -0.248)
			(end -0.494 0.25)
			(stroke
				(width 0.15)
				(type solid)
			)
			(layer "B.Fab")
		)
		(fp_line
			(start 0.504 -0.248)
			(end -0.494 -0.248)
			(stroke
				(width 0.15)
				(type solid)
			)
			(layer "B.Fab")
		)
		(fp_text user "${REFERENCE}"
			(at -0.939 -4.599 90)
			(layer "B.Fab")
			(effects
				(font
					(size 0.7 0.7)
					(thickness 0.15)
				)
				(justify left bottom mirror)
			)
		)
		(fp_text user "Author: Antmicro"
			(at -0.939 -3.399 90)
			(layer "B.Fab")
			(effects
				(font
					(size 0.7 0.7)
					(thickness 0.15)
				)
				(justify left bottom mirror)
			)
		)
		(fp_text user "License: Apache-2.0"
			(at -0.939 -5.799 90)
			(layer "B.Fab")
			(effects
				(font
					(size 0.7 0.7)
					(thickness 0.15)
				)
				(justify left bottom mirror)
			)
		)
		(pad "1" smd roundrect
			(at -0.48 0 270)
			(size 0.59 0.64)
			(layers "B.Cu" "B.Mask" "B.Paste")
			(roundrect_rratio 0.25)
			(net 682 "/Expansion connector/DP1.TX3-")
			(pintype "passive")
		)
		(pad "2" smd roundrect
			(at 0.48 0 270)
			(size 0.59 0.64)
			(layers "B.Cu" "B.Mask" "B.Paste")
			(roundrect_rratio 0.25)
			(net 1251 "/SoM_IO2/DP1.TX3_C-")
			(pintype "passive")
		)
	)
	(footprint "antmicro-footprints:TP_SMD_0.75mm"
		(layer "B.Cu")
		(at 125.4 69.4 90)
		(property "Reference" "TP57"
			(at 0.5 -0.3 90)
			(layer "B.SilkS")
			(effects
				(font
					(size 0.7 0.7)
					(thickness 0.15)
				)
				(justify right top mirror)
			)
		)
		(property "Value" "TP_0.75mm_SMD"
			(at 0 -1.2 90)
			(layer "B.Fab")
			(effects
				(font
					(size 0.7 0.7)
					(thickness 0.15)
				)
				(justify right top mirror)
			)
		)
		(property "Description" "SMT test point"
			(at 0 0 90)
			(layer "B.Fab")
			(hide yes)
			(effects
				(font
					(size 1.27 1.27)
					(thickness 0.15)
				)
				(justify mirror)
			)
		)
		(property "MPN" ""
			(at 0 0 270)
			(unlocked yes)
			(layer "B.Fab")
			(hide yes)
			(effects
				(font
					(size 1 1)
					(thickness 0.15)
				)
				(justify mirror)
			)
		)
		(property "Manufacturer" ""
			(at 0 0 270)
			(unlocked yes)
			(layer "B.Fab")
			(hide yes)
			(effects
				(font
					(size 1 1)
					(thickness 0.15)
				)
				(justify mirror)
			)
		)
		(property "Author" "Antmicro"
			(at 0 0 270)
			(unlocked yes)
			(layer "B.Fab")
			(hide yes)
			(effects
				(font
					(size 1 1)
					(thickness 0.15)
				)
				(justify mirror)
			)
		)
		(property "License" "Apache-2.0"
			(at 0 0 270)
			(unlocked yes)
			(layer "B.Fab")
			(hide yes)
			(effects
				(font
					(size 1 1)
					(thickness 0.15)
				)
				(justify mirror)
			)
		)
		(sheetname "/SoM_Power/")
		(sheetfile "som_power.kicad_sch")
		(attr exclude_from_pos_files exclude_from_bom)
		(fp_circle
			(center 0 0)
			(end 0.475 0)
			(stroke
				(width 0.05)
				(type default)
			)
			(fill no)
			(layer "B.CrtYd")
		)
		(fp_text user "Author: Antmicro"
			(at -0.4 -3.901 90)
			(layer "B.Fab")
			(effects
				(font
					(size 0.7 0.7)
					(thickness 0.15)
				)
				(justify right top mirror)
			)
		)
		(fp_text user "${REFERENCE}"
			(at -0.4 -2.7 90)
			(layer "B.Fab")
			(effects
				(font
					(size 0.7 0.7)
					(thickness 0.15)
				)
				(justify right top mirror)
			)
		)
		(fp_text user "License: Apache-2.0"
			(at -0.4 -5.101 90)
			(layer "B.Fab")
			(effects
				(font
					(size 0.7 0.7)
					(thickness 0.15)
				)
				(justify right top mirror)
			)
		)
		(pad "1" smd circle
			(at 0 0 90)
			(size 0.75 0.75)
			(layers "B.Cu" "B.Mask")
			(net 566 "Net-(J1A-VM_SLEEP_N)")
			(pinfunction "1")
			(pintype "passive")
		)
	)
	(footprint "antmicro-footprints:R_0402_1005Metric"
		(layer "B.Cu")
		(at 109.82 132.3 180)
		(descr "Resistor SMD 0402")
		(tags "resistor SMD 0402")
		(property "Reference" "R220"
			(at 3.82 0.3 180)
			(layer "B.SilkS")
			(effects
				(font
					(size 0.7 0.7)
					(thickness 0.15)
				)
				(justify right top mirror)
			)
		)
		(property "Value" "R_47k_0402"
			(at -1.011843 -1.772047 180)
			(layer "B.Fab")
			(effects
				(font
					(size 0.7 0.7)
					(thickness 0.15)
				)
				(justify right top mirror)
			)
		)
		(property "Datasheet" "https://www.bourns.com/docs/product-datasheets/cr.pdf"
			(at 0 0 180)
			(layer "B.Fab")
			(hide yes)
			(effects
				(font
					(size 1.27 1.27)
					(thickness 0.15)
				)
				(justify mirror)
			)
		)
		(property "Description" "SMD Chip Resistor, 47 kohm, ± 1%, 62.5 mW, 0402 [1005 Metric], Thick Film, General Purpose"
			(at 0 0 180)
			(layer "B.Fab")
			(hide yes)
			(effects
				(font
					(size 1.27 1.27)
					(thickness 0.15)
				)
				(justify mirror)
			)
		)
		(property "MPN" "CR0402-FX-4702GLF"
			(at 0 0 0)
			(unlocked yes)
			(layer "B.Fab")
			(hide yes)
			(effects
				(font
					(size 1 1)
					(thickness 0.15)
				)
				(justify mirror)
			)
		)
		(property "Manufacturer" "Bourns"
			(at 0 0 0)
			(unlocked yes)
			(layer "B.Fab")
			(hide yes)
			(effects
				(font
					(size 1 1)
					(thickness 0.15)
				)
				(justify mirror)
			)
		)
		(property "License" "Apache-2.0"
			(at 0 0 0)
			(unlocked yes)
			(layer "B.Fab")
			(hide yes)
			(effects
				(font
					(size 1 1)
					(thickness 0.15)
				)
				(justify mirror)
			)
		)
		(property "Author" "Antmicro"
			(at 0 0 0)
			(unlocked yes)
			(layer "B.Fab")
			(hide yes)
			(effects
				(font
					(size 1 1)
					(thickness 0.15)
				)
				(justify mirror)
			)
		)
		(property "Val" "47k"
			(at 0 0 0)
			(unlocked yes)
			(layer "B.Fab")
			(hide yes)
			(effects
				(font
					(size 1 1)
					(thickness 0.15)
				)
				(justify mirror)
			)
		)
		(property "Tolerance" "1%"
			(at 0 0 0)
			(unlocked yes)
			(layer "B.Fab")
			(hide yes)
			(effects
				(font
					(size 1 1)
					(thickness 0.15)
				)
				(justify mirror)
			)
		)
		(sheetname "/M.2/")
		(sheetfile "m2.kicad_sch")
		(attr smd)
		(fp_rect
			(start -0.925 0.47)
			(end 0.925 -0.47)
			(stroke
				(width 0.05)
				(type default)
			)
			(fill no)
			(layer "B.CrtYd")
		)
		(fp_rect
			(start -0.5 0.25)
			(end 0.5 -0.25)
			(stroke
				(width 0.15)
				(type solid)
			)
			(fill no)
			(layer "B.Fab")
		)
		(fp_text user "${REFERENCE}"
			(at -0.95 -3.168 180)
			(layer "B.Fab")
			(effects
				(font
					(size 0.7 0.7)
					(thickness 0.15)
				)
				(justify right top mirror)
			)
		)
		(fp_text user "Author: Antmicro"
			(at -0.95 -4.169 180)
			(layer "B.Fab")
			(effects
				(font
					(size 0.7 0.7)
					(thickness 0.15)
				)
				(justify right top mirror)
			)
		)
		(fp_text user "License: Apache-2.0"
			(at -0.95 -5.169 180)
			(layer "B.Fab")
			(effects
				(font
					(size 0.7 0.7)
					(thickness 0.15)
				)
				(justify right top mirror)
			)
		)
		(pad "1" smd roundrect
			(at -0.48 0 180)
			(size 0.59 0.64)
			(layers "B.Cu" "B.Mask" "B.Paste")
			(roundrect_rratio 0.25)
			(net 834 "/M.2/~{CLKREQ_E}")
			(pintype "passive")
		)
		(pad "2" smd roundrect
			(at 0.48 0 180)
			(size 0.59 0.64)
			(layers "B.Cu" "B.Mask" "B.Paste")
			(roundrect_rratio 0.25)
			(net 2 "+3V3")
			(pintype "passive")
		)
	)
	(footprint "antmicro-footprints:SOT-563"
		(layer "B.Cu")
		(at 217.04 111.24 90)
		(property "Reference" "Q26"
			(at -1.06 -2.04 90)
			(layer "B.SilkS")
			(effects
				(font
					(size 0.7 0.7)
					(thickness 0.15)
				)
				(justify right top mirror)
			)
		)
		(property "Value" "DMC2400UV-7"
			(at 0 -2 90)
			(layer "B.Fab")
			(effects
				(font
					(size 0.7 0.7)
					(thickness 0.15)
				)
				(justify right top mirror)
			)
		)
		(property "Datasheet" "https://www.mouser.com/datasheet/2/115/DIOD_S_A0010038249_1-2543538.pdf"
			(at 0 0 90)
			(layer "B.Fab")
			(hide yes)
			(effects
				(font
					(size 1.27 1.27)
					(thickness 0.15)
				)
				(justify mirror)
			)
		)
		(property "Description" "Dual MOSFET, Complementary N and P Channel, 20 V, 20 V, 1.03 A, 1.03 A, 0.3 ohm"
			(at 0 0 90)
			(layer "B.Fab")
			(hide yes)
			(effects
				(font
					(size 1.27 1.27)
					(thickness 0.15)
				)
				(justify mirror)
			)
		)
		(property "MPN" "DMC2400UV-7"
			(at 0 0 270)
			(unlocked yes)
			(layer "B.Fab")
			(hide yes)
			(effects
				(font
					(size 1 1)
					(thickness 0.15)
				)
				(justify mirror)
			)
		)
		(property "Manufacturer" "Diodes Incorporated"
			(at 0 0 270)
			(unlocked yes)
			(layer "B.Fab")
			(hide yes)
			(effects
				(font
					(size 1 1)
					(thickness 0.15)
				)
				(justify mirror)
			)
		)
		(property "Author" "Antmicro"
			(at 0 0 270)
			(unlocked yes)
			(layer "B.Fab")
			(hide yes)
			(effects
				(font
					(size 1 1)
					(thickness 0.15)
				)
				(justify mirror)
			)
		)
		(property "License" "Apache-2.0"
			(at 0 0 270)
			(unlocked yes)
			(layer "B.Fab")
			(hide yes)
			(effects
				(font
					(size 1 1)
					(thickness 0.15)
				)
				(justify mirror)
			)
		)
		(sheetname "/USB Hub/")
		(sheetfile "usb_hub.kicad_sch")
		(attr smd)
		(fp_line
			(start 0.776 -0.972)
			(end 0.526 -0.972)
			(stroke
				(width 0.15)
				(type solid)
			)
			(layer "B.SilkS")
		)
		(fp_line
			(start -0.778 -0.949)
			(end -0.424 -0.949)
			(stroke
				(width 0.15)
				(type solid)
			)
			(layer "B.SilkS")
		)
		(fp_line
			(start 0.776 -0.776)
			(end 0.776 -0.972)
			(stroke
				(width 0.15)
				(type solid)
			)
			(layer "B.SilkS")
		)
		(fp_line
			(start -0.778 -0.776)
			(end -0.778 -0.949)
			(stroke
				(width 0.15)
				(type solid)
			)
			(layer "B.SilkS")
		)
		(fp_line
			(start 0.776 0.974)
			(end 0.776 0.778)
			(stroke
				(width 0.15)
				(type solid)
			)
			(layer "B.SilkS")
		)
		(fp_line
			(start 0.776 0.974)
			(end 0.526 0.974)
			(stroke
				(width 0.15)
				(type solid)
			)
			(layer "B.SilkS")
		)
		(fp_line
			(start -0.499 0.974)
			(end -0.724 0.778)
			(stroke
				(width 0.15)
				(type solid)
			)
			(layer "B.SilkS")
		)
		(fp_circle
			(center -0.903 0.999)
			(end -0.952 0.95)
			(stroke
				(width 0.15)
				(type solid)
			)
			(fill yes)
			(layer "B.SilkS")
		)
		(fp_rect
			(start 1.19 1.12)
			(end -1.2 -1.1)
			(stroke
				(width 0.05)
				(type solid)
			)
			(fill no)
			(layer "B.CrtYd")
		)
		(fp_line
			(start 0.651 -0.847)
			(end -0.653 -0.847)
			(stroke
				(width 0.15)
				(type solid)
			)
			(layer "B.Fab")
		)
		(fp_line
			(start -0.653 0.678)
			(end -0.653 -0.847)
			(stroke
				(width 0.15)
				(type solid)
			)
			(layer "B.Fab")
		)
		(fp_line
			(start 0.651 0.849)
			(end 0.651 -0.847)
			(stroke
				(width 0.15)
				(type solid)
			)
			(layer "B.Fab")
		)
		(fp_line
			(start -0.453 0.849)
			(end -0.653 0.678)
			(stroke
				(width 0.15)
				(type solid)
			)
			(layer "B.Fab")
		)
		(fp_line
			(start -0.453 0.849)
			(end 0.651 0.849)
			(stroke
				(width 0.15)
				(type solid)
			)
			(layer "B.Fab")
		)
		(fp_text user "Author: Antmicro"
			(at -1.299 -6.124 90)
			(layer "B.Fab")
			(effects
				(font
					(size 0.7 0.7)
					(thickness 0.15)
				)
				(justify right top mirror)
			)
		)
		(fp_text user "License: Apache-2.0"
			(at -1.299 -4.924 90)
			(layer "B.Fab")
			(effects
				(font
					(size 0.7 0.7)
					(thickness 0.15)
				)
				(justify right top mirror)
			)
		)
		(fp_text user "${REFERENCE}"
			(at -1.299 -7.323 90)
			(layer "B.Fab")
			(effects
				(font
					(size 0.7 0.7)
					(thickness 0.15)
				)
				(justify right top mirror)
			)
		)
		(pad "1" smd roundrect
			(at -0.749 0.499 180)
			(size 0.3 0.6)
			(layers "B.Cu" "B.Mask" "B.Paste")
			(roundrect_rratio 0.25)
			(net 1 "GND")
			(pinfunction "S1")
			(pintype "passive")
		)
		(pad "2" smd roundrect
			(at -0.749 -0.001 180)
			(size 0.3 0.6)
			(layers "B.Cu" "B.Mask" "B.Paste")
			(roundrect_rratio 0.25)
			(net 1106 "/USB Hub/DP2_VCONN2")
			(pinfunction "G1")
			(pintype "input")
		)
		(pad "3" smd roundrect
			(at -0.749 -0.497 180)
			(size 0.3 0.6)
			(layers "B.Cu" "B.Mask" "B.Paste")
			(roundrect_rratio 0.25)
			(net 1236 "Net-(D58-A)")
			(pinfunction "D2")
			(pintype "passive")
		)
		(pad "4" smd roundrect
			(at 0.747 -0.497 180)
			(size 0.3 0.6)
			(layers "B.Cu" "B.Mask" "B.Paste")
			(roundrect_rratio 0.25)
			(net 5 "+5V")
			(pinfunction "S2")
			(pintype "passive")
		)
		(pad "5" smd roundrect
			(at 0.747 -0.001 180)
			(size 0.3 0.6)
			(layers "B.Cu" "B.Mask" "B.Paste")
			(roundrect_rratio 0.25)
			(net 1331 "Net-(Q26-D1)")
			(pinfunction "G2")
			(pintype "input")
		)
		(pad "6" smd roundrect
			(at 0.747 0.499 180)
			(size 0.3 0.6)
			(layers "B.Cu" "B.Mask" "B.Paste")
			(roundrect_rratio 0.25)
			(net 1331 "Net-(Q26-D1)")
			(pinfunction "D1")
			(pintype "passive")
		)
	)
	(footprint "antmicro-footprints:R_0402_1005Metric"
		(layer "B.Cu")
		(at 200.8 127.2 180)
		(descr "Resistor SMD 0402")
		(tags "resistor SMD 0402")
		(property "Reference" "R239"
			(at -3.8535 -0.41 0)
			(layer "B.SilkS")
			(effects
				(font
					(size 0.7 0.7)
					(thickness 0.15)
				)
				(justify left bottom mirror)
			)
		)
		(property "Value" "R_100k_0402"
			(at -1.011843 -1.772047 0)
			(layer "B.Fab")
			(effects
				(font
					(size 0.7 0.7)
					(thickness 0.15)
				)
				(justify left bottom mirror)
			)
		)
		(property "Datasheet" "https://www.bourns.com/docs/product-datasheets/cr.pdf"
			(at 0 0 0)
			(layer "B.Fab")
			(hide yes)
			(effects
				(font
					(size 1.27 1.27)
					(thickness 0.15)
				)
				(justify mirror)
			)
		)
		(property "Description" "SMD Chip Resistor, 100 kohm, ± 1%, 62.5 mW, 0402 [1005 Metric], Thick Film, General Purpose"
			(at 0 0 0)
			(layer "B.Fab")
			(hide yes)
			(effects
				(font
					(size 1.27 1.27)
					(thickness 0.15)
				)
				(justify mirror)
			)
		)
		(property "MPN" "CR0402-FX-1003GLF"
			(at 0 0 0)
			(unlocked yes)
			(layer "B.Fab")
			(hide yes)
			(effects
				(font
					(size 1 1)
					(thickness 0.15)
				)
				(justify mirror)
			)
		)
		(property "Manufacturer" "Bourns"
			(at 0 0 0)
			(unlocked yes)
			(layer "B.Fab")
			(hide yes)
			(effects
				(font
					(size 1 1)
					(thickness 0.15)
				)
				(justify mirror)
			)
		)
		(property "License" "Apache-2.0"
			(at 0 0 0)
			(unlocked yes)
			(layer "B.Fab")
			(hide yes)
			(effects
				(font
					(size 1 1)
					(thickness 0.15)
				)
				(justify mirror)
			)
		)
		(property "Author" "Antmicro"
			(at 0 0 0)
			(unlocked yes)
			(layer "B.Fab")
			(hide yes)
			(effects
				(font
					(size 1 1)
					(thickness 0.15)
				)
				(justify mirror)
			)
		)
		(property "Val" "100k"
			(at 0 0 0)
			(unlocked yes)
			(layer "B.Fab")
			(hide yes)
			(effects
				(font
					(size 1 1)
					(thickness 0.15)
				)
				(justify mirror)
			)
		)
		(property "Tolerance" "1%"
			(at 0 0 0)
			(unlocked yes)
			(layer "B.Fab")
			(hide yes)
			(effects
				(font
					(size 1 1)
					(thickness 0.15)
				)
				(justify mirror)
			)
		)
		(property "Current" "1A"
			(at 0 0 0)
			(unlocked yes)
			(layer "B.Fab")
			(hide yes)
			(effects
				(font
					(size 1 1)
					(thickness 0.15)
				)
				(justify mirror)
			)
		)
		(sheetname "/USB Hub/")
		(sheetfile "usb_hub.kicad_sch")
		(attr smd)
		(fp_rect
			(start -0.925 0.47)
			(end 0.925 -0.47)
			(stroke
				(width 0.05)
				(type default)
			)
			(fill no)
			(layer "B.CrtYd")
		)
		(fp_rect
			(start -0.5 0.25)
			(end 0.5 -0.25)
			(stroke
				(width 0.15)
				(type solid)
			)
			(fill no)
			(layer "B.Fab")
		)
		(fp_text user "License: Apache-2.0"
			(at -0.95 -5.169 0)
			(layer "B.Fab")
			(effects
				(font
					(size 0.7 0.7)
					(thickness 0.15)
				)
				(justify left bottom mirror)
			)
		)
		(fp_text user "${REFERENCE}"
			(at -0.95 -3.168 0)
			(layer "B.Fab")
			(effects
				(font
					(size 0.7 0.7)
					(thickness 0.15)
				)
				(justify left bottom mirror)
			)
		)
		(fp_text user "Author: Antmicro"
			(at -0.95 -4.169 0)
			(layer "B.Fab")
			(effects
				(font
					(size 0.7 0.7)
					(thickness 0.15)
				)
				(justify left bottom mirror)
			)
		)
		(pad "1" smd roundrect
			(at -0.48 0 180)
			(size 0.59 0.64)
			(layers "B.Cu" "B.Mask" "B.Paste")
			(roundrect_rratio 0.25)
			(net 1 "GND")
			(pintype "passive")
		)
		(pad "2" smd roundrect
			(at 0.48 0 180)
			(size 0.59 0.64)
			(layers "B.Cu" "B.Mask" "B.Paste")
			(roundrect_rratio 0.25)
			(net 921 "/USB Hub/HUB_SPI_D2")
			(pintype "passive")
		)
	)
	(footprint "antmicro-footprints:C_0402_1005Metric"
		(layer "B.Cu")
		(at 178.36 82.5 180)
		(descr "Capacitor SMD 0402")
		(tags "capacitor SMD 0402")
		(property "Reference" "C240"
			(at -0.07 -1.32 0)
			(layer "B.SilkS")
			(effects
				(font
					(size 0.7 0.7)
					(thickness 0.15)
				)
				(justify left bottom mirror)
			)
		)
		(property "Value" "C_100n_0402"
			(at -1.022927 -2.155213 0)
			(layer "B.Fab")
			(effects
				(font
					(size 0.7 0.7)
					(thickness 0.15)
				)
				(justify left bottom mirror)
			)
		)
		(property "Datasheet" "https://www.murata.com/products/productdetail?partno=GRM155R61H104KE14%23"
			(at 0 0 0)
			(layer "B.Fab")
			(hide yes)
			(effects
				(font
					(size 1.27 1.27)
					(thickness 0.15)
				)
				(justify mirror)
			)
		)
		(property "Description" "SMD Multilayer Ceramic Capacitor, 0.1 µF, 50 V, 0402 [1005 Metric], ± 10%, X5R, GRM Series"
			(at 0 0 0)
			(layer "B.Fab")
			(hide yes)
			(effects
				(font
					(size 1.27 1.27)
					(thickness 0.15)
				)
				(justify mirror)
			)
		)
		(property "MPN" "GRM155R61H104KE14D"
			(at 0 0 0)
			(unlocked yes)
			(layer "B.Fab")
			(hide yes)
			(effects
				(font
					(size 1 1)
					(thickness 0.15)
				)
				(justify mirror)
			)
		)
		(property "Manufacturer" "Murata"
			(at 0 0 0)
			(unlocked yes)
			(layer "B.Fab")
			(hide yes)
			(effects
				(font
					(size 1 1)
					(thickness 0.15)
				)
				(justify mirror)
			)
		)
		(property "License" "Apache-2.0"
			(at 0 0 0)
			(unlocked yes)
			(layer "B.Fab")
			(hide yes)
			(effects
				(font
					(size 1 1)
					(thickness 0.15)
				)
				(justify mirror)
			)
		)
		(property "Author" "Antmicro"
			(at 0 0 0)
			(unlocked yes)
			(layer "B.Fab")
			(hide yes)
			(effects
				(font
					(size 1 1)
					(thickness 0.15)
				)
				(justify mirror)
			)
		)
		(property "Val" "100n"
			(at 0 0 0)
			(unlocked yes)
			(layer "B.Fab")
			(hide yes)
			(effects
				(font
					(size 1 1)
					(thickness 0.15)
				)
				(justify mirror)
			)
		)
		(property "Voltage" "50V"
			(at 0 0 0)
			(unlocked yes)
			(layer "B.Fab")
			(hide yes)
			(effects
				(font
					(size 1 1)
					(thickness 0.15)
				)
				(justify mirror)
			)
		)
		(property "Dielectric" "X5R"
			(at 0 0 0)
			(unlocked yes)
			(layer "B.Fab")
			(hide yes)
			(effects
				(font
					(size 1 1)
					(thickness 0.15)
				)
				(justify mirror)
			)
		)
		(sheetname "/Power/")
		(sheetfile "power.kicad_sch")
		(attr smd exclude_from_pos_files exclude_from_bom dnp)
		(fp_rect
			(start -0.925 0.47)
			(end 0.925 -0.47)
			(stroke
				(width 0.05)
				(type default)
			)
			(fill no)
			(layer "B.CrtYd")
		)
		(fp_line
			(start 0.504 0.25)
			(end 0.504 -0.248)
			(stroke
				(width 0.15)
				(type solid)
			)
			(layer "B.Fab")
		)
		(fp_line
			(start 0.504 -0.248)
			(end -0.494 -0.248)
			(stroke
				(width 0.15)
				(type solid)
			)
			(layer "B.Fab")
		)
		(fp_line
			(start -0.494 0.25)
			(end 0.504 0.25)
			(stroke
				(width 0.15)
				(type solid)
			)
			(layer "B.Fab")
		)
		(fp_line
			(start -0.494 -0.248)
			(end -0.494 0.25)
			(stroke
				(width 0.15)
				(type solid)
			)
			(layer "B.Fab")
		)
		(fp_text user "License: Apache-2.0"
			(at -0.939 -5.799 0)
			(layer "B.Fab")
			(effects
				(font
					(size 0.7 0.7)
					(thickness 0.15)
				)
				(justify left bottom mirror)
			)
		)
		(fp_text user "Author: Antmicro"
			(at -0.939 -3.399 0)
			(layer "B.Fab")
			(effects
				(font
					(size 0.7 0.7)
					(thickness 0.15)
				)
				(justify left bottom mirror)
			)
		)
		(fp_text user "${REFERENCE}"
			(at -0.939 -4.599 0)
			(layer "B.Fab")
			(effects
				(font
					(size 0.7 0.7)
					(thickness 0.15)
				)
				(justify left bottom mirror)
			)
		)
		(pad "1" smd roundrect
			(at -0.48 0 180)
			(size 0.59 0.64)
			(layers "B.Cu" "B.Mask" "B.Paste")
			(roundrect_rratio 0.25)
			(net 1 "GND")
			(pintype "passive")
		)
		(pad "2" smd roundrect
			(at 0.48 0 180)
			(size 0.59 0.64)
			(layers "B.Cu" "B.Mask" "B.Paste")
			(roundrect_rratio 0.25)
			(net 525 "/Power/USBPD2_HV")
			(pintype "passive")
		)
	)
	(footprint "antmicro-footprints:Spacer_Drill3.7mm_H8mm_9774080151R"
		(locked yes)
		(layer "B.Cu")
		(at 80.430532 63.71 -90)
		(descr "Spacer M=3 h=8mm fi=5.1mm")
		(property "Reference" "H2"
			(at 0 3.2 90)
			(layer "B.SilkS")
			(effects
				(font
					(size 0.7 0.7)
					(thickness 0.15)
				)
				(justify left bottom mirror)
			)
		)
		(property "Value" "Spacer_Drill3.7mm_H8mm_9774080151R"
			(at 0 -4 90)
			(layer "B.Fab")
			(effects
				(font
					(size 0.7 0.7)
					(thickness 0.15)
				)
				(justify left bottom mirror)
			)
		)
		(property "Datasheet" "https://www.we-online.com/components/products/datasheet/9774080151R.pdf"
			(at 0 0 90)
			(layer "B.Fab")
			(hide yes)
			(effects
				(font
					(size 1.27 1.27)
					(thickness 0.15)
				)
				(justify mirror)
			)
		)
		(property "Description" "Spacer, SMT, Non Stop, Steel, Swage Round, 5.1 mm x 8 mm, M2.5 Thread, WA-SMSI Series"
			(at 0 0 90)
			(layer "B.Fab")
			(hide yes)
			(effects
				(font
					(size 1.27 1.27)
					(thickness 0.15)
				)
				(justify mirror)
			)
		)
		(property "Manufacturer" "Würth Elektronik"
			(at 0 0 270)
			(unlocked yes)
			(layer "B.Fab")
			(hide yes)
			(effects
				(font
					(size 1 1)
					(thickness 0.15)
				)
				(justify mirror)
			)
		)
		(property "MPN" "9774080151R"
			(at 0 0 270)
			(unlocked yes)
			(layer "B.Fab")
			(hide yes)
			(effects
				(font
					(size 1 1)
					(thickness 0.15)
				)
				(justify mirror)
			)
		)
		(property "Author" "Antmicro"
			(at 0 0 270)
			(unlocked yes)
			(layer "B.Fab")
			(hide yes)
			(effects
				(font
					(size 1 1)
					(thickness 0.15)
				)
				(justify mirror)
			)
		)
		(property "License" "Apache-2.0"
			(at 0 0 270)
			(unlocked yes)
			(layer "B.Fab")
			(hide yes)
			(effects
				(font
					(size 1 1)
					(thickness 0.15)
				)
				(justify mirror)
			)
		)
		(sheetname "/")
		(sheetfile "jetson-agx-thor-baseboard.kicad_sch")
		(solder_paste_margin_ratio -1)
		(attr smd)
		(fp_circle
			(center 0 0)
			(end 3.05 0)
			(stroke
				(width 0.05)
				(type solid)
			)
			(fill no)
			(layer "B.CrtYd")
		)
		(fp_circle
			(center 0 0)
			(end 2.6 0)
			(stroke
				(width 0.15)
				(type solid)
			)
			(fill no)
			(layer "B.Fab")
		)
		(fp_text user "License: Apache-2.0"
			(at -9.6 -8.9 90)
			(layer "B.Fab")
			(effects
				(font
					(size 0.7 0.7)
					(thickness 0.15)
				)
				(justify left bottom mirror)
			)
		)
		(fp_text user "${REFERENCE}"
			(at -9.6 -6.5 90)
			(layer "B.Fab")
			(effects
				(font
					(size 0.7 0.7)
					(thickness 0.15)
				)
				(justify left bottom mirror)
			)
		)
		(fp_text user "Author: Antmicro"
			(at -9.6 -7.7 90)
			(layer "B.Fab")
			(effects
				(font
					(size 0.7 0.7)
					(thickness 0.15)
				)
				(justify left bottom mirror)
			)
		)
		(pad "" smd custom
			(at -1.7 -1.7 180)
			(size 0.62 0.62)
			(layers "B.Paste")
			(thermal_bridge_angle 90)
			(options
				(clearance outline)
				(anchor circle)
			)
			(primitives
				(gr_arc
					(start 1.266786 0.24747)
					(mid 0.285453 -0.29439)
					(end -0.250195 -1.279127)
					(width 0.2)
				)
				(gr_arc
					(start 1.259603 0.339191)
					(mid 0.218448 -0.232561)
					(end -0.34334 -1.279127)
					(width 0.2)
				)
				(gr_arc
					(start 1.255279 0.431435)
					(mid 0.152481 -0.169693)
					(end -0.436309 -1.279127)
					(width 0.2)
				)
				(gr_arc
					(start 1.253811 0.524161)
					(mid 0.087542 -0.105784)
					(end -0.529126 -1.279127)
					(width 0.2)
				)
				(gr_arc
					(start 1.275473 0.621136)
					(mid 0.0309 -0.033527)
					(end -0.621807 -1.279127)
					(width 0.2)
				)
				(gr_arc
					(start 1.263664 0.711602)
					(mid -0.037759 0.026651)
					(end -0.71437 -1.279127)
					(width 0.2)
				)
				(gr_arc
					(start 1.253435 0.802342)
					(mid -0.105837 0.087395)
					(end -0.806826 -1.279127)
					(width 0.2)
				)
				(gr_arc
					(start 1.267475 0.897258)
					(mid -0.165236 0.156885)
					(end -0.899187 -1.279127)
					(width 0.2)
				)
				(gr_arc
					(start 1.270645 0.990112)
					(mid -0.228522 0.222449)
					(end -0.991463 -1.279127)
					(width 0.2)
				)
				(gr_arc
					(start 1.266278 1.081674)
					(mid -0.294507 0.285313)
					(end -1.083663 -1.279127)
					(width 0.2)
				)
				(gr_line
					(start 1.279127 0.250195)
					(end 1.279127 1.083663)
					(width 0.2)
				)
				(gr_line
					(start -0.250195 -1.279127)
					(end -1.083663 -1.279127)
					(width 0.2)
				)
			)
		)
		(pad "" smd custom
			(at -1.7 1.7 270)
			(size 0.62 0.62)
			(layers "B.Paste")
			(thermal_bridge_angle 90)
			(options
				(clearance outline)
				(anchor circle)
			)
			(primitives
				(gr_arc
					(start 1.266786 0.24747)
					(mid 0.285453 -0.29439)
					(end -0.250195 -1.279127)
					(width 0.2)
				)
				(gr_arc
					(start 1.259603 0.339191)
					(mid 0.218448 -0.232561)
					(end -0.34334 -1.279127)
					(width 0.2)
				)
				(gr_arc
					(start 1.255279 0.431435)
					(mid 0.152481 -0.169693)
					(end -0.436309 -1.279127)
					(width 0.2)
				)
				(gr_arc
					(start 1.253811 0.524161)
					(mid 0.087542 -0.105784)
					(end -0.529126 -1.279127)
					(width 0.2)
				)
				(gr_arc
					(start 1.275473 0.621136)
					(mid 0.0309 -0.033527)
					(end -0.621807 -1.279127)
					(width 0.2)
				)
				(gr_arc
					(start 1.263664 0.711602)
					(mid -0.037759 0.026651)
					(end -0.71437 -1.279127)
					(width 0.2)
				)
				(gr_arc
					(start 1.253435 0.802342)
					(mid -0.105837 0.087395)
					(end -0.806826 -1.279127)
					(width 0.2)
				)
				(gr_arc
					(start 1.267475 0.897258)
					(mid -0.165236 0.156885)
					(end -0.899187 -1.279127)
					(width 0.2)
				)
				(gr_arc
					(start 1.270645 0.990112)
					(mid -0.228522 0.222449)
					(end -0.991463 -1.279127)
					(width 0.2)
				)
				(gr_arc
					(start 1.266278 1.081674)
					(mid -0.294507 0.285313)
					(end -1.083663 -1.279127)
					(width 0.2)
				)
				(gr_line
					(start 1.279127 0.250195)
					(end 1.279127 1.083663)
					(width 0.2)
				)
				(gr_line
					(start -0.250195 -1.279127)
					(end -1.083663 -1.279127)
					(width 0.2)
				)
			)
		)
		(pad "" smd custom
			(at 1.7 -1.7 90)
			(size 0.62 0.62)
			(layers "B.Paste")
			(thermal_bridge_angle 90)
			(options
				(clearance outline)
				(anchor circle)
			)
			(primitives
				(gr_arc
					(start 1.266786 0.24747)
					(mid 0.285453 -0.29439)
					(end -0.250195 -1.279127)
					(width 0.2)
				)
				(gr_arc
					(start 1.259603 0.339191)
					(mid 0.218448 -0.232561)
					(end -0.34334 -1.279127)
					(width 0.2)
				)
				(gr_arc
					(start 1.255279 0.431435)
					(mid 0.152481 -0.169693)
					(end -0.436309 -1.279127)
					(width 0.2)
				)
				(gr_arc
					(start 1.253811 0.524161)
					(mid 0.087542 -0.105784)
					(end -0.529126 -1.279127)
					(width 0.2)
				)
				(gr_arc
					(start 1.275473 0.621136)
					(mid 0.0309 -0.033527)
					(end -0.621807 -1.279127)
					(width 0.2)
				)
				(gr_arc
					(start 1.263664 0.711602)
					(mid -0.037759 0.026651)
					(end -0.71437 -1.279127)
					(width 0.2)
				)
				(gr_arc
					(start 1.253435 0.802342)
					(mid -0.105837 0.087395)
					(end -0.806826 -1.279127)
					(width 0.2)
				)
				(gr_arc
					(start 1.267475 0.897258)
					(mid -0.165236 0.156885)
					(end -0.899187 -1.279127)
					(width 0.2)
				)
				(gr_arc
					(start 1.270645 0.990112)
					(mid -0.228522 0.222449)
					(end -0.991463 -1.279127)
					(width 0.2)
				)
				(gr_arc
					(start 1.266278 1.081674)
					(mid -0.294507 0.285313)
					(end -1.083663 -1.279127)
					(width 0.2)
				)
				(gr_line
					(start 1.279127 0.250195)
					(end 1.279127 1.083663)
					(width 0.2)
				)
				(gr_line
					(start -0.250195 -1.279127)
					(end -1.083663 -1.279127)
					(width 0.2)
				)
			)
		)
		(pad "" smd custom
			(at 1.7 1.7)
			(size 0.62 0.62)
			(layers "B.Paste")
			(thermal_bridge_angle 90)
			(options
				(clearance outline)
				(anchor circle)
			)
			(primitives
				(gr_arc
					(start 1.266786 0.24747)
					(mid 0.285453 -0.29439)
					(end -0.250195 -1.279127)
					(width 0.2)
				)
				(gr_arc
					(start 1.259603 0.339191)
					(mid 0.218448 -0.232561)
					(end -0.34334 -1.279127)
					(width 0.2)
				)
				(gr_arc
					(start 1.255279 0.431435)
					(mid 0.152481 -0.169693)
					(end -0.436309 -1.279127)
					(width 0.2)
				)
				(gr_arc
					(start 1.253811 0.524161)
					(mid 0.087542 -0.105784)
					(end -0.529126 -1.279127)
					(width 0.2)
				)
				(gr_arc
					(start 1.275473 0.621136)
					(mid 0.0309 -0.033527)
					(end -0.621807 -1.279127)
					(width 0.2)
				)
				(gr_arc
					(start 1.263664 0.711602)
					(mid -0.037759 0.026651)
					(end -0.71437 -1.279127)
					(width 0.2)
				)
				(gr_arc
					(start 1.253435 0.802342)
					(mid -0.105837 0.087395)
					(end -0.806826 -1.279127)
					(width 0.2)
				)
				(gr_arc
					(start 1.267475 0.897258)
					(mid -0.165236 0.156885)
					(end -0.899187 -1.279127)
					(width 0.2)
				)
				(gr_arc
					(start 1.270645 0.990112)
					(mid -0.228522 0.222449)
					(end -0.991463 -1.279127)
					(width 0.2)
				)
				(gr_arc
					(start 1.266278 1.081674)
					(mid -0.294507 0.285313)
					(end -1.083663 -1.279127)
					(width 0.2)
				)
				(gr_line
					(start 1.279127 0.250195)
					(end 1.279127 1.083663)
					(width 0.2)
				)
				(gr_line
					(start -0.250195 -1.279127)
					(end -1.083663 -1.279127)
					(width 0.2)
				)
			)
		)
		(pad "1" thru_hole circle
			(at 0 0 270)
			(size 6 6)
			(drill 3.7)
			(layers "*.Cu" "*.Mask")
			(remove_unused_layers no)
			(net 1 "GND")
			(pintype "passive")
		)
	)
	(footprint "antmicro-footprints:C_0805_2012Metric"
		(layer "B.Cu")
		(at 229.4 133.8 90)
		(descr "Capacitor SMD 0805")
		(tags "capacitor SMD 0805")
		(property "Reference" "C105"
			(at -1.4 -1.9 90)
			(layer "B.SilkS")
			(effects
				(font
					(size 0.7 0.7)
					(thickness 0.15)
				)
				(justify right top mirror)
			)
		)
		(property "Value" "C_22u_25V_0805"
			(at -2.055717 -1.963153 90)
			(layer "B.Fab")
			(effects
				(font
					(size 0.7 0.7)
					(thickness 0.15)
				)
				(justify right top mirror)
			)
		)
		(property "Datasheet" "https://product.samsungsem.com/mlcc/CL21A226MAYNNN.do"
			(at 0 0 90)
			(layer "B.Fab")
			(hide yes)
			(effects
				(font
					(size 1.27 1.27)
					(thickness 0.15)
				)
				(justify mirror)
			)
		)
		(property "Description" "SMT Multilayer Ceramic Capacitor, 22uF, +/-20%, 25V, X5R, 0805 [2012 Metric]"
			(at 0 0 90)
			(layer "B.Fab")
			(hide yes)
			(effects
				(font
					(size 1.27 1.27)
					(thickness 0.15)
				)
				(justify mirror)
			)
		)
		(property "Manufacturer" "Samsung Electro-Mechanics"
			(at 0 0 90)
			(unlocked yes)
			(layer "B.Fab")
			(hide yes)
			(effects
				(font
					(size 1 1)
					(thickness 0.15)
				)
				(justify mirror)
			)
		)
		(property "MPN" "CL21A226MAYNNNE"
			(at 0 0 90)
			(unlocked yes)
			(layer "B.Fab")
			(hide yes)
			(effects
				(font
					(size 1 1)
					(thickness 0.15)
				)
				(justify mirror)
			)
		)
		(property "Val" "22u"
			(at 0 0 90)
			(unlocked yes)
			(layer "B.Fab")
			(hide yes)
			(effects
				(font
					(size 1 1)
					(thickness 0.15)
				)
				(justify mirror)
			)
		)
		(property "License" "Apache-2.0"
			(at 0 0 90)
			(unlocked yes)
			(layer "B.Fab")
			(hide yes)
			(effects
				(font
					(size 1 1)
					(thickness 0.15)
				)
				(justify mirror)
			)
		)
		(property "Author" "Antmicro"
			(at 0 0 90)
			(unlocked yes)
			(layer "B.Fab")
			(hide yes)
			(effects
				(font
					(size 1 1)
					(thickness 0.15)
				)
				(justify mirror)
			)
		)
		(property "Voltage" "25V"
			(at 0 0 90)
			(unlocked yes)
			(layer "B.Fab")
			(hide yes)
			(effects
				(font
					(size 1 1)
					(thickness 0.15)
				)
				(justify mirror)
			)
		)
		(property "Dielectric" "X5R"
			(at 0 0 90)
			(unlocked yes)
			(layer "B.Fab")
			(hide yes)
			(effects
				(font
					(size 1 1)
					(thickness 0.15)
				)
				(justify mirror)
			)
		)
		(property "Public" "False"
			(at 0 0 90)
			(unlocked yes)
			(layer "B.Fab")
			(hide yes)
			(effects
				(font
					(size 1 1)
					(thickness 0.15)
				)
				(justify mirror)
			)
		)
		(sheetname "/USB Hub/")
		(sheetfile "usb_hub.kicad_sch")
		(attr smd)
		(fp_line
			(start -0.3 -0.7)
			(end 0.3 -0.7)
			(stroke
				(width 0.15)
				(type solid)
			)
			(layer "B.SilkS")
		)
		(fp_line
			(start -0.3 0.7)
			(end 0.3 0.7)
			(stroke
				(width 0.15)
				(type solid)
			)
			(layer "B.SilkS")
		)
		(fp_poly
			(pts
				(xy 1.95 0.9) (xy -1.95 0.9) (xy -1.95 -0.9) (xy 1.95 -0.9)
			)
			(stroke
				(width 0.05)
				(type default)
			)
			(fill no)
			(layer "B.CrtYd")
		)
		(fp_poly
			(pts
				(xy -0.95 0.675001) (xy 0.95 0.675001) (xy 0.95 -0.675001) (xy -0.95 -0.675001)
			)
			(stroke
				(width 0.15)
				(type solid)
			)
			(fill no)
			(layer "B.Fab")
		)
		(fp_text user "License: Apache-2.0"
			(at -1.9 -4.947 90)
			(layer "B.Fab")
			(effects
				(font
					(size 0.7 0.7)
					(thickness 0.15)
				)
				(justify right top mirror)
			)
		)
		(fp_text user "${REFERENCE}"
			(at -1.899999 -3.947 90)
			(layer "B.Fab")
			(effects
				(font
					(size 0.7 0.7)
					(thickness 0.15)
				)
				(justify right top mirror)
			)
		)
		(fp_text user "Author: Antmicro"
			(at -1.9 -5.947 90)
			(layer "B.Fab")
			(effects
				(font
					(size 0.7 0.7)
					(thickness 0.15)
				)
				(justify right top mirror)
			)
		)
		(pad "1" smd roundrect
			(at -1.099999 0 90)
			(size 1.2 1.3)
			(layers "B.Cu" "B.Mask" "B.Paste")
			(roundrect_rratio 0.25)
			(net 115 "/USB Hub/USBC4_VBUS")
			(pintype "passive")
		)
		(pad "2" smd roundrect
			(at 1.099999 0 90)
			(size 1.2 1.3)
			(layers "B.Cu" "B.Mask" "B.Paste")
			(roundrect_rratio 0.25)
			(net 1 "GND")
			(pintype "passive")
		)
	)
	(gr_line
		(start 237.2 153.71)
		(end 233.930532 153.71)
		(stroke
			(width 0.1)
			(type solid)
		)
		(locked yes)
		(layer "Edge.Cuts")
	)
	(gr_line
		(start 59.930532 53.71)
		(end 59.930532 153.71)
		(stroke
			(width 0.1)
			(type default)
		)
		(locked yes)
		(layer "Edge.Cuts")
	)
	(gr_line
		(start 239.930532 136.71)
		(end 239.930532 53.71)
		(stroke
			(width 0.1)
			(type default)
		)
		(locked yes)
		(layer "Edge.Cuts")
	)
	(gr_line
		(start 239.930532 53.71)
		(end 59.930532 53.71)
		(stroke
			(width 0.1)
			(type solid)
		)
		(locked yes)
		(layer "Edge.Cuts")
	)
	(gr_line
		(start 237.2 136.71)
		(end 239.930532 136.71)
		(stroke
			(width 0.1)
			(type solid)
		)
		(locked yes)
		(layer "Edge.Cuts")
	)
	(gr_line
		(start 59.930532 153.71)
		(end 233.930532 153.71)
		(stroke
			(width 0.1)
			(type solid)
		)
		(locked yes)
		(layer "Edge.Cuts")
	)
	(gr_line
		(start 237.2 153.71)
		(end 237.2 136.71)
		(stroke
			(width 0.1)
			(type default)
		)
		(locked yes)
		(layer "Edge.Cuts")
	)
	(segment
		(start 182.325 143.525)
		(end 182.18 143.38)
		(width 0.2)
		(layer "F.Cu")
		(net 1)
	)
	(segment
		(start 95.9 58.86)
		(end 97.21 58.86)
		(width 0.2)
		(layer "F.Cu")
		(net 1)
	)
	(segment
		(start 229.93 128.2)
		(end 229.93 128.36)
		(width 0.2)
		(layer "F.Cu")
		(net 1)
	)
	(segment
		(start 188.400999 55.147)
		(end 188.95 54.597999)
		(width 0.2)
		(layer "F.Cu")
		(net 1)
	)
	(segment
		(start 182.93 128.525)
		(end 183.995 128.525)
		(width 0.2)
		(layer "F.Cu")
		(net 1)
	)
	(segment
		(start 221.756 99.26)
		(end 222.36 99.26)
		(width 0.1)
		(layer "F.Cu")
		(net 1)
	)
	(segment
		(start 142.772 133.95)
		(end 142.054 133.95)
		(width 0.3)
		(layer "F.Cu")
		(net 1)
	)
	(segment
		(start 213.912407 96.987593)
		(end 214 96.9)
		(width 0.3)
		(layer "F.Cu")
		(net 1)
	)
	(segment
		(start 197.658 58.158)
		(end 197.658 59.8)
		(width 0.2)
		(layer "F.Cu")
		(net 1)
	)
	(segment
		(start 187.815907 61.400242)
		(end 187.840523 61.400242)
		(width 0.15)
		(layer "F.Cu")
		(net 1)
	)
	(segment
		(start 152.23 113.749)
		(end 152.23 114.57)
		(width 0.2)
		(layer "F.Cu")
		(net 1)
	)
	(segment
		(start 160.605 145.228)
		(end 159.222 145.228)
		(width 0.15)
		(layer "F.Cu")
		(net 1)
	)
	(segment
		(start 130.365 135.29)
		(end 130.365 134.335)
		(width 0.3)
		(layer "F.Cu")
		(net 1)
	)
	(segment
		(start 197.55 88.92)
		(end 197.55 89.75)
		(width 0.1)
		(layer "F.Cu")
		(net 1)
	)
	(segment
		(start 99.916002 55.89)
		(end 97.95 55.89)
		(width 0.2)
		(layer "F.Cu")
		(net 1)
	)
	(segment
		(start 229.930532 117.439468)
		(end 229.87 117.5)
		(width 0.3)
		(layer "F.Cu")
		(net 1)
	)
	(segment
		(start 193.048 54.598)
		(end 193.795999 54.598)
		(width 0.2)
		(layer "F.Cu")
		(net 1)
	)
	(segment
		(start 235.430532 78.539468)
		(end 235.37 78.6)
		(width 0.2)
		(layer "F.Cu")
		(net 1)
	)
	(segment
		(start 181.565 110.175)
		(end 181.49 110.25)
		(width 0.2)
		(layer "F.Cu")
		(net 1)
	)
	(segment
		(start 198.25 85.25)
		(end 198.2 85.3)
		(width 0.1)
		(layer "F.Cu")
		(net 1)
	)
	(segment
		(start 191.102 85.198)
		(end 191 85.3)
		(width 0.2)
		(layer "F.Cu")
		(net 1)
	)
	(segment
		(start 193.795999 54.598)
		(end 193.798 54.595999)
		(width 0.2)
		(layer "F.Cu")
		(net 1)
	)
	(segment
		(start 212.58 133.1)
		(end 212.58 133.67)
		(width 0.2)
		(layer "F.Cu")
		(net 1)
	)
	(segment
		(start 210.73 133.68)
		(end 210.75 133.7)
		(width 0.2)
		(layer "F.Cu")
		(net 1)
	)
	(segment
		(start 160.997234 80.652234)
		(end 160.997234 79.657766)
		(width 0.15)
		(layer "F.Cu")
		(net 1)
	)
	(segment
		(start 62.12 85.45)
		(end 63.22 85.45)
		(width 0.2)
		(layer "F.Cu")
		(net 1)
	)
	(segment
		(start 206.48 77.9)
		(end 206.5 77.9)
		(width 0.1)
		(layer "F.Cu")
		(net 1)
	)
	(segment
		(start 224.751001 75.125)
		(end 224.751001 75.751001)
		(width 0.5)
		(layer "F.Cu")
		(net 1)
	)
	(segment
		(start 229.93 128.36)
		(end 229.930532 128.360532)
		(width 0.2)
		(layer "F.Cu")
		(net 1)
	)
	(segment
		(start 152.699999 101.299999)
		(end 152.8 101.4)
		(width 0.2)
		(layer "F.Cu")
		(net 1)
	)
	(segment
		(start 222.44 92.66)
		(end 222.45 92.65)
		(width 0.3)
		(layer "F.Cu")
		(net 1)
	)
	(segment
		(start 67.469 62.299)
		(end 68.099 62.299)
		(width 0.2)
		(layer "F.Cu")
		(net 1)
	)
	(segment
		(start 145.55 91)
		(end 145.51 91.04)
		(width 0.5)
		(layer "F.Cu")
		(net 1)
	)
	(segment
		(start 220.36 105.46)
		(end 220.35 105.45)
		(width 0.3)
		(layer "F.Cu")
		(net 1)
	)
	(segment
		(start 166.25 54.6)
		(end 184.25 54.6)
		(width 0.1)
		(layer "F.Cu")
		(net 1)
	)
	(segment
		(start 203.25 59.35)
		(end 202.9 59.7)
		(width 0.15)
		(layer "F.Cu")
		(net 1)
	)
	(segment
		(start 152.73 118.5)
		(end 152.48 118.75)
		(width 0.2)
		(layer "F.Cu")
		(net 1)
	)
	(segment
		(start 196.17 88.92)
		(end 196.17 89.77)
		(width 0.1)
		(layer "F.Cu")
		(net 1)
	)
	(segment
		(start 136.249 57.3)
		(end 135.949 57.6)
		(width 0.5)
		(layer "F.Cu")
		(net 1)
	)
	(segment
		(start 228.385 82)
		(end 227.613 82)
		(width 0.3)
		(layer "F.Cu")
		(net 1)
	)
	(segment
		(start 214.8 107.48)
		(end 214.8 108.2)
		(width 0.1)
		(layer "F.Cu")
		(net 1)
	)
	(segment
		(start 215.3 99.4)
		(end 215.246 99.454)
		(width 0.1)
		(layer "F.Cu")
		(net 1)
	)
	(segment
		(start 138.6 57.3)
		(end 137.15 57.3)
		(width 0.5)
		(layer "F.Cu")
		(net 1)
	)
	(segment
		(start 208 94)
		(end 208 93.592)
		(width 0.3)
		(layer "F.Cu")
		(net 1)
	)
	(segment
		(start 203.25 55.145)
		(end 203.248 55.147)
		(width 0.2)
		(layer "F.Cu")
		(net 1)
	)
	(segment
		(start 203.248 55.147)
		(end 204.400999 55.147)
		(width 0.2)
		(layer "F.Cu")
		(net 1)
	)
	(segment
		(start 91.253 59.503)
		(end 91.25 59.5)
		(width 0.2)
		(layer "F.Cu")
		(net 1)
	)
	(segment
		(start 235.430532 77.3475)
		(end 235.430532 78.539468)
		(width 0.2)
		(layer "F.Cu")
		(net 1)
	)
	(segment
		(start 229.930532 88.0725)
		(end 229.930532 87.010532)
		(width 0.2)
		(layer "F.Cu")
		(net 1)
	)
	(segment
		(start 160.79 73.56)
		(end 160.8 73.55)
		(width 0.2)
		(layer "F.Cu")
		(net 1)
	)
	(segment
		(start 235.430532 128.130532)
		(end 235.5 128.2)
		(width 0.2)
		(layer "F.Cu")
		(net 1)
	)
	(segment
		(start 220.43 117.625)
		(end 221.202 117.625)
		(width 0.3)
		(layer "F.Cu")
		(net 1)
	)
	(segment
		(start 211.42 95.88)
		(end 211.4 95.9)
		(width 0.3)
		(layer "F.Cu")
		(net 1)
	)
	(segment
		(start 95.9 59.4)
		(end 95.9 58.86)
		(width 0.2)
		(layer "F.Cu")
		(net 1)
	)
	(segment
		(start 162.925 140.475)
		(end 162.95 140.5)
		(width 0.15)
		(layer "F.Cu")
		(net 1)
	)
	(segment
		(start 127.594212 63.49)
		(end 127.594212 64.164213)
		(width 0.2)
		(layer "F.Cu")
		(net 1)
	)
	(segment
		(start 183.535 127.175)
		(end 184.04 126.67)
		(width 0.2)
		(layer "F.Cu")
		(net 1)
	)
	(segment
		(start 167.6 141.6)
		(end 167.6 141)
		(width 0.2)
		(layer "F.Cu")
		(net 1)
	)
	(segment
		(start 181.85 138.85)
		(end 180.859468 138.85)
		(width 0.2)
		(layer "F.Cu")
		(net 1)
	)
	(segment
		(start 198.27 73.5)
		(end 198.27 72.77)
		(width 0.2)
		(layer "F.Cu")
		(net 1)
	)
	(segment
		(start 196.952 54.6)
		(end 196.204001 54.6)
		(width 0.2)
		(layer "F.Cu")
		(net 1)
	)
	(segment
		(start 220.982 102.36)
		(end 222.36 102.36)
		(width 0.3)
		(layer "F.Cu")
		(net 1)
	)
	(segment
		(start 157.82 141.88)
		(end 157.85 141.85)
		(width 0.15)
		(layer "F.Cu")
		(net 1)
	)
	(segment
		(start 212.58 133.67)
		(end 212.5 133.75)
		(width 0.2)
		(layer "F.Cu")
		(net 1)
	)
	(segment
		(start 181.897112 123.717356)
		(end 182.126775 123.947019)
		(width 0.2)
		(layer "F.Cu")
		(net 1)
	)
	(segment
		(start 221.754 102.36)
		(end 222.36 102.36)
		(width 0.1)
		(layer "F.Cu")
		(net 1)
	)
	(segment
		(start 126.244212 64.685787)
		(end 126.049999 64.88)
		(width 0.2)
		(layer "F.Cu")
		(net 1)
	)
	(segment
		(start 181.504296 123.67)
		(end 181.513471 123.679175)
		(width 0.2)
		(layer "F.Cu")
		(net 1)
	)
	(segment
		(start 182.93 127.175)
		(end 183.535 127.175)
		(width 0.2)
		(layer "F.Cu")
		(net 1)
	)
	(segment
		(start 229.930532 89.239468)
		(end 229.97 89.2)
		(width 0.2)
		(layer "F.Cu")
		(net 1)
	)
	(segment
		(start 235.430532 102.29)
		(end 235.430532 103.3475)
		(width 0.2)
		(layer "F.Cu")
		(net 1)
	)
	(segment
		(start 140.372 133.95)
		(end 139.654 133.95)
		(width 0.3)
		(layer "F.Cu")
		(net 1)
	)
	(segment
		(start 229.93 128.2)
		(end 229.93 128.04)
		(width 0.2)
		(layer "F.Cu")
		(net 1)
	)
	(segment
		(start 95.530329 59.4)
		(end 95.505329 59.425)
		(width 0.2)
		(layer "F.Cu")
		(net 1)
	)
	(segment
		(start 181.64 70.975)
		(end 179.2 70.975)
		(width 0.2)
		(layer "F.Cu")
		(net 1)
	)
	(segment
		(start 186.7 121.6)
		(end 186.7 122.279)
		(width 0.2)
		(layer "F.Cu")
		(net 1)
	)
	(segment
		(start 210.72 81.3)
		(end 210.7 81.3)
		(width 0.2)
		(layer "F.Cu")
		(net 1)
	)
	(segment
		(start 169.579468 135.92)
		(end 169.579468 135.2)
		(width 0.15)
		(layer "F.Cu")
		(net 1)
	)
	(segment
		(start 180.49 128.525)
		(end 180.24 128.775)
		(width 0.2)
		(layer "F.Cu")
		(net 1)
	)
	(segment
		(start 153.075 105.01)
		(end 154.675 105.01)
		(width 0.1)
		(layer "F.Cu")
		(net 1)
	)
	(segment
		(start 142.845 55.975)
		(end 142.52 56.3)
		(width 0.3)
		(layer "F.Cu")
		(net 1)
	)
	(segment
		(start 160.605 144.23)
		(end 161.27 144.23)
		(width 0.15)
		(layer "F.Cu")
		(net 1)
	)
	(segment
		(start 214.9 97.72)
		(end 214.9 97)
		(width 0.1)
		(layer "F.Cu")
		(net 1)
	)
	(segment
		(start 137.202 133.948)
		(end 137.2 133.95)
		(width 0.3)
		(layer "F.Cu")
		(net 1)
	)
	(segment
		(start 206.48 79.205)
		(end 206.495 79.205)
		(width 0.1)
		(layer "F.Cu")
		(net 1)
	)
	(segment
		(start 139.4 104.32)
		(end 139.4 103.4)
		(width 0.2)
		(layer "F.Cu")
		(net 1)
	)
	(segment
		(start 197.726 148.7)
		(end 199.126 148.7)
		(width 0.2)
		(layer "F.Cu")
		(net 1)
	)
	(segment
		(start 236.240532 95.71)
		(end 236.240532 97.340532)
		(width 0.2)
		(layer "F.Cu")
		(net 1)
	)
	(segment
		(start 171.009468 119.216)
		(end 171.009468 119.594468)
		(width 0.15)
		(layer "F.Cu")
		(net 1)
	)
	(segment
		(start 181.64 69.625)
		(end 180.265 69.625)
		(width 0.2)
		(layer "F.Cu")
		(net 1)
	)
	(segment
		(start 164.675 143.025)
		(end 165.580532 143.025)
		(width 0.3)
		(layer "F.Cu")
		(net 1)
	)
	(segment
		(start 229.930532 87.010532)
		(end 229.82 86.9)
		(width 0.2)
		(layer "F.Cu")
		(net 1)
	)
	(segment
		(start 140.24 131.648)
		(end 139.248 131.648)
		(width 0.2)
		(layer "F.Cu")
		(net 1)
	)
	(segment
		(start 126.244212 61.05)
		(end 125.994212 60.8)
		(width 0.2)
		(layer "F.Cu")
		(net 1)
	)
	(segment
		(start 182.94 111.525)
		(end 180.5 111.525)
		(width 0.2)
		(layer "F.Cu")
		(net 1)
	)
	(segment
		(start 187.840523 61.400242)
		(end 187.842281 61.402)
		(width 0.15)
		(layer "F.Cu")
		(net 1)
	)
	(segment
		(start 97.93 55.87)
		(end 97.95 55.89)
		(width 0.1)
		(layer "F.Cu")
		(net 1)
	)
	(segment
		(start 179.604468 86.245)
		(end 179.604468 86.420532)
		(width 0.15)
		(layer "F.Cu")
		(net 1)
	)
	(segment
		(start 63.9 98.48)
		(end 63.9 98.5)
		(width 0.2)
		(layer "F.Cu")
		(net 1)
	)
	(segment
		(start 162.297234 83.252234)
		(end 162.297234 84.147234)
		(width 0.15)
		(layer "F.Cu")
		(net 1)
	)
	(segment
		(start 142.054 133.95)
		(end 142.052 133.952)
		(width 0.3)
		(layer "F.Cu")
		(net 1)
	)
	(segment
		(start 229.930532 115.160532)
		(end 229.97 115.2)
		(width 0.2)
		(layer "F.Cu")
		(net 1)
	)
	(segment
		(start 182.94 110.175)
		(end 181.565 110.175)
		(width 0.2)
		(layer "F.Cu")
		(net 1)
	)
	(segment
		(start 135.9 58.6)
		(end 135.949 58.551)
		(width 0.5)
		(layer "F.Cu")
		(net 1)
	)
	(segment
		(start 152.96 121.5)
		(end 153.8 121.5)
		(width 0.2)
		(layer "F.Cu")
		(net 1)
	)
	(segment
		(start 210.4 64.9)
		(end 210.4 63.415)
		(width 0.3)
		(layer "F.Cu")
		(net 1)
	)
	(segment
		(start 214.08 127.2)
		(end 214.7 127.2)
		(width 0.2)
		(layer "F.Cu")
		(net 1)
	)
	(segment
		(start 211.25 55.149001)
		(end 212.402999 55.149001)
		(width 0.2)
		(layer "F.Cu")
		(net 1)
	)
	(segment
		(start 135.949 58.249)
		(end 136.3 58.6)
		(width 0.5)
		(layer "F.Cu")
		(net 1)
	)
	(segment
		(start 130.8 143.68)
		(end 131.78 143.68)
		(width 0.1)
		(layer "F.Cu")
		(net 1)
	)
	(segment
		(start 152.8 101.4)
		(end 154 101.4)
		(width 0.2)
		(layer "F.Cu")
		(net 1)
	)
	(segment
		(start 111.530532 78.530532)
		(end 111.530532 78.15)
		(width 0.2)
		(layer "F.Cu")
		(net 1)
	)
	(segment
		(start 181.513471 123.679175)
		(end 181.513471 123.717356)
		(width 0.2)
		(layer "F.Cu")
		(net 1)
	)
	(segment
		(start 61.05 85.47)
		(end 61.03 85.47)
		(width 0.2)
		(layer "F.Cu")
		(net 1)
	)
	(segment
		(start 141 133.95)
		(end 141.002 133.952)
		(width 0.3)
		(layer "F.Cu")
		(net 1)
	)
	(segment
		(start 131.985349 60.98)
		(end 131.985349 58.295352)
		(width 0.3)
		(layer "F.Cu")
		(net 1)
	)
	(segment
		(start 170.879468 137.520532)
		(end 170.9 137.5)
		(width 0.15)
		(layer "F.Cu")
		(net 1)
	)
	(segment
		(start 151 101.4)
		(end 150.9 101.3)
		(width 0.2)
		(layer "F.Cu")
		(net 1)
	)
	(segment
		(start 200.7 134.18)
		(end 200.7 134.9)
		(width 0.2)
		(layer "F.Cu")
		(net 1)
	)
	(segment
		(start 104.695 56.205)
		(end 104.91 55.99)
		(width 0.2)
		(layer "F.Cu")
		(net 1)
	)
	(segment
		(start 60.6 91.5)
		(end 60.6 91)
		(width 0.2)
		(layer "F.Cu")
		(net 1)
	)
	(segment
		(start 160.605 144.23)
		(end 159.833 144.23)
		(width 0.15)
		(layer "F.Cu")
		(net 1)
	)
	(segment
		(start 152.300001 101.299999)
		(end 152.2 101.4)
		(width 0.2)
		(layer "F.Cu")
		(net 1)
	)
	(segment
		(start 95.9 59.4)
		(end 95.530329 59.4)
		(width 0.2)
		(layer "F.Cu")
		(net 1)
	)
	(segment
		(start 160.605 143.23)
		(end 159.13 143.23)
		(width 0.15)
		(layer "F.Cu")
		(net 1)
	)
	(segment
		(start 204.08 135.7)
		(end 204.9 135.7)
		(width 0.1)
		(layer "F.Cu")
		(net 1)
	)
	(segment
		(start 112.230532 79.230532)
		(end 111.530532 78.530532)
		(width 0.2)
		(layer "F.Cu")
		(net 1)
	)
	(segment
		(start 152 109.5)
		(end 151.3 109.5)
		(width 0.2)
		(layer "F.Cu")
		(net 1)
	)
	(segment
		(start 66.75 85.4)
		(end 66.75 85.05)
		(width 0.2)
		(layer "F.Cu")
		(net 1)
	)
	(segment
		(start 212.42 134.7)
		(end 212.4 134.72)
		(width 0.2)
		(layer "F.Cu")
		(net 1)
	)
	(segment
		(start 186.7 122.279)
		(end 186.68 122.299)
		(width 0.2)
		(layer "F.Cu")
		(net 1)
	)
	(segment
		(start 151.8 102.15)
		(end 151.05 102.15)
		(width 0.2)
		(layer "F.Cu")
		(net 1)
	)
	(segment
		(start 105.530532 85.369468)
		(end 106.230532 84.669468)
		(width 0.2)
		(layer "F.Cu")
		(net 1)
	)
	(segment
		(start 179.2 90.975)
		(end 181.64 90.975)
		(width 0.2)
		(layer "F.Cu")
		(net 1)
	)
	(segment
		(start 182.764468 91.085)
		(end 182.654468 90.975)
		(width 0.2)
		(layer "F.Cu")
		(net 1)
	)
	(segment
		(start 182.94 143.525)
		(end 184.039468 143.525)
		(width 0.2)
		(layer "F.Cu")
		(net 1)
	)
	(segment
		(start 157.81 141.88)
		(end 157.82 141.88)
		(width 0.15)
		(layer "F.Cu")
		(net 1)
	)
	(segment
		(start 229.930532 99.910532)
		(end 229.92 99.9)
		(width 0.3)
		(layer "F.Cu")
		(net 1)
	)
	(segment
		(start 135.495 54.875)
		(end 133.805 54.875)
		(width 0.1)
		(layer "F.Cu")
		(net 1)
	)
	(segment
		(start 152.3 102.05)
		(end 151.9 102.05)
		(width 0.2)
		(layer "F.Cu")
		(net 1)
	)
	(segment
		(start 131.985349 60.98)
		(end 131.029999 60.98)
		(width 0.2)
		(layer "F.Cu")
		(net 1)
	)
	(segment
		(start 131.935349 63.98)
		(end 131.029999 63.98)
		(width 0.2)
		(layer "F.Cu")
		(net 1)
	)
	(segment
		(start 196.72 127.88)
		(end 196.7 127.9)
		(width 0.1)
		(layer "F.Cu")
		(net 1)
	)
	(segment
		(start 214.48 123.68)
		(end 213.98 123.68)
		(width 0.2)
		(layer "F.Cu")
		(net 1)
	)
	(segment
		(start 151.02 107.37)
		(end 150.5 106.85)
		(width 0.2)
		(layer "F.Cu")
		(net 1)
	)
	(segment
		(start 211.442 134.72)
		(end 211.286 134.564)
		(width 0.2)
		(layer "F.Cu")
		(net 1)
	)
	(segment
		(start 221.24 128.5)
		(end 221.8 128.5)
		(width 0.2)
		(layer "F.Cu")
		(net 1)
	)
	(segment
		(start 127.594212 64.164213)
		(end 128.299999 64.87)
		(width 0.2)
		(layer "F.Cu")
		(net 1)
	)
	(segment
		(start 152.73 117.251)
		(end 152.73 116.33)
		(width 0.2)
		(layer "F.Cu")
		(net 1)
	)
	(segment
		(start 215.246 100.125)
		(end 215.246 102.325)
		(width 0.3)
		(layer "F.Cu")
		(net 1)
	)
	(segment
		(start 157.06 144.78)
		(end 156.89 144.95)
		(width 0.15)
		(layer "F.Cu")
		(net 1)
	)
	(segment
		(start 197.23 57.73)
		(end 197.658 58.158)
		(width 0.2)
		(layer "F.Cu")
		(net 1)
	)
	(segment
		(start 211.142 121.301)
		(end 209.699 121.301)
		(width 0.2)
		(layer "F.Cu")
		(net 1)
	)
	(segment
		(start 96.93 55.87)
		(end 97.93 55.87)
		(width 0.1)
		(layer "F.Cu")
		(net 1)
	)
	(segment
		(start 195.25 54.625)
		(end 195.25 55.149001)
		(width 0.2)
		(layer "F.Cu")
		(net 1)
	)
	(segment
		(start 235.430532 86.939468)
		(end 235.47 86.9)
		(width 0.2)
		(layer "F.Cu")
		(net 1)
	)
	(segment
		(start 146.400001 91)
		(end 145.55 91)
		(width 0.5)
		(layer "F.Cu")
		(net 1)
	)
	(segment
		(start 229.930532 91.539468)
		(end 229.87 91.6)
		(width 0.2)
		(layer "F.Cu")
		(net 1)
	)
	(segment
		(start 182.364468 69.625)
		(end 182.764468 69.225)
		(width 0.2)
		(layer "F.Cu")
		(net 1)
	)
	(segment
		(start 221.199 114.527)
		(end 222.177 114.527)
		(width 0.3)
		(layer "F.Cu")
		(net 1)
	)
	(segment
		(start 68.099 62.299)
		(end 68.2 62.4)
		(width 0.2)
		(layer "F.Cu")
		(net 1)
	)
	(segment
		(start 63.2 99.2)
		(end 62.7 99.2)
		(width 0.2)
		(layer "F.Cu")
		(net 1)
	)
	(segment
		(start 235.430532 127.0725)
		(end 235.430532 128.130532)
		(width 0.2)
		(layer "F.Cu")
		(net 1)
	)
	(segment
		(start 66.754 90.301)
		(end 66.754 89.446)
		(width 0.2)
		(layer "F.Cu")
		(net 1)
	)
	(segment
		(start 229.930532 101.0725)
		(end 229.930532 99.910532)
		(width 0.3)
		(layer "F.Cu")
		(net 1)
	)
	(segment
		(start 106.230532 84.669468)
		(end 106.230532 84.15)
		(width 0.2)
		(layer "F.Cu")
		(net 1)
	)
	(segment
		(start 62.7 89.5)
		(end 62.7 90.055)
		(width 0.2)
		(layer "F.Cu")
		(net 1)
	)
	(segment
		(start 143.2 55.975)
		(end 142.845 55.975)
		(width 0.3)
		(layer "F.Cu")
		(net 1)
	)
	(segment
		(start 65.7 84.74)
		(end 65.68 84.76)
		(width 0.2)
		(layer "F.Cu")
		(net 1)
	)
	(segment
		(start 187.815907 61.400242)
		(end 187.793415 61.37775)
		(width 0.15)
		(layer "F.Cu")
		(net 1)
	)
	(segment
		(start 138.931999 109.3)
		(end 138.9 109.331999)
		(width 0.1)
		(layer "F.Cu")
		(net 1)
	)
	(segment
		(start 229.87 112.9)
		(end 229.87 113)
		(width 0.3)
		(layer "F.Cu")
		(net 1)
	)
	(segment
		(start 182.126775 123.947019)
		(end 182.602981 123.947019)
		(width 0.2)
		(layer "F.Cu")
		(net 1)
	)
	(segment
		(start 95.9 59.4)
		(end 95.9 60.3)
		(width 0.2)
		(layer "F.Cu")
		(net 1)
	)
	(segment
		(start 215.246 104.526)
		(end 215.246 105.554)
		(width 0.1)
		(layer "F.Cu")
		(net 1)
	)
	(segment
		(start 210.4 63.1)
		(end 210.4 63.415)
		(width 0.1)
		(layer "F.Cu")
		(net 1)
	)
	(segment
		(start 229.930532 116.3475)
		(end 229.930532 117.439468)
		(width 0.3)
		(layer "F.Cu")
		(net 1)
	)
	(segment
		(start 209.699 121.301)
		(end 208.5 122.5)
		(width 0.2)
		(layer "F.Cu")
		(net 1)
	)
	(segment
		(start 109.178 64.448)
		(end 109.86 65.13)
		(width 0.1)
		(layer "F.Cu")
		(net 1)
	)
	(segment
		(start 222.177 114.527)
		(end 222.2 114.55)
		(width 0.3)
		(layer "F.Cu")
		(net 1)
	)
	(segment
		(start 182.94 142.175)
		(end 181.49 142.175)
		(width 0.2)
		(layer "F.Cu")
		(net 1)
	)
	(segment
		(start 180.8 106.67)
		(end 181.75 106.67)
		(width 0.2)
		(layer "F.Cu")
		(net 1)
	)
	(segment
		(start 161.079468 99.795532)
		(end 161.079468 100.775)
		(width 0.2)
		(layer "F.Cu")
		(net 1)
	)
	(segment
		(start 153.8 100.8)
		(end 154 101)
		(width 0.2)
		(layer "F.Cu")
		(net 1)
	)
	(segment
		(start 229.930532 89.160532)
		(end 229.97 89.2)
		(width 0.2)
		(layer "F.Cu")
		(net 1)
	)
	(segment
		(start 134.8 66.6)
		(end 134.8 65.400999)
		(width 0.3)
		(layer "F.Cu")
		(net 1)
	)
	(segment
		(start 137.52 104.32)
		(end 137.4 104.2)
		(width 0.2)
		(layer "F.Cu")
		(net 1)
	)
	(segment
		(start 212.912407 97.732991)
		(end 213.912407 97.732991)
		(width 0.3)
		(layer "F.Cu")
		(net 1)
	)
	(segment
		(start 82.85 57.998)
		(end 82.252 57.998)
		(width 0.1)
		(layer "F.Cu")
		(net 1)
	)
	(segment
		(start 131.985349 58.295352)
		(end 131.229996 57.539999)
		(width 0.3)
		(layer "F.Cu")
		(net 1)
	)
	(segment
		(start 187.793415 61.37775)
		(end 187.326751 61.37775)
		(width 0.15)
		(layer "F.Cu")
		(net 1)
	)
	(segment
		(start 94.48 61.5)
		(end 95.05 61.5)
		(width 0.1)
		(layer "F.Cu")
		(net 1)
	)
	(segment
		(start 203.7 134.28)
		(end 203.7 134.9)
		(width 0.2)
		(layer "F.Cu")
		(net 1)
	)
	(segment
		(start 61.03 85.47)
		(end 60.6 85.9)
		(width 0.2)
		(layer "F.Cu")
		(net 1)
	)
	(segment
		(start 201.199 82.599)
		(end 201.199 81.831)
		(width 0.2)
		(layer "F.Cu")
		(net 1)
	)
	(segment
		(start 187.25 54.5)
		(end 187.25 55.145)
		(width 0.2)
		(layer "F.Cu")
		(net 1)
	)
	(segment
		(start 235.5 128.27)
		(end 235.430532 128.339468)
		(width 0.2)
		(layer "F.Cu")
		(net 1)
	)
	(segment
		(start 187.326751 61.37775)
		(end 187.3 61.350999)
		(width 0.15)
		(layer "F.Cu")
		(net 1)
	)
	(segment
		(start 235.430532 73.760532)
		(end 235.37 73.7)
		(width 0.2)
		(layer "F.Cu")
		(net 1)
	)
	(segment
		(start 91.5 150.11)
		(end 91.5 150.74)
		(width 0.2)
		(layer "F.Cu")
		(net 1)
	)
	(segment
		(start 142.06 58.32)
		(end 142.79 58.32)
		(width 0.2)
		(layer "F.Cu")
		(net 1)
	)
	(segment
		(start 236.350532 108.6)
		(end 236.240532 108.71)
		(width 0.2)
		(layer "F.Cu")
		(net 1)
	)
	(segment
		(start 236.240532 134.323)
		(end 236.923 134.323)
		(width 0.3)
		(layer "F.Cu")
		(net 1)
	)
	(segment
		(start 128.12 133.28)
		(end 127.8 133.6)
		(width 0.3)
		(layer "F.Cu")
		(net 1)
	)
	(segment
		(start 96.95 55.89)
		(end 96.93 55.87)
		(width 0.1)
		(layer "F.Cu")
		(net 1)
	)
	(segment
		(start 235.430532 88.0725)
		(end 235.430532 89.160532)
		(width 0.2)
		(layer "F.Cu")
		(net 1)
	)
	(segment
		(start 196.395 116.595)
		(end 196.4 116.6)
		(width 0.3)
		(layer "F.Cu")
		(net 1)
	)
	(segment
		(start 126.244212 63.49)
		(end 126.244212 64.685787)
		(width 0.2)
		(layer "F.Cu")
		(net 1)
	)
	(segment
		(start 235.430532 114.0725)
		(end 235.430532 113.139468)
		(width 0.2)
		(layer "F.Cu")
		(net 1)
	)
	(segment
		(start 235.430532 128.339468)
		(end 235.430532 129.3475)
		(width 0.2)
		(layer "F.Cu")
		(net 1)
	)
	(segment
		(start 187.25 55.145)
		(end 187.248 55.147)
		(width 0.2)
		(layer "F.Cu")
		(net 1)
	)
	(segment
		(start 153.35 97.6)
		(end 154.4 97.6)
		(width 0.2)
		(layer "F.Cu")
		(net 1)
	)
	(segment
		(start 61.12 61.2)
		(end 60.6 61.2)
		(width 0.2)
		(layer "F.Cu")
		(net 1)
	)
	(segment
		(start 217.049999 54.6)
		(end 212.952 54.6)
		(width 0.2)
		(layer "F.Cu")
		(net 1)
	)
	(segment
		(start 222.388 96.162)
		(end 222.4 96.15)
		(width 0.3)
		(layer "F.Cu")
		(net 1)
	)
	(segment
		(start 236.240532 121.71)
		(end 236.530532 122)
		(width 0.2)
		(layer "F.Cu")
		(net 1)
	)
	(segment
		(start 151.02 107.5)
		(end 151.02 107.37)
		(width 0.2)
		(layer "F.Cu")
		(net 1)
	)
	(segment
		(start 201.05 54.600001)
		(end 201.797999 54.600001)
		(width 0.2)
		(layer "F.Cu")
		(net 1)
	)
	(segment
		(start 213.912407 97.732991)
		(end 213.912407 96.987593)
		(width 0.3)
		(layer "F.Cu")
		(net 1)
	)
	(segment
		(start 152.23 113.749)
		(end 152.23 112.5)
		(width 0.2)
		(layer "F.Cu")
		(net 1)
	)
	(segment
		(start 64.319 59.519)
		(end 64.2 59.4)
		(width 0.2)
		(layer "F.Cu")
		(net 1)
	)
	(segment
		(start 183.995 128.525)
		(end 184.04 128.57)
		(width 0.2)
		(layer "F.Cu")
		(net 1)
	)
	(segment
		(start 67.4 97.555)
		(end 67.245 97.4)
		(width 0.2)
		(layer "F.Cu")
		(net 1)
	)
	(segment
		(start 235.430532 129.3475)
		(end 235.430532 130.560532)
		(width 0.2)
		(layer "F.Cu")
		(net 1)
	)
	(segment
		(start 153.35 100.8)
		(end 153.8 100.8)
		(width 0.2)
		(layer "F.Cu")
		(net 1)
	)
	(segment
		(start 162.832532 149.324)
		(end 162.826 149.324)
		(width 0.15)
		(layer "F.Cu")
		(net 1)
	)
	(segment
		(start 151.675 105.81)
		(end 151.01 105.81)
		(width 0.2)
		(layer "F.Cu")
		(net 1)
	)
	(segment
		(start 188.476 124.44)
		(end 187.64 124.44)
		(width 0.2)
		(layer "F.Cu")
		(net 1)
	)
	(segment
		(start 128.12 132.8)
		(end 128.12 133.28)
		(width 0.3)
		(layer "F.Cu")
		(net 1)
	)
	(segment
		(start 212.8 95.88)
		(end 211.42 95.88)
		(width 0.3)
		(layer "F.Cu")
		(net 1)
	)
	(segment
		(start 178.95 91.225)
		(end 179.2 90.975)
		(width 0.2)
		(layer "F.Cu")
		(net 1)
	)
	(segment
		(start 91.5 147.27)
		(end 91.5 146.64)
		(width 0.2)
		(layer "F.Cu")
		(net 1)
	)
	(segment
		(start 193.32 82.4)
		(end 193.32 82.969999)
		(width 0.2)
		(layer "F.Cu")
		(net 1)
	)
	(segment
		(start 220.984 99.26)
		(end 222.36 99.26)
		(width 0.3)
		(layer "F.Cu")
		(net 1)
	)
	(segment
		(start 97.7 61.24)
		(end 97.7 60.775)
		(width 0.2)
		(layer "F.Cu")
		(net 1)
	)
	(segment
		(start 229.930532 128.360532)
		(end 229.930532 129.3475)
		(width 0.2)
		(layer "F.Cu")
		(net 1)
	)
	(segment
		(start 229.930532 75.0725)
		(end 229.930532 73.839468)
		(width 0.2)
		(layer "F.Cu")
		(net 1)
	)
	(segment
		(start 135.69 55.07)
		(end 135.495 54.875)
		(width 0.1)
		(layer "F.Cu")
		(net 1)
	)
	(segment
		(start 90.248501 145.931499)
		(end 90.25 145.93)
		(width 0.2)
		(layer "F.Cu")
		(net 1)
	)
	(segment
		(start 235.430532 104.410532)
		(end 235.52 104.5)
		(width 0.3)
		(layer "F.Cu")
		(net 1)
	)
	(segment
		(start 162.826 149.324)
		(end 162.8 149.35)
		(width 0.15)
		(layer "F.Cu")
		(net 1)
	)
	(segment
		(start 159.23 144.23)
		(end 159.2 144.2)
		(width 0.15)
		(layer "F.Cu")
		(net 1)
	)
	(segment
		(start 97.59 61.35)
		(end 97.7 61.24)
		(width 0.2)
		(layer "F.Cu")
		(net 1)
	)
	(segment
		(start 131.635 141.835)
		(end 131.7 141.9)
		(width 0.3)
		(layer "F.Cu")
		(net 1)
	)
	(segment
		(start 229.930532 77.3475)
		(end 229.930532 76.239468)
		(width 0.2)
		(layer "F.Cu")
		(net 1)
	)
	(segment
		(start 227.613 82)
		(end 227 82)
		(width 0.3)
		(layer "F.Cu")
		(net 1)
	)
	(segment
		(start 137.92 133.948)
		(end 138.548 133.948)
		(width 0.3)
		(layer "F.Cu")
		(net 1)
	)
	(segment
		(start 196.204001 54.6)
		(end 196.202 54.602001)
		(width 0.2)
		(layer "F.Cu")
		(net 1)
	)
	(segment
		(start 235.430532 75.0725)
		(end 235.430532 73.760532)
		(width 0.2)
		(layer "F.Cu")
		(net 1)
	)
	(segment
		(start 71.248 56.4)
		(end 71.248 57.248)
		(width 0.1)
		(layer "F.Cu")
		(net 1)
	)
	(segment
		(start 212.3 78)
		(end 211.68 78)
		(width 0.2)
		(layer "F.Cu")
		(net 1)
	)
	(segment
		(start 229.930532 130.439468)
		(end 229.87 130.5)
		(width 0.2)
		(layer "F.Cu")
		(net 1)
	)
	(segment
		(start 183.714468 89.225)
		(end 183.754468 89.265)
		(width 0.2)
		(layer "F.Cu")
		(net 1)
	)
	(segment
		(start 105.61 55.99)
		(end 106.349999 55.25)
		(width 0.2)
		(layer "F.Cu")
		(net 1)
	)
	(segment
		(start 152.96 116.1)
		(end 153.8 116.1)
		(width 0.2)
		(layer "F.Cu")
		(net 1)
	)
	(segment
		(start 66.05 97.45)
		(end 66.65 97.45)
		(width 0.2)
		(layer "F.Cu")
		(net 1)
	)
	(segment
		(start 182.94 142.175)
		(end 183.43 142.175)
		(width 0.2)
		(layer "F.Cu")
		(net 1)
	)
	(segment
		(start 222.412 86.512)
		(end 222.45 86.55)
		(width 0.3)
		(layer "F.Cu")
		(net 1)
	)
	(segment
		(start 229.930532 102.160532)
		(end 229.97 102.2)
		(width 0.2)
		(layer "F.Cu")
		(net 1)
	)
	(segment
		(start 130.8 143.68)
		(end 128.81 143.68)
		(width 0.1)
		(layer "F.Cu")
		(net 1)
	)
	(segment
		(start 201.199 74.45)
		(end 201.199 75.13)
		(width 0.2)
		(layer "F.Cu")
		(net 1)
	)
	(segment
		(start 214.5 123.7)
		(end 214.48 123.68)
		(width 0.2)
		(layer "F.Cu")
		(net 1)
	)
	(segment
		(start 222.275 117.625)
		(end 222.35 117.55)
		(width 0.3)
		(layer "F.Cu")
		(net 1)
	)
	(segment
		(start 65.68 84.76)
		(end 65.68 85.39)
		(width 0.2)
		(layer "F.Cu")
		(net 1)
	)
	(segment
		(start 164.2 144.05)
		(end 164.2 143.5)
		(width 0.3)
		(layer "F.Cu")
		(net 1)
	)
	(segment
		(start 222.36 102.36)
		(end 222.4 102.4)
		(width 0.3)
		(layer "F.Cu")
		(net 1)
	)
	(segment
		(start 209.639132 92.592)
		(end 209 92.592)
		(width 0.3)
		(layer "F.Cu")
		(net 1)
	)
	(segment
		(start 162.297234 84.147234)
		(end 162.3 84.15)
		(width 0.15)
		(layer "F.Cu")
		(net 1)
	)
	(segment
		(start 236.240532 82.71)
		(end 237.91 82.71)
		(width 0.15)
		(layer "F.Cu")
		(net 1)
	)
	(segment
		(start 180.554468 86.245)
		(end 179.604468 86.245)
		(width 0.2)
		(layer "F.Cu")
		(net 1)
	)
	(segment
		(start 172.465 123.001)
		(end 172.465 123.915)
		(width 0.15)
		(layer "F.Cu")
		(net 1)
	)
	(segment
		(start 229.930532 115.239468)
		(end 229.97 115.2)
		(width 0.2)
		(layer "F.Cu")
		(net 1)
	)
	(segment
		(start 182 139)
		(end 181.85 138.85)
		(width 0.2)
		(layer "F.Cu")
		(net 1)
	)
	(segment
		(start 109.11 64.448)
		(end 109.178 64.448)
		(width 0.1)
		(layer "F.Cu")
		(net 1)
	)
	(segment
		(start 216.6 83.82)
		(end 216.6 83.2)
		(width 0.2)
		(layer "F.Cu")
		(net 1)
	)
	(segment
		(start 235.430532 90.3475)
		(end 235.430532 89.239468)
		(width 0.2)
		(layer "F.Cu")
		(net 1)
	)
	(segment
		(start 66.754 89.446)
		(end 66.8 89.4)
		(width 0.2)
		(layer "F.Cu")
		(net 1)
	)
	(segment
		(start 184.25 54.6)
		(end 185.25 54.6)
		(width 0.1)
		(layer "F.Cu")
		(net 1)
	)
	(segment
		(start 210.95 80.25)
		(end 210.95 81.07)
		(width 0.2)
		(layer "F.Cu")
		(net 1)
	)
	(segment
		(start 217.6 83.82)
		(end 217.6 83.5)
		(width 0.2)
		(layer "F.Cu")
		(net 1)
	)
	(segment
		(start 208.1 67.31927)
		(end 208.1 66.6)
		(width 0.1)
		(layer "F.Cu")
		(net 1)
	)
	(segment
		(start 181 60.5)
		(end 181 59.9)
		(width 0.3)
		(layer "F.Cu")
		(net 1)
	)
	(segment
		(start 212.199 121.301)
		(end 212.2 121.3)
		(width 0.2)
		(layer "F.Cu")
		(net 1)
	)
	(segment
		(start 159.13 143.23)
		(end 159.1 143.2)
		(width 0.15)
		(layer "F.Cu")
		(net 1)
	)
	(segment
		(start 182.88 69.15)
		(end 182.84 69.11)
		(width 0.2)
		(layer "F.Cu")
		(net 1)
	)
	(segment
		(start 215.246 99.454)
		(end 215.246 100.125)
		(width 0.1)
		(layer "F.Cu")
		(net 1)
	)
	(segment
		(start 193.32 82.969999)
		(end 193.375001 83.025)
		(width 0.2)
		(layer "F.Cu")
		(net 1)
	)
	(segment
		(start 167.6 141)
		(end 167.2 140.6)
		(width 0.2)
		(layer "F.Cu")
		(net 1)
	)
	(segment
		(start 67.08 92.7)
		(end 67.8 92.7)
		(width 0.2)
		(layer "F.Cu")
		(net 1)
	)
	(segment
		(start 199.075 110)
		(end 199.075 108.8)
		(width 0.2)
		(layer "F.Cu")
		(net 1)
	)
	(segment
		(start 66.75 85.05)
		(end 67.1 84.7)
		(width 0.2)
		(layer "F.Cu")
		(net 1)
	)
	(segment
		(start 144.45 125.405609)
		(end 144.484391 125.44)
		(width 0.2)
		(layer "F.Cu")
		(net 1)
	)
	(segment
		(start 180.5 111.525)
		(end 180.25 111.775)
		(width 0.2)
		(layer "F.Cu")
		(net 1)
	)
	(segment
		(start 221.873 111.427)
		(end 221.9 111.4)
		(width 0.3)
		(layer "F.Cu")
		(net 1)
	)
	(segment
		(start 184.019468 141.689468)
		(end 183.9675 141.6375)
		(width 0.2)
		(layer "F.Cu")
		(net 1)
	)
	(segment
		(start 135.5 58.6)
		(end 136.3 58.6)
		(width 0.5)
		(layer "F.Cu")
		(net 1)
	)
	(segment
		(start 213.3 134.7)
		(end 212.42 134.7)
		(width 0.2)
		(layer "F.Cu")
		(net 1)
	)
	(segment
		(start 235.430532 117.260532)
		(end 235.57 117.4)
		(width 0.2)
		(layer "F.Cu")
		(net 1)
	)
	(segment
		(start 182.93 127.175)
		(end 181.555 127.175)
		(width 0.2)
		(layer "F.Cu")
		(net 1)
	)
	(segment
		(start 154 96)
		(end 154.8 96.8)
		(width 0.2)
		(layer "F.Cu")
		(net 1)
	)
	(segment
		(start 229.930532 90.3475)
		(end 229.930532 91.539468)
		(width 0.2)
		(layer "F.Cu")
		(net 1)
	)
	(segment
		(start 208 93.592)
		(end 209 92.592)
		(width 0.3)
		(layer "F.Cu")
		(net 1)
	)
	(segment
		(start 209.048 54.598)
		(end 204.95 54.597999)
		(width 0.2)
		(layer "F.Cu")
		(net 1)
	)
	(segment
		(start 161.27 144.23)
		(end 161.3 144.2)
		(width 0.15)
		(layer "F.Cu")
		(net 1)
	)
	(segment
		(start 135.949 57.6)
		(end 135.949 58.151)
		(width 0.5)
		(layer "F.Cu")
		(net 1)
	)
	(segment
		(start 206.8 83.9)
		(end 206.5 83.6)
		(width 0.2)
		(layer "F.Cu")
		(net 1)
	)
	(segment
		(start 235.5 128.2)
		(end 235.5 128.27)
		(width 0.2)
		(layer "F.Cu")
		(net 1)
	)
	(segment
		(start 235.430532 115.139468)
		(end 235.37 115.2)
		(width 0.2)
		(layer "F.Cu")
		(net 1)
	)
	(segment
		(start 61 91.82)
		(end 60.92 91.82)
		(width 0.2)
		(layer "F.Cu")
		(net 1)
	)
	(segment
		(start 88.48 63.5)
		(end 89.25 63.5)
		(width 0.2)
		(layer "F.Cu")
		(net 1)
	)
	(segment
		(start 229.930532 90.3475)
		(end 229.930532 89.239468)
		(width 0.2)
		(layer "F.Cu")
		(net 1)
	)
	(segment
		(start 194.8 79)
		(end 194.72 79)
		(width 0.2)
		(layer "F.Cu")
		(net 1)
	)
	(segment
		(start 171.009468 119.594468)
		(end 171.165 119.75)
		(width 0.15)
		(layer "F.Cu")
		(net 1)
	)
	(segment
		(start 96.95 61.35)
		(end 97.59 61.35)
		(width 0.2)
		(layer "F.Cu")
		(net 1)
	)
	(segment
		(start 221.24 131.573)
		(end 222.273 131.573)
		(width 0.2)
		(layer "F.Cu")
		(net 1)
	)
	(segment
		(start 196.72 127.3)
		(end 196.72 127.88)
		(width 0.1)
		(layer "F.Cu")
		(net 1)
	)
	(segment
		(start 140.372 133.95)
		(end 141 133.95)
		(width 0.3)
		(layer "F.Cu")
		(net 1)
	)
	(segment
		(start 235.430532 115.260532)
		(end 235.37 115.2)
		(width 0.2)
		(layer "F.Cu")
		(net 1)
	)
	(segment
		(start 207 75.72)
		(end 207 75)
		(width 0.3)
		(layer "F.Cu")
		(net 1)
	)
	(segment
		(start 205.926 141.1)
		(end 207.326 141.1)
		(width 0.2)
		(layer "F.Cu")
		(net 1)
	)
	(segment
		(start 180.265 69.625)
		(end 180.19 69.7)
		(width 0.2)
		(layer "F.Cu")
		(net 1)
	)
	(segment
		(start 206.08 82.5)
		(end 206.08 83.6)
		(width 0.2)
		(layer "F.Cu")
		(net 1)
	)
	(segment
		(start 62.7 90.055)
		(end 62.414 90.341)
		(width 0.2)
		(layer "F.Cu")
		(net 1)
	)
	(segment
		(start 221.017132 89.587)
		(end 222.387 89.587)
		(width 0.3)
		(layer "F.Cu")
		(net 1)
	)
	(segment
		(start 203.25 54.5)
		(end 203.25 55.145)
		(width 0.2)
		(layer "F.Cu")
		(net 1)
	)
	(segment
		(start 214.48 130.8)
		(end 215.2 130.8)
		(width 0.1)
		(layer "F.Cu")
		(net 1)
	)
	(segment
		(start 238.55 83.35)
		(end 238.55 84.3)
		(width 0.15)
		(layer "F.Cu")
		(net 1)
	)
	(segment
		(start 206.5 83.6)
		(end 206.08 83.6)
		(width 0.2)
		(layer "F.Cu")
		(net 1)
	)
	(segment
		(start 220.468 125.425)
		(end 221.24 125.425)
		(width 0.2)
		(layer "F.Cu")
		(net 1)
	)
	(segment
		(start 137.92 133.948)
		(end 137.202 133.948)
		(width 0.3)
		(layer "F.Cu")
		(net 1)
	)
	(segment
		(start 235.430532 102.13)
		(end 235.430532 101.0725)
		(width 0.2)
		(layer "F.Cu")
		(net 1)
	)
	(segment
		(start 160.848936 99.565)
		(end 161.079468 99.795532)
		(width 0.2)
		(layer "F.Cu")
		(net 1)
	)
	(segment
		(start 237.2 134.6)
		(end 237.2 135)
		(width 0.3)
		(layer "F.Cu")
		(net 1)
	)
	(segment
		(start 147.23 91)
		(end 147.25 91.02)
		(width 0.5)
		(layer "F.Cu")
		(net 1)
	)
	(segment
		(start 210.73 133.1)
		(end 210.73 133.68)
		(width 0.2)
		(layer "F.Cu")
		(net 1)
	)
	(segment
		(start 229.930532 77.3475)
		(end 229.930532 78.560532)
		(width 0.2)
		(layer "F.Cu")
		(net 1)
	)
	(segment
		(start 162.832532 140.475)
		(end 162.925 140.475)
		(width 0.15)
		(layer "F.Cu")
		(net 1)
	)
	(segment
		(start 221.017132 86.512)
		(end 222.412 86.512)
		(width 0.3)
		(layer "F.Cu")
		(net 1)
	)
	(segment
		(start 196.17 89.77)
		(end 196.2 89.8)
		(width 0.1)
		(layer "F.Cu")
		(net 1)
	)
	(segment
		(start 222.387 89.587)
		(end 222.4 89.6)
		(width 0.3)
		(layer "F.Cu")
		(net 1)
	)
	(segment
		(start 169.404468 134.56)
		(end 169.404468 135.025)
		(width 0.15)
		(layer "F.Cu")
		(net 1)
	)
	(segment
		(start 201.2 82.6)
		(end 201.199 82.599)
		(width 0.2)
		(layer "F.Cu")
		(net 1)
	)
	(segment
		(start 143.22 56.624999)
		(end 142.844999 56.624999)
		(width 0.3)
		(layer "F.Cu")
		(net 1)
	)
	(segment
		(start 198.27 72.77)
		(end 198.25 72.75)
		(width 0.2)
		(layer "F.Cu")
		(net 1)
	)
	(segment
		(start 212.8 63.2)
		(end 212.8 62.525)
		(width 0.1)
		(layer "F.Cu")
		(net 1)
	)
	(segment
		(start 229.930532 78.560532)
		(end 229.97 78.6)
		(width 0.2)
		(layer "F.Cu")
		(net 1)
	)
	(segment
		(start 198.25 84.48)
		(end 198.25 85.25)
		(width 0.1)
		(layer "F.Cu")
		(net 1)
	)
	(segment
		(start 196.402999 55.149001)
		(end 196.952 54.6)
		(width 0.2)
		(layer "F.Cu")
		(net 1)
	)
	(segment
		(start 214.8 119.62)
		(end 212.8 119.62)
		(width 0.2)
		(layer "F.Cu")
		(net 1)
	)
	(segment
		(start 184.005 111.525)
		(end 184.05 111.57)
		(width 0.2)
		(layer "F.Cu")
		(net 1)
	)
	(segment
		(start 208 75.72)
		(end 208 75)
		(width 0.3)
		(layer "F.Cu")
		(net 1)
	)
	(segment
		(start 210.625 103.325)
		(end 210.6 103.3)
		(width 0.3)
		(layer "F.Cu")
		(net 1)
	)
	(segment
		(start 229.930532 103.3475)
		(end 229.930532 104.439468)
		(width 0.3)
		(layer "F.Cu")
		(net 1)
	)
	(segment
		(start 151.9 102.05)
		(end 151.8 102.15)
		(width 0.2)
		(layer "F.Cu")
		(net 1)
	)
	(segment
		(start 82.252 57.998)
		(end 82.25 58)
		(width 0.1)
		(layer "F.Cu")
		(net 1)
	)
	(segment
		(start 229.930532 129.3475)
		(end 229.930532 130.439468)
		(width 0.2)
		(layer "F.Cu")
		(net 1)
	)
	(segment
		(start 139.02 57.72)
		(end 138.6 57.3)
		(width 0.5)
		(layer "F.Cu")
		(net 1)
	)
	(segment
		(start 235.430532 77.3475)
		(end 235.430532 76.239468)
		(width 0.2)
		(layer "F.Cu")
		(net 1)
	)
	(segment
		(start 152.23 112.5)
		(end 152.48 112.25)
		(width 0.2)
		(layer "F.Cu")
		(net 1)
	)
	(segment
		(start 63.001 62.799)
		(end 63 62.8)
		(width 0.2)
		(layer "F.Cu")
		(net 1)
	)
	(segment
		(start 217.6 83.5)
		(end 217.3 83.2)
		(width 0.2)
		(layer "F.Cu")
		(net 1)
	)
	(segment
		(start 201.199 75.13)
		(end 201.199 76.83)
		(width 0.2)
		(layer "F.Cu")
		(net 1)
	)
	(segment
		(start 221.017132 92.66)
		(end 222.44 92.66)
		(width 0.3)
		(layer "F.Cu")
		(net 1)
	)
	(segment
		(start 170.879468 138.52)
		(end 170.879468 137.520532)
		(width 0.15)
		(layer "F.Cu")
		(net 1)
	)
	(segment
		(start 221.202 117.625)
		(end 222.275 117.625)
		(width 0.3)
		(layer "F.Cu")
		(net 1)
	)
	(segment
		(start 152.23 114.57)
		(end 152 114.8)
		(width 0.2)
		(layer "F.Cu")
		(net 1)
	)
	(segment
		(start 182.654468 90.975)
		(end 181.64 90.975)
		(width 0.2)
		(layer "F.Cu")
		(net 1)
	)
	(segment
		(start 105.530532 85.65)
		(end 105.530532 85.369468)
		(width 0.2)
		(layer "F.Cu")
		(net 1)
	)
	(segment
		(start 235.510532 102.21)
		(end 235.430532 102.13)
		(width 0.2)
		(layer "F.Cu")
		(net 1)
	)
	(segment
		(start 183.5 70.65)
		(end 183.16 70.65)
		(width 0.2)
		(layer "F.Cu")
		(net 1)
	)
	(segment
		(start 221.8 128.5)
		(end 221.9 128.6)
		(width 0.2)
		(layer "F.Cu")
		(net 1)
	)
	(segment
		(start 182.72 107)
		(end 182.39 106.67)
		(width 0.2)
		(layer "F.Cu")
		(net 1)
	)
	(segment
		(start 63.22 85.45)
		(end 63.22 84.32)
		(width 0.2)
		(layer "F.Cu")
		(net 1)
	)
	(segment
		(start 182.77 138.95)
		(end 183.23 138.49)
		(width 0.2)
		(layer "F.Cu")
		(net 1)
	)
	(segment
		(start 205.926 148.3)
		(end 207.326 148.3)
		(width 0.2)
		(layer "F.Cu")
		(net 1)
	)
	(segment
		(start 132.945349 62.97)
		(end 131.935349 63.98)
		(width 0.2)
		(layer "F.Cu")
		(net 1)
	)
	(segment
		(start 229.930532 114.0725)
		(end 229.930532 115.160532)
		(width 0.2)
		(layer "F.Cu")
		(net 1)
	)
	(segment
		(start 150.4 96)
		(end 151.019998 96.000001)
		(width 0.2)
		(layer "F.Cu")
		(net 1)
	)
	(segment
		(start 211.25 54.575)
		(end 211.25 55.149001)
		(width 0.2)
		(layer "F.Cu")
		(net 1)
	)
	(segment
		(start 152.73 116.33)
		(end 152.96 116.1)
		(width 0.2)
		(layer "F.Cu")
		(net 1)
	)
	(segment
		(start 169.1 147.15)
		(end 169.1 147.62)
		(width 0.1)
		(layer "F.Cu")
		(net 1)
	)
	(segment
		(start 138.548 133.948)
		(end 138.55 133.95)
		(width 0.3)
		(layer "F.Cu")
		(net 1)
	)
	(segment
		(start 144.45 124.85)
		(end 144.45 125.405609)
		(width 0.2)
		(layer "F.Cu")
		(net 1)
	)
	(segment
		(start 135.500999 66.500999)
		(end 135.6 66.6)
		(width 0.5)
		(layer "F.Cu")
		(net 1)
	)
	(segment
		(start 94.48 57.5)
		(end 95.25 57.5)
		(width 0.2)
		(layer "F.Cu")
		(net 1)
	)
	(segment
		(start 235.430532 76.239468)
		(end 235.47 76.2)
		(width 0.2)
		(layer "F.Cu")
		(net 1)
	)
	(segment
		(start 91.52 64.77)
		(end 91.5 64.75)
		(width 0.1)
		(layer "F.Cu")
		(net 1)
	)
	(segment
		(start 235.430532 90.3475)
		(end 235.430532 91.610532)
		(width 0.2)
		(layer "F.Cu")
		(net 1)
	)
	(segment
		(start 202.9 59.7)
		(end 201.5 59.7)
		(width 0.15)
		(layer "F.Cu")
		(net 1)
	)
	(segment
		(start 86.570001 149.289499)
		(end 85.440501 149.289499)
		(width 0.2)
		(layer "F.Cu")
		(net 1)
	)
	(segment
		(start 210.7 81.3)
		(end 210.2 81.8)
		(width 0.2)
		(layer "F.Cu")
		(net 1)
	)
	(segment
		(start 193.05 61.402001)
		(end 188.952 61.402)
		(width 0.15)
		(layer "F.Cu")
		(net 1)
	)
	(segment
		(start 152.724999 102.585)
		(end 152.724999 102.074999)
		(width 0.2)
		(layer "F.Cu")
		(net 1)
	)
	(segment
		(start 152.699999 100.825)
		(end 152.699999 101.299999)
		(width 0.2)
		(layer "F.Cu")
		(net 1)
	)
	(segment
		(start 97.7 60.775)
		(end 97.7 59.35)
		(width 0.2)
		(layer "F.Cu")
		(net 1)
	)
	(segment
		(start 180.265 89.625)
		(end 180.19 89.7)
		(width 0.2)
		(layer "F.Cu")
		(net 1)
	)
	(segment
		(start 71.248 57.248)
		(end 71.25 57.25)
		(width 0.1)
		(layer "F.Cu")
		(net 1)
	)
	(segment
		(start 127.594212 62.115)
		(end 127.519212 62.04)
		(width 0.2)
		(layer "F.Cu")
		(net 1)
	)
	(segment
		(start 211.32 103.325)
		(end 210.625 103.325)
		(width 0.3)
		(layer "F.Cu")
		(net 1)
	)
	(segment
		(start 197.726 146.3)
		(end 199.126 146.3)
		(width 0.2)
		(layer "F.Cu")
		(net 1)
	)
	(segment
		(start 139.654 133.95)
		(end 139.652 133.952)
		(width 0.3)
		(layer "F.Cu")
		(net 1)
	)
	(segment
		(start 182.39 106.67)
		(end 181.75 106.67)
		(width 0.2)
		(layer "F.Cu")
		(net 1)
	)
	(segment
		(start 180.889468 65.99)
		(end 179.949468 65.99)
		(width 0.15)
		(layer "F.Cu")
		(net 1)
	)
	(segment
		(start 154 101)
		(end 154 101.4)
		(width 0.2)
		(layer "F.Cu")
		(net 1)
	)
	(segment
		(start 235.430532 114.0725)
		(end 235.430532 115.139468)
		(width 0.2)
		(layer "F.Cu")
		(net 1)
	)
	(segment
		(start 94.48 63.5)
		(end 95.25 63.5)
		(width 0.1)
		(layer "F.Cu")
		(net 1)
	)
	(segment
		(start 229.930532 128.039468)
		(end 229.930532 127.0725)
		(width 0.2)
		(layer "F.Cu")
		(net 1)
	)
	(segment
		(start 235.430532 101.0725)
		(end 235.430532 99.960532)
		(width 0.3)
		(layer "F.Cu")
		(net 1)
	)
	(segment
		(start 235.430532 103.3475)
		(end 235.430532 104.410532)
		(width 0.3)
		(layer "F.Cu")
		(net 1)
	)
	(segment
		(start 235.430532 130.560532)
		(end 235.47 130.6)
		(width 0.2)
		(layer "F.Cu")
		(net 1)
	)
	(segment
		(start 89.55 145.931499)
		(end 90.248501 145.931499)
		(width 0.2)
		(layer "F.Cu")
		(net 1)
	)
	(segment
		(start 212.402999 55.149001)
		(end 212.952 54.6)
		(width 0.2)
		(layer "F.Cu")
		(net 1)
	)
	(segment
		(start 152.325001 102.075001)
		(end 152.3 102.05)
		(width 0.2)
		(layer "F.Cu")
		(net 1)
	)
	(segment
		(start 139.02 59.5)
		(end 139.02 57.72)
		(width 0.5)
		(layer "F.Cu")
		(net 1)
	)
	(segment
		(start 236.530532 122)
		(end 236.9 122)
		(width 0.2)
		(layer "F.Cu")
		(net 1)
	)
	(segment
		(start 61.12 63.2)
		(end 60.6 63.2)
		(width 0.2)
		(layer "F.Cu")
		(net 1)
	)
	(segment
		(start 127.594212 63.49)
		(end 127.594212 62.115)
		(width 0.2)
		(layer "F.Cu")
		(net 1)
	)
	(segment
		(start 229.930532 76.239468)
		(end 229.97 76.2)
		(width 0.2)
		(layer "F.Cu")
		(net 1)
	)
	(segment
		(start 146.400001 91)
		(end 147.23 91)
		(width 0.5)
		(layer "F.Cu")
		(net 1)
	)
	(segment
		(start 184.039468 143.57)
		(end 184.16 143.57)
		(width 0.2)
		(layer "F.Cu")
		(net 1)
	)
	(segment
		(start 203.1 117.42)
		(end 203.1 117.4)
		(width 0.1)
		(layer "F.Cu")
		(net 1)
	)
	(segment
		(start 221.24 125.425)
		(end 221.975 125.425)
		(width 0.2)
		(layer "F.Cu")
		(net 1)
	)
	(segment
		(start 63.22 84.32)
		(end 63.2 84.3)
		(width 0.2)
		(layer "F.Cu")
		(net 1)
	)
	(segment
		(start 229.930532 113.060532)
		(end 229.930532 114.0725)
		(width 0.3)
		(layer "F.Cu")
		(net 1)
	)
	(segment
		(start 63.67 62.799)
		(end 63.001 62.799)
		(width 0.2)
		(layer "F.Cu")
		(net 1)
	)
	(segment
		(start 152.7 102.05)
		(end 152.3 102.05)
		(width 0.2)
		(layer "F.Cu")
		(net 1)
	)
	(segment
		(start 203.1 111.3)
		(end 204.6 111.3)
		(width 0.2)
		(layer "F.Cu")
		(net 1)
	)
	(segment
		(start 182.94 110.175)
		(end 183.545 110.175)
		(width 0.2)
		(layer "F.Cu")
		(net 1)
	)
	(segment
		(start 132.905 141.795)
		(end 132.9 141.8)
		(width 0.3)
		(layer "F.Cu")
		(net 1)
	)
	(segment
		(start 179.2 70.975)
		(end 178.95 71.225)
		(width 0.2)
		(layer "F.Cu")
		(net 1)
	)
	(segment
		(start 169.1 127.9)
		(end 169.1 128.4)
		(width 0.1)
		(layer "F.Cu")
		(net 1)
	)
	(segment
		(start 64.319 60.151)
		(end 64.319 59.519)
		(width 0.2)
		(layer "F.Cu")
		(net 1)
	)
	(segment
		(start 126.244212 63.49)
		(end 126.244212 61.05)
		(width 0.2)
		(layer "F.Cu")
		(net 1)
	)
	(segment
		(start 160.8 73.57)
		(end 160.79 73.56)
		(width 0.2)
		(layer "F.Cu")
		(net 1)
	)
	(segment
		(start 181.64 89.625)
		(end 182.364468 89.625)
		(width 0.2)
		(layer "F.Cu")
		(net 1)
	)
	(segment
		(start 238.95 72.55)
		(end 238.9 72.6)
		(width 0.1)
		(layer "F.Cu")
		(net 1)
	)
	(segment
		(start 152.73 117.251)
		(end 152.73 118.5)
		(width 0.2)
		(layer "F.Cu")
		(net 1)
	)
	(segment
		(start 182.94 111.525)
		(end 184.005 111.525)
		(width 0.2)
		(layer "F.Cu")
		(net 1)
	)
	(segment
		(start 179.604468 86.420532)
		(end 179.6 86.425)
		(width 0.15)
		(layer "F.Cu")
		(net 1)
	)
	(segment
		(start 201.199 76.83)
		(end 199.549 78.48)
		(width 0.2)
		(layer "F.Cu")
		(net 1)
	)
	(segment
		(start 229.93 128.04)
		(end 229.930532 128.039468)
		(width 0.2)
		(layer "F.Cu")
		(net 1)
	)
	(segment
		(start 67.245 97.4)
		(end 66.7 97.4)
		(width 0.2)
		(layer "F.Cu")
		(net 1)
	)
	(segment
		(start 180.79 123.67)
		(end 181.504296 123.67)
		(width 0.2)
		(layer "F.Cu")
		(net 1)
	)
	(segment
		(start 201.6 113.1)
		(end 202.7 113.1)
		(width 0.2)
		(layer "F.Cu")
		(net 1)
	)
	(segment
		(start 160.95 61.65)
		(end 160.9 61.6)
		(width 0.2)
		(layer "F.Cu")
		(net 1)
	)
	(segment
		(start 169.6 150.4)
		(end 168.899 150.4)
		(width 0.2)
		(layer "F.Cu")
		(net 1)
	)
	(segment
		(start 169.6 146.65)
		(end 169.1 147.15)
		(width 0.1)
		(layer "F.Cu")
		(net 1)
	)
	(segment
		(start 201.7 134.18)
		(end 201.7 134.9)
		(width 0.2)
		(layer "F.Cu")
		(net 1)
	)
	(segment
		(start 199.075 113.2)
		(end 199.075 114.4)
		(width 0.2)
		(layer "F.Cu")
		(net 1)
	)
	(segment
		(start 235.430532 125.839468)
		(end 235.47 125.8)
		(width 0.2)
		(layer "F.Cu")
		(net 1)
	)
	(segment
		(start 235.430532 89.160532)
		(end 235.47 89.2)
		(width 0.2)
		(layer "F.Cu")
		(net 1)
	)
	(segment
		(start 143.4 133.95)
		(end 143.402 133.952)
		(width 0.3)
		(layer "F.Cu")
		(net 1)
	)
	(segment
		(start 104.04 56.205)
		(end 104.695 56.205)
		(width 0.2)
		(layer "F.Cu")
		(net 1)
	)
	(segment
		(start 100.05 55.9)
		(end 99.916002 55.89)
		(width 0.1)
		(layer "F.Cu")
		(net 1)
	)
	(segment
		(start 220.984 105.46)
		(end 220.36 105.46)
		(width 0.3)
		(layer "F.Cu")
		(net 1)
	)
	(segment
		(start 221.199 114.527)
		(end 220.427 114.527)
		(width 0.3)
		(layer "F.Cu")
		(net 1)
	)
	(segment
		(start 201.797999 54.600001)
		(end 201.8 54.598)
		(width 0.2)
		(layer "F.Cu")
		(net 1)
	)
	(segment
		(start 196.735 125.3)
		(end 196.2 125.3)
		(width 0.1)
		(layer "F.Cu")
		(net 1)
	)
	(segment
		(start 235.430532 76.160532)
		(end 235.47 76.2)
		(width 0.2)
		(layer "F.Cu")
		(net 1)
	)
	(segment
		(start 151.05 102.15)
		(end 150.9 102.3)
		(width 0.2)
		(layer "F.Cu")
		(net 1)
	)
	(segment
		(start 203.6 134.18)
		(end 203.7 134.28)
		(width 0.2)
		(layer "F.Cu")
		(net 1)
	)
	(segment
		(start 229.930532 101.0725)
		(end 229.930532 102.160532)
		(width 0.2)
		(layer "F.Cu")
		(net 1)
	)
	(segment
		(start 181.64 69.625)
		(end 182.364468 69.625)
		(width 0.2)
		(layer "F.Cu")
		(net 1)
	)
	(segment
		(start 66.65 97.45)
		(end 66.7 97.4)
		(width 0.2)
		(layer "F.Cu")
		(net 1)
	)
	(segment
		(start 215.246 104.526)
		(end 215.246 102.325)
		(width 0.3)
		(layer "F.Cu")
		(net 1)
	)
	(segment
		(start 201.199 81.831)
		(end 201.199 80.13)
		(width 0.2)
		(layer "F.Cu")
		(net 1)
	)
	(segment
		(start 89.9 63.5)
		(end 89.25 63.5)
		(width 0.2)
		(layer "F.Cu")
		(net 1)
	)
	(segment
		(start 160.95 62.302)
		(end 160.95 61.65)
		(width 0.2)
		(layer "F.Cu")
		(net 1)
	)
	(segment
		(start 152.325001 102.585)
		(end 152.325001 102.075001)
		(width 0.2)
		(layer "F.Cu")
		(net 1)
	)
	(segment
		(start 182.77 139)
		(end 182.77 138.95)
		(width 0.2)
		(layer "F.Cu")
		(net 1)
	)
	(segment
		(start 210.95 81.07)
		(end 210.72 81.3)
		(width 0.2)
		(layer "F.Cu")
		(net 1)
	)
	(segment
		(start 229.930532 73.839468)
		(end 229.97 73.8)
		(width 0.2)
		(layer "F.Cu")
		(net 1)
	)
	(segment
		(start 197.726 141.5)
		(end 199.126 141.5)
		(width 0.2)
		(layer "F.Cu")
		(net 1)
	)
	(segment
		(start 60.92 91.82)
		(end 60.6 91.5)
		(width 0.2)
		(layer "F.Cu")
		(net 1)
	)
	(segment
		(start 229.930532 104.439468)
		(end 229.92 104.45)
		(width 0.3)
		(layer "F.Cu")
		(net 1)
	)
	(segment
		(start 235.430532 127.0725)
		(end 235.430532 125.839468)
		(width 0.2)
		(layer "F.Cu")
		(net 1)
	)
	(segment
		(start 169.404468 135.025)
		(end 169.579468 135.2)
		(width 0.15)
		(layer "F.Cu")
		(net 1)
	)
	(segment
		(start 208.09027 67.329)
		(end 208.1 67.31927)
		(width 0.1)
		(layer "F.Cu")
		(net 1)
	)
	(segment
		(start 191.677 85.198)
		(end 191.102 85.198)
		(width 0.2)
		(layer "F.Cu")
		(net 1)
	)
	(segment
		(start 194.4 116.595)
		(end 196.395 116.595)
		(width 0.3)
		(layer "F.Cu")
		(net 1)
	)
	(segment
		(start 131.78 143.68)
		(end 131.8 143.7)
		(width 0.1)
		(layer "F.Cu")
		(net 1)
	)
	(segment
		(start 221.975 125.425)
		(end 222 125.4)
		(width 0.2)
		(layer "F.Cu")
		(net 1)
	)
	(segment
		(start 201.199 80.13)
		(end 199.549 78.48)
		(width 0.2)
		(layer "F.Cu")
		(net 1)
	)
	(segment
		(start 135.949 58.551)
		(end 135.949 58)
		(width 0.5)
		(layer "F.Cu")
		(net 1)
	)
	(segment
		(start 196 122.9)
		(end 196.74 122.9)
		(width 0.2)
		(layer "F.Cu")
		(net 1)
	)
	(segment
		(start 224.751001 75.751001)
		(end 225.2 76.2)
		(width 0.5)
		(layer "F.Cu")
		(net 1)
	)
	(segment
		(start 221.202 111.427)
		(end 221.873 111.427)
		(width 0.3)
		(layer "F.Cu")
		(net 1)
	)
	(segment
		(start 222.36 99.26)
		(end 222.4 99.3)
		(width 0.3)
		(layer "F.Cu")
		(net 1)
	)
	(segment
		(start 184.16 143.57)
		(end 184.69 144.1)
		(width 0.2)
		(layer "F.Cu")
		(net 1)
	)
	(segment
		(start 215.8 119.62)
		(end 214.8 119.62)
		(width 0.2)
		(layer "F.Cu")
		(net 1)
	)
	(segment
		(start 222.273 131.573)
		(end 222.3 131.6)
		(width 0.2)
		(layer "F.Cu")
		(net 1)
	)
	(segment
		(start 104.91 55.99)
		(end 105.61 55.99)
		(width 0.2)
		(layer "F.Cu")
		(net 1)
	)
	(segment
		(start 187.842281 61.402)
		(end 188.952 61.402)
		(width 0.15)
		(layer "F.Cu")
		(net 1)
	)
	(segment
		(start 97.21 58.86)
		(end 97.7 59.35)
		(width 0.2)
		(layer "F.Cu")
		(net 1)
	)
	(segment
		(start 229.930532 116.3475)
		(end 229.930532 115.239468)
		(width 0.2)
		(layer "F.Cu")
		(net 1)
	)
	(segment
		(start 137.15 57.3)
		(end 136.249 57.3)
		(width 0.5)
		(layer "F.Cu")
		(net 1)
	)
	(segment
		(start 134.8 65.400999)
		(end 135.000999 65.2)
		(width 0.3)
		(layer "F.Cu")
		(net 1)
	)
	(segment
		(start 215.246 105.554)
		(end 215.2 105.6)
		(width 0.1)
		(layer "F.Cu")
		(net 1)
	)
	(segment
		(start 183.16 70.65)
		(end 182.84 70.97)
		(width 0.2)
		(layer "F.Cu")
		(net 1)
	)
	(segment
		(start 152.2 101.4)
		(end 151 101.4)
		(width 0.2)
		(layer "F.Cu")
		(net 1)
	)
	(segment
		(start 235.430532 99.960532)
		(end 235.42 99.95)
		(width 0.3)
		(layer "F.Cu")
		(net 1)
	)
	(segment
		(start 91.52 65.5)
		(end 91.52 64.77)
		(width 0.1)
		(layer "F.Cu")
		(net 1)
	)
	(segment
		(start 220.468 128.5)
		(end 221.24 128.5)
		(width 0.2)
		(layer "F.Cu")
		(net 1)
	)
	(segment
		(start 229.930532 102.239468)
		(end 229.97 102.2)
		(width 0.2)
		(layer "F.Cu")
		(net 1)
	)
	(segment
		(start 142.844999 56.624999)
		(end 142.52 56.3)
		(width 0.3)
		(layer "F.Cu")
		(net 1)
	)
	(segment
		(start 135.949 58)
		(end 135.949 57.6)
		(width 0.5)
		(layer "F.Cu")
		(net 1)
	)
	(segment
		(start 211.88 118.3)
		(end 212.6 118.3)
		(width 0.2)
		(layer "F.Cu")
		(net 1)
	)
	(segment
		(start 212.8 119.62)
		(end 212.8 119)
		(width 0.2)
		(layer "F.Cu")
		(net 1)
	)
	(segment
		(start 229.930532 75.0725)
		(end 229.930532 76.160532)
		(width 0.2)
		(layer "F.Cu")
		(net 1)
	)
	(segment
		(start 229.930532 103.3475)
		(end 229.930532 102.239468)
		(width 0.2)
		(layer "F.Cu")
		(net 1)
	)
	(segment
		(start 135.949 58.151)
		(end 135.5 58.6)
		(width 0.5)
		(layer "F.Cu")
		(net 1)
	)
	(segment
		(start 184.019468 141.71)
		(end 184.019468 141.689468)
		(width 0.2)
		(layer "F.Cu")
		(net 1)
	)
	(segment
		(start 235.430532 75.0725)
		(end 235.430532 76.160532)
		(width 0.2)
		(layer "F.Cu")
		(net 1)
	)
	(segment
		(start 135.949 58)
		(end 135.949 58.249)
		(width 0.5)
		(layer "F.Cu")
		(net 1)
	)
	(segment
		(start 236.240532 97.340532)
		(end 236.3 97.4)
		(width 0.2)
		(layer "F.Cu")
		(net 1)
	)
	(segment
		(start 172.465 123.915)
		(end 172.5 123.95)
		(width 0.15)
		(layer "F.Cu")
		(net 1)
	)
	(segment
		(start 212.8 62.525)
		(end 212.875 62.45)
		(width 0.1)
		(layer "F.Cu")
		(net 1)
	)
	(segment
		(start 182.654468 70.975)
		(end 181.64 70.975)
		(width 0.2)
		(layer "F.Cu")
		(net 1)
	)
	(segment
		(start 214.48 132.8)
		(end 215.2 132.8)
		(width 0.1)
		(layer "F.Cu")
		(net 1)
	)
	(segment
		(start 235.430532 89.239468)
		(end 235.47 89.2)
		(width 0.2)
		(layer "F.Cu")
		(net 1)
	)
	(segment
		(start 63.2 99.2)
		(end 63.9 98.5)
		(width 0.2)
		(layer "F.Cu")
		(net 1)
	)
	(segment
		(start 181.555 127.175)
		(end 181.48 127.25)
		(width 0.2)
		(layer "F.Cu")
		(net 1)
	)
	(segment
		(start 159.222 145.228)
		(end 159.15 145.3)
		(width 0.15)
		(layer "F.Cu")
		(net 1)
	)
	(segment
		(start 160.997234 79.657766)
		(end 160.849468 79.51)
		(width 0.15)
		(layer "F.Cu")
		(net 1)
	)
	(segment
		(start 235.430532 88.0725)
		(end 235.430532 86.939468)
		(width 0.2)
		(layer "F.Cu")
		(net 1)
	)
	(segment
		(start 181.513471 123.717356)
		(end 181.897112 123.717356)
		(width 0.2)
		(layer "F.Cu")
		(net 1)
	)
	(segment
		(start 130.365 134.335)
		(end 130.6 134.1)
		(width 0.3)
		(layer "F.Cu")
		(net 1)
	)
	(segment
		(start 206.8 84)
		(end 206.8 83.9)
		(width 0.2)
		(layer "F.Cu")
		(net 1)
	)
	(segment
		(start 151.01 105.81)
		(end 151 105.8)
		(width 0.2)
		(layer "F.Cu")
		(net 1)
	)
	(segment
		(start 187.64 124.44)
		(end 187.6 124.4)
		(width 0.2)
		(layer "F.Cu")
		(net 1)
	)
	(segment
		(start 182.77 139)
		(end 182 139)
		(width 0.2)
		(layer "F.Cu")
		(net 1)
	)
	(segment
		(start 237.91 82.71)
		(end 238.55 83.35)
		(width 0.15)
		(layer "F.Cu")
		(net 1)
	)
	(segment
		(start 211.142 121.301)
		(end 212.199 121.301)
		(width 0.2)
		(layer "F.Cu")
		(net 1)
	)
	(segment
		(start 171.165 120.401)
		(end 171.165 119.75)
		(width 0.15)
		(layer "F.Cu")
		(net 1)
	)
	(segment
		(start 138.9 109.331999)
		(end 138.9 110)
		(width 0.1)
		(layer "F.Cu")
		(net 1)
	)
	(segment
		(start 164.2 143.5)
		(end 164.675 143.025)
		(width 0.3)
		(layer "F.Cu")
		(net 1)
	)
	(segment
		(start 112.230532 79.65)
		(end 112.230532 79.230532)
		(width 0.2)
		(layer "F.Cu")
		(net 1)
	)
	(segment
		(start 221.015132 96.162)
		(end 222.388 96.162)
		(width 0.3)
		(layer "F.Cu")
		(net 1)
	)
	(segment
		(start 157.06 143.88)
		(end 157.06 144.78)
		(width 0.15)
		(layer "F.Cu")
		(net 1)
	)
	(segment
		(start 201.2 82.9)
		(end 201.2 82.6)
		(width 0.2)
		(layer "F.Cu")
		(net 1)
	)
	(segment
		(start 152 114.8)
		(end 151.3 114.8)
		(width 0.2)
		(layer "F.Cu")
		(net 1)
	)
	(segment
		(start 229.930532 88.0725)
		(end 229.930532 89.160532)
		(width 0.2)
		(layer "F.Cu")
		(net 1)
	)
	(segment
		(start 181.64 89.625)
		(end 180.265 89.625)
		(width 0.2)
		(layer "F.Cu")
		(net 1)
	)
	(segment
		(start 220.468 131.573)
		(end 221.24 131.573)
		(width 0.2)
		(layer "F.Cu")
		(net 1)
	)
	(segment
		(start 235.430532 91.610532)
		(end 235.47 91.65)
		(width 0.2)
		(layer "F.Cu")
		(net 1)
	)
	(segment
		(start 183.43 142.175)
		(end 183.9675 141.6375)
		(width 0.2)
		(layer "F.Cu")
		(net 1)
	)
	(segment
		(start 197.55 89.75)
		(end 197.6 89.8)
		(width 0.1)
		(layer "F.Cu")
		(net 1)
	)
	(segment
		(start 229.930532 126.060532)
		(end 229.77 125.9)
		(width 0.2)
		(layer "F.Cu")
		(net 1)
	)
	(segment
		(start 95.05 61.5)
		(end 95.25 61.7)
		(width 0.1)
		(layer "F.Cu")
		(net 1)
	)
	(segment
		(start 212.4 134.72)
		(end 211.442 134.72)
		(width 0.2)
		(layer "F.Cu")
		(net 1)
	)
	(segment
		(start 139.23 131.63)
		(end 139.248 131.648)
		(width 0.2)
		(layer "F.Cu")
		(net 1)
	)
	(segment
		(start 183.545 110.175)
		(end 184.05 109.67)
		(width 0.2)
		(layer "F.Cu")
		(net 1)
	)
	(segment
		(start 204.400999 55.147)
		(end 204.95 54.597999)
		(width 0.2)
		(layer "F.Cu")
		(net 1)
	)
	(segment
		(start 229.930532 76.160532)
		(end 229.97 76.2)
		(width 0.2)
		(layer "F.Cu")
		(net 1)
	)
	(segment
		(start 182.764468 71.085)
		(end 182.654468 70.975)
		(width 0.2)
		(layer "F.Cu")
		(net 1)
	)
	(segment
		(start 132.905 140.714999)
		(end 132.905 141.795)
		(width 0.3)
		(layer "F.Cu")
		(net 1)
	)
	(segment
		(start 142.772 133.95)
		(end 143.4 133.95)
		(width 0.3)
		(layer "F.Cu")
		(net 1)
	)
	(segment
		(start 182.364468 89.625)
		(end 182.764468 89.225)
		(width 0.2)
		(layer "F.Cu")
		(net 1)
	)
	(segment
		(start 225.2 76.2)
		(end 225.5 76.2)
		(width 0.5)
		(layer "F.Cu")
		(net 1)
	)
	(segment
		(start 182.94 143.525)
		(end 182.325 143.525)
		(width 0.2)
		(layer "F.Cu")
		(net 1)
	)
	(segment
		(start 220.43 111.427)
		(end 221.202 111.427)
		(width 0.3)
		(layer "F.Cu")
		(net 1)
	)
	(segment
		(start 235.430532 116.3475)
		(end 235.430532 115.260532)
		(width 0.2)
		(layer "F.Cu")
		(net 1)
	)
	(segment
		(start 138.2 104.32)
		(end 137.52 104.32)
		(width 0.2)
		(layer "F.Cu")
		(net 1)
	)
	(segment
		(start 195.25 55.149001)
		(end 196.402999 55.149001)
		(width 0.2)
		(layer "F.Cu")
		(net 1)
	)
	(segment
		(start 182.764468 89.225)
		(end 183.714468 89.225)
		(width 0.2)
		(layer "F.Cu")
		(net 1)
	)
	(segment
		(start 196.735 121.9)
		(end 196 121.9)
		(width 0.2)
		(layer "F.Cu")
		(net 1)
	)
	(segment
		(start 229.87 113)
		(end 229.930532 113.060532)
		(width 0.3)
		(layer "F.Cu")
		(net 1)
	)
	(segment
		(start 236.9 108.6)
		(end 236.350532 108.6)
		(width 0.2)
		(layer "F.Cu")
		(net 1)
	)
	(segment
		(start 221.756 105.46)
		(end 220.984 105.46)
		(width 0.3)
		(layer "F.Cu")
		(net 1)
	)
	(segment
		(start 95.9 60.3)
		(end 96.95 61.35)
		(width 0.2)
		(layer "F.Cu")
		(net 1)
	)
	(segment
		(start 203.25 57.73)
		(end 203.25 59.35)
		(width 0.15)
		(layer "F.Cu")
		(net 1)
	)
	(segment
		(start 153.98 107.5)
		(end 155 107.5)
		(width 0.2)
		(layer "F.Cu")
		(net 1)
	)
	(segment
		(start 92.1 59.503)
		(end 91.253 59.503)
		(width 0.2)
		(layer "F.Cu")
		(net 1)
	)
	(segment
		(start 215.3 99.35)
		(end 215.3 99.4)
		(width 0.1)
		(layer "F.Cu")
		(net 1)
	)
	(segment
		(start 229.930532 127.0725)
		(end 229.930532 126.060532)
		(width 0.2)
		(layer "F.Cu")
		(net 1)
	)
	(segment
		(start 131.635 140.715)
		(end 131.635 141.835)
		(width 0.3)
		(layer "F.Cu")
		(net 1)
	)
	(segment
		(start 199.27 84.48)
		(end 199.27 85.23)
		(width 0.1)
		(layer "F.Cu")
		(net 1)
	)
	(segment
		(start 159.833 144.23)
		(end 159.23 144.23)
		(width 0.15)
		(layer "F.Cu")
		(net 1)
	)
	(segment
		(start 236.923 134.323)
		(end 237.2 134.6)
		(width 0.3)
		(layer "F.Cu")
		(net 1)
	)
	(segment
		(start 235.430532 113.139468)
		(end 235.57 113)
		(width 0.2)
		(layer "F.Cu")
		(net 1)
	)
	(segment
		(start 235.430532 116.3475)
		(end 235.430532 117.260532)
		(width 0.2)
		(layer "F.Cu")
		(net 1)
	)
	(segment
		(start 235.510532 102.21)
		(end 235.430532 102.29)
		(width 0.2)
		(layer "F.Cu")
		(net 1)
	)
	(segment
		(start 152.724999 102.074999)
		(end 152.7 102.05)
		(width 0.2)
		(layer "F.Cu")
		(net 1)
	)
	(segment
		(start 152.300001 100.825)
		(end 152.300001 101.299999)
		(width 0.2)
		(layer "F.Cu")
		(net 1)
	)
	(segment
		(start 153.979999 96)
		(end 154 96)
		(width 0.2)
		(layer "F.Cu")
		(net 1)
	)
	(segment
		(start 187.248 55.147)
		(end 188.400999 55.147)
		(width 0.2)
		(layer "F.Cu")
		(net 1)
	)
	(segment
		(start 151.65 97.6)
		(end 150.8 97.6)
		(width 0.2)
		(layer "F.Cu")
		(net 1)
	)
	(segment
		(start 135.5 58.6)
		(end 135.9 58.6)
		(width 0.5)
		(layer "F.Cu")
		(net 1)
	)
	(segment
		(start 199.27 85.23)
		(end 199.2 85.3)
		(width 0.1)
		(layer "F.Cu")
		(net 1)
	)
	(segment
		(start 85.440501 149.289499)
		(end 85.44 149.29)
		(width 0.2)
		(layer "F.Cu")
		(net 1)
	)
	(segment
		(start 197.726 143.9)
		(end 199.126 143.9)
		(width 0.2)
		(layer "F.Cu")
		(net 1)
	)
	(segment
		(start 206.495 79.205)
		(end 206.5 79.2)
		(width 0.1)
		(layer "F.Cu")
		(net 1)
	)
	(segment
		(start 217.68 94.2)
		(end 218.4 94.2)
		(width 0.2)
		(layer "F.Cu")
		(net 1)
	)
	(segment
		(start 195.25 57.73)
		(end 197.23 57.73)
		(width 0.2)
		(layer "F.Cu")
		(net 1)
	)
	(segment
		(start 183.809468 69.15)
		(end 182.88 69.15)
		(width 0.2)
		(layer "F.Cu")
		(net 1)
	)
	(via
		(at 142 66.2)
		(size 0.45)
		(drill 0.1)
		(layers "F.Cu" "B.Cu")
		(net 1)
	)
	(via
		(at 126.6 151.2)
		(size 0.45)
		(drill 0.1)
		(layers "F.Cu" "B.Cu")
		(net 1)
	)
	(via
		(at 214.25 113.1)
		(size 0.45)
		(drill 0.1)
		(layers "F.Cu" "B.Cu")
		(net 1)
	)
	(via
		(at 138.6 65.7)
		(size 0.45)
		(drill 0.1)
		(layers "F.Cu" "B.Cu")
		(net 1)
	)
	(via
		(at 80.855532 97.995)
		(size 0.45)
		(drill 0.1)
		(layers "F.Cu" "B.Cu")
		(net 1)
	)
	(via
		(at 70.695532 91.645)
		(size 0.45)
		(drill 0.1)
		(layers "F.Cu" "B.Cu")
		(net 1)
	)
	(via
		(at 80.855532 113.235)
		(size 0.45)
		(drill 0.1)
		(layers "F.Cu" "B.Cu")
		(net 1)
	)
	(via
		(at 213.8 76.2)
		(size 0.45)
		(drill 0.1)
		(layers "F.Cu" "B.Cu")
		(net 1)
	)
	(via
		(at 199.075 113.2)
		(size 0.45)
		(drill 0.1)
		(layers "F.Cu" "B.Cu")
		(net 1)
	)
	(via
		(at 61.4 107.5)
		(size 0.45)
		(drill 0.1)
		(layers "F.Cu" "B.Cu")
		(net 1)
	)
	(via
		(at 102.15 104.7)
		(size 0.45)
		(drill 0.1)
		(layers "F.Cu" "B.Cu")
		(net 1)
	)
	(via
		(at 207.5 128)
		(size 0.45)
		(drill 0.1)
		(layers "F.Cu" "B.Cu")
		(net 1)
	)
	(via
		(at 229.97 73.8)
		(size 0.45)
		(drill 0.1)
		(layers "F.Cu" "B.Cu")
		(net 1)
	)
	(via
		(at 95.530532 84.15)
		(size 0.45)
		(drill 0.1)
		(layers "F.Cu" "B.Cu")
		(net 1)
	)
	(via
		(at 173.05 143.92)
		(size 0.45)
		(drill 0.1)
		(layers "F.Cu" "B.Cu")
		(remove_unused_layers yes)
		(keep_end_layers yes)
		(free yes)
		(zone_layer_connections "In1.Cu" "In3.Cu" "In6.Cu" "In8.Cu")
		(net 1)
	)
	(via
		(at 121.530532 73.65)
		(size 0.45)
		(drill 0.1)
		(layers "F.Cu" "B.Cu")
		(net 1)
	)
	(via
		(at 170.9 137.5)
		(size 0.45)
		(drill 0.1)
		(layers "F.Cu" "B.Cu")
		(remove_unused_layers yes)
		(keep_end_layers yes)
		(zone_layer_connections "In1.Cu" "In3.Cu" "In6.Cu" "In8.Cu")
		(net 1)
	)
	(via
		(at 230.15 95.4)
		(size 0.45)
		(drill 0.1)
		(layers "F.Cu" "B.Cu")
		(net 1)
	)
	(via
		(at 69.425532 94.185)
		(size 0.45)
		(drill 0.1)
		(layers "F.Cu" "B.Cu")
		(net 1)
	)
	(via
		(at 65 153)
		(size 0.45)
		(drill 0.1)
		(layers "F.Cu" "B.Cu")
		(free yes)
		(net 1)
	)
	(via
		(at 225.15 80.65)
		(size 0.45)
		(drill 0.1)
		(layers "F.Cu" "B.Cu")
		(net 1)
	)
	(via
		(at 101.530532 82.65)
		(size 0.45)
		(drill 0.1)
		(layers "F.Cu" "B.Cu")
		(net 1)
	)
	(via
		(at 139.652 133.952)
		(size 0.45)
		(drill 0.1)
		(layers "F.Cu" "B.Cu")
		(net 1)
	)
	(via
		(at 202 129)
		(size 0.45)
		(drill 0.1)
		(layers "F.Cu" "B.Cu")
		(net 1)
	)
	(via
		(at 189.8 108.4)
		(size 0.45)
		(drill 0.1)
		(layers "F.Cu" "B.Cu")
		(free yes)
		(net 1)
	)
	(via
		(at 215.3 99.35)
		(size 0.45)
		(drill 0.1)
		(layers "F.Cu" "B.Cu")
		(net 1)
	)
	(via
		(at 165.74 93.1)
		(size 0.45)
		(drill 0.1)
		(layers "F.Cu" "B.Cu")
		(remove_unused_layers yes)
		(keep_end_layers yes)
		(free yes)
		(zone_layer_connections "In1.Cu" "In3.Cu" "In6.Cu" "In8.Cu")
		(net 1)
	)
	(via
		(at 100.230532 76.65)
		(size 0.45)
		(drill 0.1)
		(layers "F.Cu" "B.Cu")
		(free yes)
		(net 1)
	)
	(via
		(at 128.030532 75.15)
		(size 0.45)
		(drill 0.1)
		(layers "F.Cu" "B.Cu")
		(net 1)
	)
	(via
		(at 73.235532 78.945)
		(size 0.45)
		(drill 0.1)
		(layers "F.Cu" "B.Cu")
		(net 1)
	)
	(via
		(at 99.25 138.5)
		(size 0.45)
		(drill 0.1)
		(layers "F.Cu" "B.Cu")
		(free yes)
		(net 1)
	)
	(via
		(at 88 106.7)
		(size 0.45)
		(drill 0.1)
		(layers "F.Cu" "B.Cu")
		(net 1)
	)
	(via
		(at 74.505532 100.535)
		(size 0.45)
		(drill 0.1)
		(layers "F.Cu" "B.Cu")
		(net 1)
	)
	(via
		(at 70.695532 86.565)
		(size 0.45)
		(drill 0.1)
		(layers "F.Cu" "B.Cu")
		(net 1)
	)
	(via
		(at 125.76 61.67)
		(size 0.45)
		(drill 0.1)
		(layers "F.Cu" "B.Cu")
		(net 1)
	)
	(via
		(at 82.25 58)
		(size 0.45)
		(drill 0.1)
		(layers "F.Cu" "B.Cu")
		(net 1)
	)
	(via
		(at 169.6 146.65)
		(size 0.45)
		(drill 0.1)
		(layers "F.Cu" "B.Cu")
		(remove_unused_layers yes)
		(keep_end_layers yes)
		(zone_layer_connections "In1.Cu" "In3.Cu" "In6.Cu" "In8.Cu")
		(net 1)
	)
	(via
		(at 223.35 130.1)
		(size 0.45)
		(drill 0.1)
		(layers "F.Cu" "B.Cu")
		(net 1)
	)
	(via
		(at 230.1 131.3)
		(size 0.45)
		(drill 0.1)
		(layers "F.Cu" "B.Cu")
		(net 1)
	)
	(via
		(at 151 105.8)
		(size 0.45)
		(drill 0.1)
		(layers "F.Cu" "B.Cu")
		(net 1)
	)
	(via
		(at 174.82 143.94)
		(size 0.45)
		(drill 0.1)
		(layers "F.Cu" "B.Cu")
		(remove_unused_layers yes)
		(keep_end_layers yes)
		(free yes)
		(zone_layer_connections "In1.Cu" "In3.Cu" "In6.Cu" "In8.Cu")
		(net 1)
	)
	(via
		(at 67.8 92.7)
		(size 0.45)
		(drill 0.1)
		(layers "F.Cu" "B.Cu")
		(net 1)
	)
	(via
		(at 203.2 92.85)
		(size 0.45)
		(drill 0.1)
		(layers "F.Cu" "B.Cu")
		(net 1)
	)
	(via
		(at 171.040166 113.259834)
		(size 0.45)
		(drill 0.1)
		(layers "F.Cu" "B.Cu")
		(remove_unused_layers yes)
		(keep_end_layers yes)
		(zone_layer_connections "In1.Cu" "In3.Cu" "In6.Cu" "In8.Cu")
		(net 1)
	)
	(via
		(at 137.575 61.9)
		(size 0.45)
		(drill 0.1)
		(layers "F.Cu" "B.Cu")
		(net 1)
	)
	(via
		(at 74.505532 92.915)
		(size 0.45)
		(drill 0.1)
		(layers "F.Cu" "B.Cu")
		(net 1)
	)
	(via
		(at 80.855532 125.935)
		(size 0.45)
		(drill 0.1)
		(layers "F.Cu" "B.Cu")
		(net 1)
	)
	(via
		(at 123.55 84.16)
		(size 0.45)
		(drill 0.1)
		(layers "F.Cu" "B.Cu")
		(net 1)
	)
	(via
		(at 229.46 133.94)
		(size 0.45)
		(drill 0.1)
		(layers "F.Cu" "B.Cu")
		(net 1)
	)
	(via
		(at 229.97 76.2)
		(size 0.45)
		(drill 0.1)
		(layers "F.Cu" "B.Cu")
		(net 1)
	)
	(via
		(at 82.125532 110.695)
		(size 0.45)
		(drill 0.1)
		(layers "F.Cu" "B.Cu")
		(net 1)
	)
	(via
		(at 91.5 150.74)
		(size 0.45)
		(drill 0.1)
		(layers "F.Cu" "B.Cu")
		(net 1)
	)
	(via
		(at 84.665532 125.935)
		(size 0.45)
		(drill 0.1)
		(layers "F.Cu" "B.Cu")
		(net 1)
	)
	(via
		(at 71 151.5)
		(size 0.45)
		(drill 0.1)
		(layers "F.Cu" "B.Cu")
		(free yes)
		(net 1)
	)
	(via
		(at 204.6 111.3)
		(size 0.45)
		(drill 0.1)
		(layers "F.Cu" "B.Cu")
		(net 1)
	)
	(via
		(at 222.35 117.55)
		(size 0.45)
		(drill 0.1)
		(layers "F.Cu" "B.Cu")
		(net 1)
	)
	(via
		(at 115.620003 55.64)
		(size 0.45)
		(drill 0.1)
		(layers "F.Cu" "B.Cu")
		(net 1)
	)
	(via
		(at 159.1 143.2)
		(size 0.45)
		(drill 0.1)
		(layers "F.Cu" "B.Cu")
		(net 1)
	)
	(via
		(at 97.55 76.65)
		(size 0.45)
		(drill 0.1)
		(layers "F.Cu" "B.Cu")
		(net 1)
	)
	(via
		(at 227.7 54.75)
		(size 0.45)
		(drill 0.1)
		(layers "F.Cu" "B.Cu")
		(net 1)
	)
	(via
		(at 82.125532 122.125)
		(size 0.45)
		(drill 0.1)
		(layers "F.Cu" "B.Cu")
		(net 1)
	)
	(via
		(at 139.35 98.6)
		(size 0.45)
		(drill 0.1)
		(layers "F.Cu" "B.Cu")
		(net 1)
	)
	(via
		(at 113.750002 55.64)
		(size 0.45)
		(drill 0.1)
		(layers "F.Cu" "B.Cu")
		(net 1)
	)
	(via
		(at 178.84 128.95)
		(size 0.45)
		(drill 0.1)
		(layers "F.Cu" "B.Cu")
		(remove_unused_layers yes)
		(keep_end_layers yes)
		(free yes)
		(zone_layer_connections "In1.Cu" "In3.Cu" "In6.Cu" "In8.Cu")
		(net 1)
	)
	(via
		(at 198.9 96.4)
		(size 0.45)
		(drill 0.1)
		(layers "F.Cu" "B.Cu")
		(net 1)
	)
	(via
		(at 69.425532 84.025)
		(size 0.45)
		(drill 0.1)
		(layers "F.Cu" "B.Cu")
		(net 1)
	)
	(via
		(at 172.3 93)
		(size 0.45)
		(drill 0.1)
		(layers "F.Cu" "B.Cu")
		(remove_unused_layers yes)
		(keep_end_layers yes)
		(free yes)
		(zone_layer_connections "In1.Cu" "In3.Cu" "In6.Cu" "In8.Cu")
		(net 1)
	)
	(via
		(at 82.125532 101.805)
		(size 0.45)
		(drill 0.1)
		(layers "F.Cu" "B.Cu")
		(net 1)
	)
	(via
		(at 115.530532 72.15)
		(size 0.45)
		(drill 0.1)
		(layers "F.Cu" "B.Cu")
		(net 1)
	)
	(via
		(at 172.55 81.9)
		(size 0.45)
		(drill 0.1)
		(layers "F.Cu" "B.Cu")
		(remove_unused_layers yes)
		(keep_end_layers yes)
		(free yes)
		(zone_layer_connections "In1.Cu" "In3.Cu" "In6.Cu" "In8.Cu")
		(net 1)
	)
	(via
		(at 195.25 54.625)
		(size 0.45)
		(drill 0.1)
		(layers "F.Cu" "B.Cu")
		(net 1)
	)
	(via
		(at 235.37 73.7)
		(size 0.45)
		(drill 0.1)
		(layers "F.Cu" "B.Cu")
		(net 1)
	)
	(via
		(at 113.249999 55.64)
		(size 0.45)
		(drill 0.1)
		(layers "F.Cu" "B.Cu")
		(net 1)
	)
	(via
		(at 222.45 94.1)
		(size 0.45)
		(drill 0.1)
		(layers "F.Cu" "B.Cu")
		(net 1)
	)
	(via
		(at 123.55 75.15)
		(size 0.45)
		(drill 0.1)
		(layers "F.Cu" "B.Cu")
		(net 1)
	)
	(via
		(at 169.26 91.045856)
		(size 0.45)
		(drill 0.1)
		(layers "F.Cu" "B.Cu")
		(remove_unused_layers yes)
		(keep_end_layers yes)
		(free yes)
		(zone_layer_connections "In1.Cu" "In3.Cu" "In6.Cu" "In8.Cu")
		(net 1)
	)
	(via
		(at 112.6 129.7)
		(size 0.45)
		(drill 0.1)
		(layers "F.Cu" "B.Cu")
		(net 1)
	)
	(via
		(at 78.315532 106.885)
		(size 0.45)
		(drill 0.1)
		(layers "F.Cu" "B.Cu")
		(net 1)
	)
	(via
		(at 83.395532 97.995)
		(size 0.45)
		(drill 0.1)
		(layers "F.Cu" "B.Cu")
		(net 1)
	)
	(via
		(at 111.750999 63.45)
		(size 0.45)
		(drill 0.1)
		(layers "F.Cu" "B.Cu")
		(net 1)
	)
	(via
		(at 177.945 111.186)
		(size 0.45)
		(drill 0.1)
		(layers "F.Cu" "B.Cu")
		(remove_unused_layers yes)
		(keep_end_layers yes)
		(free yes)
		(zone_layer_connections "In1.Cu" "In3.Cu" "In6.Cu" "In8.Cu")
		(net 1)
	)
	(via
		(at 144.875 70.75)
		(size 0.45)
		(drill 0.1)
		(layers "F.Cu" "B.Cu")
		(net 1)
	)
	(via
		(at 192.026 142.1)
		(size 0.45)
		(drill 0.1)
		(layers "F.Cu" "B.Cu")
		(net 1)
	)
	(via
		(at 124.799997 58.71)
		(size 0.45)
		(drill 0.1)
		(layers "F.Cu" "B.Cu")
		(net 1)
	)
	(via
		(at 100.5 118.2)
		(size 0.45)
		(drill 0.1)
		(layers "F.Cu" "B.Cu")
		(net 1)
	)
	(via
		(at 206.52 63.453001)
		(size 0.45)
		(drill 0.1)
		(layers "F.Cu" "B.Cu")
		(net 1)
	)
	(via
		(at 80.855532 82.755)
		(size 0.45)
		(drill 0.1)
		(layers "F.Cu" "B.Cu")
		(net 1)
	)
	(via
		(at 178.85 111.95)
		(size 0.45)
		(drill 0.1)
		(layers "F.Cu" "B.Cu")
		(remove_unused_layers yes)
		(keep_end_layers yes)
		(free yes)
		(zone_layer_connections "In1.Cu" "In3.Cu" "In6.Cu" "In8.Cu")
		(net 1)
	)
	(via
		(at 197.658 59.8)
		(size 0.45)
		(drill 0.1)
		(layers "F.Cu" "B.Cu")
		(net 1)
	)
	(via
		(at 110.230532 84.15)
		(size 0.45)
		(drill 0.1)
		(layers "F.Cu" "B.Cu")
		(net 1)
	)
	(via
		(at 112.230532 82.65)
		(size 0.45)
		(drill 0.1)
		(layers "F.Cu" "B.Cu")
		(net 1)
	)
	(via
		(at 108.230532 76.65)
		(size 0.45)
		(drill 0.1)
		(layers "F.Cu" "B.Cu")
		(free yes)
		(net 1)
	)
	(via
		(at 114.230532 75.15)
		(size 0.45)
		(drill 0.1)
		(layers "F.Cu" "B.Cu")
		(net 1)
	)
	(via
		(at 112.5 138.75)
		(size 0.45)
		(drill 0.1)
		(layers "F.Cu" "B.Cu")
		(net 1)
	)
	(via
		(at 174.18 144.97)
		(size 0.45)
		(drill 0.1)
		(layers "F.Cu" "B.Cu")
		(remove_unused_layers yes)
		(keep_end_layers yes)
		(free yes)
		(zone_layer_connections "In1.Cu" "In3.Cu" "In6.Cu" "In8.Cu")
		(net 1)
	)
	(via
		(at 85.935532 124.665)
		(size 0.45)
		(drill 0.1)
		(layers "F.Cu" "B.Cu")
		(net 1)
	)
	(via
		(at 84.665532 101.805)
		(size 0.45)
		(drill 0.1)
		(layers "F.Cu" "B.Cu")
		(net 1)
	)
	(via
		(at 235.37 78.6)
		(size 0.45)
		(drill 0.1)
		(layers "F.Cu" "B.Cu")
		(net 1)
	)
	(via
		(at 174.6 128.35)
		(size 0.45)
		(drill 0.1)
		(layers "F.Cu" "B.Cu")
		(remove_unused_layers yes)
		(keep_end_layers yes)
		(free yes)
		(zone_layer_connections "In1.Cu" "In3.Cu" "In6.Cu" "In8.Cu")
		(net 1)
	)
	(via
		(at 93.2 98.5)
		(size 0.45)
		(drill 0.1)
		(layers "F.Cu" "B.Cu")
		(net 1)
	)
	(via
		(at 113.530532 73.65)
		(size 0.45)
		(drill 0.1)
		(layers "F.Cu" "B.Cu")
		(net 1)
	)
	(via
		(at 120.230532 79.65)
		(size 0.45)
		(drill 0.1)
		(layers "F.Cu" "B.Cu")
		(free yes)
		(net 1)
	)
	(via
		(at 175.9 111.2)
		(size 0.45)
		(drill 0.1)
		(layers "F.Cu" "B.Cu")
		(remove_unused_layers yes)
		(keep_end_layers yes)
		(free yes)
		(zone_layer_connections "In1.Cu" "In3.Cu" "In6.Cu" "In8.Cu")
		(net 1)
	)
	(via
		(at 199.126 148.7)
		(size 0.45)
		(drill 0.1)
		(layers "F.Cu" "B.Cu")
		(net 1)
	)
	(via
		(at 77.045532 127.205)
		(size 0.45)
		(drill 0.1)
		(layers "F.Cu" "B.Cu")
		(net 1)
	)
	(via
		(at 222.4 100.9)
		(size 0.45)
		(drill 0.1)
		(layers "F.Cu" "B.Cu")
		(net 1)
	)
	(via
		(at 229.87 112.9)
		(size 0.45)
		(drill 0.1)
		(layers "F.Cu" "B.Cu")
		(net 1)
	)
	(via
		(at 131.229997 56.61)
		(size 0.45)
		(drill 0.1)
		(layers "F.Cu" "B.Cu")
		(net 1)
	)
	(via
		(at 80.855532 114.505)
		(size 0.45)
		(drill 0.1)
		(layers "F.Cu" "B.Cu")
		(net 1)
	)
	(via
		(at 108.230532 79.65)
		(size 0.45)
		(drill 0.1)
		(layers "F.Cu" "B.Cu")
		(net 1)
	)
	(via
		(at 126.2 97)
		(size 0.45)
		(drill 0.1)
		(layers "F.Cu" "B.Cu")
		(net 1)
	)
	(via
		(at 142.79 58.32)
		(size 0.45)
		(drill 0.1)
		(layers "F.Cu" "B.Cu")
		(net 1)
	)
	(via
		(at 75.775532 125.935)
		(size 0.45)
		(drill 0.1)
		(layers "F.Cu" "B.Cu")
		(net 1)
	)
	(via
		(at 89.230532 78.15)
		(size 0.45)
		(drill 0.1)
		(layers "F.Cu" "B.Cu")
		(net 1)
	)
	(via
		(at 173.9 111.2)
		(size 0.45)
		(drill 0.1)
		(layers "F.Cu" "B.Cu")
		(remove_unused_layers yes)
		(keep_end_layers yes)
		(free yes)
		(zone_layer_connections "In1.Cu" "In3.Cu" "In6.Cu" "In8.Cu")
		(net 1)
	)
	(via
		(at 160.848936 99.565)
		(size 0.45)
		(drill 0.1)
		(layers "F.Cu" "B.Cu")
		(net 1)
	)
	(via
		(at 220.35 105.45)
		(size 0.45)
		(drill 0.1)
		(layers "F.Cu" "B.Cu")
		(net 1)
	)
	(via
		(at 77.045532 85.295)
		(size 0.45)
		(drill 0.1)
		(layers "F.Cu" "B.Cu")
		(net 1)
	)
	(via
		(at 70.695532 81.485)
		(size 0.45)
		(drill 0.1)
		(layers "F.Cu" "B.Cu")
		(net 1)
	)
	(via
		(at 98.5 138.25)
		(size 0.45)
		(drill 0.1)
		(layers "F.Cu" "B.Cu")
		(free yes)
		(net 1)
	)
	(via
		(at 78.315532 122.125)
		(size 0.45)
		(drill 0.1)
		(layers "F.Cu" "B.Cu")
		(net 1)
	)
	(via
		(at 62.8 102.9)
		(size 0.45)
		(drill 0.1)
		(layers "F.Cu" "B.Cu")
		(net 1)
	)
	(via
		(at 127.8 133.6)
		(size 0.45)
		(drill 0.1)
		(layers "F.Cu" "B.Cu")
		(net 1)
	)
	(via
		(at 168.06 91.045856)
		(size 0.45)
		(drill 0.1)
		(layers "F.Cu" "B.Cu")
		(remove_unused_layers yes)
		(keep_end_layers yes)
		(free yes)
		(zone_layer_connections "In1.Cu" "In3.Cu" "In6.Cu" "In8.Cu")
		(net 1)
	)
	(via
		(at 78.315532 84.025)
		(size 0.45)
		(drill 0.1)
		(layers "F.Cu" "B.Cu")
		(net 1)
	)
	(via
		(at 112.5 114)
		(size 0.45)
		(drill 0.1)
		(layers "F.Cu" "B.Cu")
		(net 1)
	)
	(via
		(at 84.665532 91.645)
		(size 0.45)
		(drill 0.1)
		(layers "F.Cu" "B.Cu")
		(net 1)
	)
	(via
		(at 97.530532 70.65)
		(size 0.45)
		(drill 0.1)
		(layers "F.Cu" "B.Cu")
		(net 1)
	)
	(via
		(at 179.2 80.4)
		(size 0.45)
		(drill 0.1)
		(layers "F.Cu" "B.Cu")
		(net 1)
	)
	(via
		(at 112.5 95.761)
		(size 0.45)
		(drill 0.1)
		(layers "F.Cu" "B.Cu")
		(net 1)
	)
	(via
		(at 129.630532 79.65)
		(size 0.45)
		(drill 0.1)
		(layers "F.Cu" "B.Cu")
		(net 1)
	)
	(via
		(at 97 143.25)
		(size 0.45)
		(drill 0.1)
		(layers "F.Cu" "B.Cu")
		(free yes)
		(net 1)
	)
	(via
		(at 137.930532 72.15)
		(size 0.45)
		(drill 0.1)
		(layers "F.Cu" "B.Cu")
		(net 1)
	)
	(via
		(at 168 101.15)
		(size 0.45)
		(drill 0.1)
		(layers "F.Cu" "B.Cu")
		(remove_unused_layers yes)
		(keep_end_layers yes)
		(free yes)
		(zone_layer_connections "In1.Cu" "In3.Cu" "In6.Cu" "In8.Cu")
		(net 1)
	)
	(via
		(at 125.570004 56.61)
		(size 0.45)
		(drill 0.1)
		(layers "F.Cu" "B.Cu")
		(net 1)
	)
	(via
		(at 71 141)
		(size 0.45)
		(drill 0.1)
		(layers "F.Cu" "B.Cu")
		(free yes)
		(net 1)
	)
	(via
		(at 88.125 135.925)
		(size 0.45)
		(drill 0.1)
		(layers "F.Cu" "B.Cu")
		(net 1)
	)
	(via
		(at 71.965532 115.775)
		(size 0.45)
		(drill 0.1)
		(layers "F.Cu" "B.Cu")
		(net 1)
	)
	(via
		(at 96.230532 76.65)
		(size 0.45)
		(drill 0.1)
		(layers "F.Cu" "B.Cu")
		(net 1)
	)
	(via
		(at 177.65 129.45)
		(size 0.45)
		(drill 0.1)
		(layers "F.Cu" "B.Cu")
		(remove_unused_layers yes)
		(keep_end_layers yes)
		(free yes)
		(zone_layer_connections "In1.Cu" "In3.Cu" "In6.Cu" "In8.Cu")
		(net 1)
	)
	(via
		(at 200.8 68)
		(size 0.45)
		(drill 0.1)
		(layers "F.Cu" "B.Cu")
		(net 1)
	)
	(via
		(at 83.395532 119.585)
		(size 0.45)
		(drill 0.1)
		(layers "F.Cu" "B.Cu")
		(net 1)
	)
	(via
		(at 98.5 146.25)
		(size 0.45)
		(drill 0.1)
		(layers "F.Cu" "B.Cu")
		(free yes)
		(net 1)
	)
	(via
		(at 166.15 101.15)
		(size 0.45)
		(drill 0.1)
		(layers "F.Cu" "B.Cu")
		(remove_unused_layers yes)
		(keep_end_layers yes)
		(free yes)
		(zone_layer_connections "In1.Cu" "In3.Cu" "In6.Cu" "In8.Cu")
		(net 1)
	)
	(via
		(at 212.7 66)
		(size 0.45)
		(drill 0.1)
		(layers "F.Cu" "B.Cu")
		(net 1)
	)
	(via
		(at 229.87 117.5)
		(size 0.45)
		(drill 0.1)
		(layers "F.Cu" "B.Cu")
		(net 1)
	)
	(via
		(at 85.95 94.25)
		(size 0.45)
		(drill 0.1)
		(layers "F.Cu" "B.Cu")
		(net 1)
	)
	(via
		(at 206.5 79.2)
		(size 0.45)
		(drill 0.1)
		(layers "F.Cu" "B.Cu")
		(net 1)
	)
	(via
		(at 70.695532 125.935)
		(size 0.45)
		(drill 0.1)
		(layers "F.Cu" "B.Cu")
		(net 1)
	)
	(via
		(at 223.75 113.1)
		(size 0.45)
		(drill 0.1)
		(layers "F.Cu" "B.Cu")
		(net 1)
	)
	(via
		(at 66.8 89.4)
		(size 0.45)
		(drill 0.1)
		(layers "F.Cu" "B.Cu")
		(net 1)
	)
	(via
		(at 116.230532 76.65)
		(size 0.45)
		(drill 0.1)
		(layers "F.Cu" "B.Cu")
		(net 1)
	)
	(via
		(at 60.6 127)
		(size 0.45)
		(drill 0.1)
		(layers "F.Cu" "B.Cu")
		(free yes)
		(net 1)
	)
	(via
		(at 220.75 83.65)
		(size 0.45)
		(drill 0.1)
		(layers "F.Cu" "B.Cu")
		(net 1)
	)
	(via
		(at 136.3 58.6)
		(size 0.45)
		(drill 0.1)
		(layers "F.Cu" "B.Cu")
		(net 1)
	)
	(via
		(at 166.66 81.15)
		(size 0.45)
		(drill 0.1)
		(layers "F.Cu" "B.Cu")
		(remove_unused_layers yes)
		(keep_end_layers yes)
		(free yes)
		(zone_layer_connections "In1.Cu" "In3.Cu" "In6.Cu" "In8.Cu")
		(net 1)
	)
	(via
		(at 70.695532 101.805)
		(size 0.45)
		(drill 0.1)
		(layers "F.Cu" "B.Cu")
		(net 1)
	)
	(via
		(at 191.025999 141.4)
		(size 0.45)
		(drill 0.1)
		(layers "F.Cu" "B.Cu")
		(net 1)
	)
	(via
		(at 80.855532 123.395)
		(size 0.45)
		(drill 0.1)
		(layers "F.Cu" "B.Cu")
		(net 1)
	)
	(via
		(at 191.576 141.75)
		(size 0.45)
		(drill 0.1)
		(layers "F.Cu" "B.Cu")
		(net 1)
	)
	(via
		(at 144.4 55.2)
		(size 0.45)
		(drill 0.1)
		(layers "F.Cu" "B.Cu")
		(net 1)
	)
	(via
		(at 80.855532 87.835)
		(size 0.45)
		(drill 0.1)
		(layers "F.Cu" "B.Cu")
		(net 1)
	)
	(via
		(at 85.3 79.6)
		(size 0.45)
		(drill 0.1)
		(layers "F.Cu" "B.Cu")
		(net 1)
	)
	(via
		(at 173.55 93)
		(size 0.45)
		(drill 0.1)
		(layers "F.Cu" "B.Cu")
		(remove_unused_layers yes)
		(keep_end_layers yes)
		(free yes)
		(zone_layer_connections "In1.Cu" "In3.Cu" "In6.Cu" "In8.Cu")
		(net 1)
	)
	(via
		(at 95.530532 75.15)
		(size 0.45)
		(drill 0.1)
		(layers "F.Cu" "B.Cu")
		(net 1)
	)
	(via
		(at 73.235532 82.755)
		(size 0.45)
		(drill 0.1)
		(layers "F.Cu" "B.Cu")
		(net 1)
	)
	(via
		(at 75.775532 91.645)
		(size 0.45)
		(drill 0.1)
		(layers "F.Cu" "B.Cu")
		(net 1)
	)
	(via
		(at 160.66 92.695856)
		(size 0.45)
		(drill 0.1)
		(layers "F.Cu" "B.Cu")
		(remove_unused_layers yes)
		(keep_end_layers yes)
		(free yes)
		(zone_layer_connections "In1.Cu" "In3.Cu" "In6.Cu" "In8.Cu")
		(net 1)
	)
	(via
		(at 80.855532 103.075)
		(size 0.45)
		(drill 0.1)
		(layers "F.Cu" "B.Cu")
		(net 1)
	)
	(via
		(at 223.2 86.45)
		(size 0.45)
		(drill 0.1)
		(layers "F.Cu" "B.Cu")
		(net 1)
	)
	(via
		(at 75.775532 95.455)
		(size 0.45)
		(drill 0.1)
		(layers "F.Cu" "B.Cu")
		(net 1)
	)
	(via
		(at 63.2 84.3)
		(size 0.45)
		(drill 0.1)
		(layers "F.Cu" "B.Cu")
		(net 1)
	)
	(via
		(at 83.395532 94.185)
		(size 0.45)
		(drill 0.1)
		(layers "F.Cu" "B.Cu")
		(net 1)
	)
	(via
		(at 190.676 140.95)
		(size 0.45)
		(drill 0.1)
		(layers "F.Cu" "B.Cu")
		(net 1)
	)
	(via
		(at 161.85 72.25)
		(size 0.45)
		(drill 0.1)
		(layers "F.Cu" "B.Cu")
		(remove_unused_layers yes)
		(keep_end_layers yes)
		(free yes)
		(zone_layer_connections "In1.Cu" "In3.Cu" "In6.Cu" "In8.Cu")
		(net 1)
	)
	(via
		(at 101.530532 79.65)
		(size 0.45)
		(drill 0.1)
		(layers "F.Cu" "B.Cu")
		(net 1)
	)
	(via
		(at 173 91.045856)
		(size 0.45)
		(drill 0.1)
		(layers "F.Cu" "B.Cu")
		(remove_unused_layers yes)
		(keep_end_layers yes)
		(free yes)
		(zone_layer_connections "In1.Cu" "In3.Cu" "In6.Cu" "In8.Cu")
		(net 1)
	)
	(via
		(at 222.45 92.65)
		(size 0.45)
		(drill 0.1)
		(layers "F.Cu" "B.Cu")
		(net 1)
	)
	(via
		(at 92.5 107.1)
		(size 0.45)
		(drill 0.1)
		(layers "F.Cu" "B.Cu")
		(net 1)
	)
	(via
		(at 202.7 113.1)
		(size 0.45)
		(drill 0.1)
		(layers "F.Cu" "B.Cu")
		(net 1)
	)
	(via
		(at 62.8 104.8)
		(size 0.45)
		(drill 0.1)
		(layers "F.Cu" "B.Cu")
		(net 1)
	)
	(via
		(at 128.030532 78.15)
		(size 0.45)
		(drill 0.1)
		(layers "F.Cu" "B.Cu")
		(net 1)
	)
	(via
		(at 80.855532 89.105)
		(size 0.45)
		(drill 0.1)
		(layers "F.Cu" "B.Cu")
		(net 1)
	)
	(via
		(at 122.25 78.15)
		(size 0.45)
		(drill 0.1)
		(layers "F.Cu" "B.Cu")
		(net 1)
	)
	(via
		(at 175.41 91.045856)
		(size 0.45)
		(drill 0.1)
		(layers "F.Cu" "B.Cu")
		(remove_unused_layers yes)
		(keep_end_layers yes)
		(free yes)
		(zone_layer_connections "In1.Cu" "In3.Cu" "In6.Cu" "In8.Cu")
		(net 1)
	)
	(via
		(at 95.530532 81.15)
		(size 0.45)
		(drill 0.1)
		(layers "F.Cu" "B.Cu")
		(net 1)
	)
	(via
		(at 125.91 60.3)
		(size 0.45)
		(drill 0.1)
		(layers "F.Cu" "B.Cu")
		(net 1)
	)
	(via
		(at 84.665532 117.045)
		(size 0.45)
		(drill 0.1)
		(layers "F.Cu" "B.Cu")
		(net 1)
	)
	(via
		(at 119.530532 78.15)
		(size 0.45)
		(drill 0.1)
		(layers "F.Cu" "B.Cu")
		(net 1)
	)
	(via
		(at 95.9 65.1)
		(size 0.45)
		(drill 0.1)
		(layers "F.Cu" "B.Cu")
		(net 1)
	)
	(via
		(at 167.2 140.6)
		(size 0.45)
		(drill 0.1)
		(layers "F.Cu" "B.Cu")
		(net 1)
	)
	(via
		(at 83.395532 87.835)
		(size 0.45)
		(drill 0.1)
		(layers "F.Cu" "B.Cu")
		(net 1)
	)
	(via
		(at 100.9 132.7)
		(size 0.45)
		(drill 0.1)
		(layers "F.Cu" "B.Cu")
		(net 1)
	)
	(via
		(at 223.25 117.6)
		(size 0.45)
		(drill 0.1)
		(layers "F.Cu" "B.Cu")
		(net 1)
	)
	(via
		(at 181.49 127)
		(size 0.45)
		(drill 0.1)
		(layers "F.Cu" "B.Cu")
		(remove_unused_layers yes)
		(keep_end_layers yes)
		(free yes)
		(zone_layer_connections "In1.Cu" "In3.Cu" "In6.Cu" "In8.Cu")
		(net 1)
	)
	(via
		(at 77.045532 119.585)
		(size 0.45)
		(drill 0.1)
		(layers "F.Cu" "B.Cu")
		(net 1)
	)
	(via
		(at 139.730532 81.15)
		(size 0.45)
		(drill 0.1)
		(layers "F.Cu" "B.Cu")
		(net 1)
	)
	(via
		(at 92.7 92.75)
		(size 0.45)
		(drill 0.1)
		(layers "F.Cu" "B.Cu")
		(net 1)
	)
	(via
		(at 103.530532 72.15)
		(size 0.45)
		(drill 0.1)
		(layers "F.Cu" "B.Cu")
		(net 1)
	)
	(via
		(at 78.315532 82.755)
		(size 0.45)
		(drill 0.1)
		(layers "F.Cu" "B.Cu")
		(net 1)
	)
	(via
		(at 112.5 109.261)
		(size 0.45)
		(drill 0.1)
		(layers "F.Cu" "B.Cu")
		(net 1)
	)
	(via
		(at 204.476 145)
		(size 0.45)
		(drill 0.1)
		(layers "F.Cu" "B.Cu")
		(net 1)
	)
	(via
		(at 98.230532 84.15)
		(size 0.45)
		(drill 0.1)
		(layers "F.Cu" "B.Cu")
		(net 1)
	)
	(via
		(at 203.25 54.5)
		(size 0.45)
		(drill 0.1)
		(layers "F.Cu" "B.Cu")
		(net 1)
	)
	(via
		(at 222.4 99.3)
		(size 0.45)
		(drill 0.1)
		(layers "F.Cu" "B.Cu")
		(net 1)
	)
	(via
		(at 182.05 110)
		(size 0.45)
		(drill 0.1)
		(layers "F.Cu" "B.Cu")
		(remove_unused_layers yes)
		(keep_end_layers yes)
		(free yes)
		(zone_layer_connections "In1.Cu" "In3.Cu" "In6.Cu" "In8.Cu")
		(net 1)
	)
	(via
		(at 180.54 128.4)
		(size 0.45)
		(drill 0.1)
		(layers "F.Cu" "B.Cu")
		(remove_unused_layers yes)
		(keep_end_layers yes)
		(free yes)
		(zone_layer_connections "In1.Cu" "In3.Cu" "In6.Cu" "In8.Cu")
		(net 1)
	)
	(via
		(at 230 107.2)
		(size 0.45)
		(drill 0.1)
		(layers "F.Cu" "B.Cu")
		(net 1)
	)
	(via
		(at 131.73 56.61)
		(size 0.45)
		(drill 0.1)
		(layers "F.Cu" "B.Cu")
		(net 1)
	)
	(via
		(at 84.665532 120.855)
		(size 0.45)
		(drill 0.1)
		(layers "F.Cu" "B.Cu")
		(net 1)
	)
	(via
		(at 92.3 98.65)
		(size 0.45)
		(drill 0.1)
		(layers "F.Cu" "B.Cu")
		(net 1)
	)
	(via
		(at 173.35 81.1)
		(size 0.45)
		(drill 0.1)
		(layers "F.Cu" "B.Cu")
		(remove_unused_layers yes)
		(keep_end_layers yes)
		(free yes)
		(zone_layer_connections "In1.Cu" "In3.Cu" "In6.Cu" "In8.Cu")
		(net 1)
	)
	(via
		(at 123.530532 81.15)
		(size 0.45)
		(drill 0.1)
		(layers "F.Cu" "B.Cu")
		(net 1)
	)
	(via
		(at 106.5 66)
		(size 0.45)
		(drill 0.1)
		(layers "F.Cu" "B.Cu")
		(net 1)
	)
	(via
		(at 111.880004 55.640001)
		(size 0.45)
		(drill 0.1)
		(layers "F.Cu" "B.Cu")
		(net 1)
	)
	(via
		(at 195.13 97.635)
		(size 0.45)
		(drill 0.1)
		(layers "F.Cu" "B.Cu")
		(net 1)
	)
	(via
		(at 135.5 58.6)
		(size 0.45)
		(drill 0.1)
		(layers "F.Cu" "B.Cu")
		(net 1)
	)
	(via
		(at 122.230532 84.15)
		(size 0.45)
		(drill 0.1)
		(layers "F.Cu" "B.Cu")
		(net 1)
	)
	(via
		(at 224.5 122.6)
		(size 0.45)
		(drill 0.1)
		(layers "F.Cu" "B.Cu")
		(net 1)
	)
	(via
		(at 231.27 112.1)
		(size 0.45)
		(drill 0.1)
		(layers "F.Cu" "B.Cu")
		(net 1)
	)
	(via
		(at 116.230532 79.65)
		(size 0.45)
		(drill 0.1)
		(layers "F.Cu" "B.Cu")
		(free yes)
		(net 1)
	)
	(via
		(at 136.130532 84.15)
		(size 0.45)
		(drill 0.1)
		(layers "F.Cu" "B.Cu")
		(net 1)
	)
	(via
		(at 79.585532 81.485)
		(size 0.45)
		(drill 0.1)
		(layers "F.Cu" "B.Cu")
		(net 1)
	)
	(via
		(at 196 121.9)
		(size 0.45)
		(drill 0.1)
		(layers "F.Cu" "B.Cu")
		(remove_unused_layers yes)
		(keep_end_layers yes)
		(zone_layer_connections "In1.Cu" "In3.Cu" "In6.Cu" "In8.Cu")
		(net 1)
	)
	(via
		(at 164.2 144.05)
		(size 0.45)
		(drill 0.1)
		(layers "F.Cu" "B.Cu")
		(net 1)
	)
	(via
		(at 197.4 64.4)
		(size 0.45)
		(drill 0.1)
		(layers "F.Cu" "B.Cu")
		(net 1)
	)
	(via
		(at 95 54.4)
		(size 0.45)
		(drill 0.1)
		(layers "F.Cu" "B.Cu")
		(net 1)
	)
	(via
		(at 77.045532 123.395)
		(size 0.45)
		(drill 0.1)
		(layers "F.Cu" "B.Cu")
		(net 1)
	)
	(via
		(at 124.25 76.625)
		(size 0.45)
		(drill 0.1)
		(layers "F.Cu" "B.Cu")
		(net 1)
	)
	(via
		(at 129.630532 76.65)
		(size 0.45)
		(drill 0.1)
		(layers "F.Cu" "B.Cu")
		(net 1)
	)
	(via
		(at 126.930532 82.65)
		(size 0.45)
		(drill 0.1)
		(layers "F.Cu" "B.Cu")
		(net 1)
	)
	(via
		(at 91.5 64.75)
		(size 0.45)
		(drill 0.1)
		(layers "F.Cu" "B.Cu")
		(net 1)
	)
	(via
		(at 98.65 115.5)
		(size 0.45)
		(drill 0.1)
		(layers "F.Cu" "B.Cu")
		(net 1)
	)
	(via
		(at 176.75 62.5)
		(size 0.45)
		(drill 0.1)
		(layers "F.Cu" "B.Cu")
		(net 1)
	)
	(via
		(at 179.27 144.01)
		(size 0.45)
		(drill 0.1)
		(layers "F.Cu" "B.Cu")
		(remove_unused_layers yes)
		(keep_end_layers yes)
		(free yes)
		(zone_layer_connections "In1.Cu" "In3.Cu" "In6.Cu" "In8.Cu")
		(net 1)
	)
	(via
		(at 181.12 144.02)
		(size 0.45)
		(drill 0.1)
		(layers "F.Cu" "B.Cu")
		(remove_unused_layers yes)
		(keep_end_layers yes)
		(free yes)
		(zone_layer_connections "In1.Cu" "In3.Cu" "In6.Cu" "In8.Cu")
		(net 1)
	)
	(via
		(at 88.130532 76.65)
		(size 0.45)
		(drill 0.1)
		(layers "F.Cu" "B.Cu")
		(net 1)
	)
	(via
		(at 97.75 143.25)
		(size 0.45)
		(drill 0.1)
		(layers "F.Cu" "B.Cu")
		(free yes)
		(net 1)
	)
	(via
		(at 66.6 104.8)
		(size 0.45)
		(drill 0.1)
		(layers "F.Cu" "B.Cu")
		(net 1)
	)
	(via
		(at 98.9 118.5)
		(size 0.45)
		(drill 0.1)
		(layers "F.Cu" "B.Cu")
		(net 1)
	)
	(via
		(at 105.530532 76.65)
		(size 0.45)
		(drill 0.1)
		(layers "F.Cu" "B.Cu")
		(net 1)
	)
	(via
		(at 79.585532 105.615)
		(size 0.45)
		(drill 0.1)
		(layers "F.Cu" "B.Cu")
		(net 1)
	)
	(via
		(at 122.230532 75.15)
		(size 0.45)
		(drill 0.1)
		(layers "F.Cu" "B.Cu")
		(free yes)
		(net 1)
	)
	(via
		(at 181.09 128.95)
		(size 0.45)
		(drill 0.1)
		(layers "F.Cu" "B.Cu")
		(remove_unused_layers yes)
		(keep_end_layers yes)
		(free yes)
		(zone_layer_connections "In1.Cu" "In3.Cu" "In6.Cu" "In8.Cu")
		(net 1)
	)
	(via
		(at 229.87 130.5)
		(size 0.45)
		(drill 0.1)
		(layers "F.Cu" "B.Cu")
		(net 1)
	)
	(via
		(at 60.6 142.5)
		(size 0.45)
		(drill 0.1)
		(layers "F.Cu" "B.Cu")
		(free yes)
		(net 1)
	)
	(via
		(at 163.47 81.16)
		(size 0.45)
		(drill 0.1)
		(layers "F.Cu" "B.Cu")
		(remove_unused_layers yes)
		(keep_end_layers yes)
		(free yes)
		(zone_layer_connections "In1.Cu" "In3.Cu" "In6.Cu" "In8.Cu")
		(net 1)
	)
	(via
		(at 168.4 91.4)
		(size 0.45)
		(drill 0.1)
		(layers "F.Cu" "B.Cu")
		(remove_unused_layers yes)
		(keep_end_layers yes)
		(free yes)
		(zone_layer_connections "In1.Cu" "In3.Cu" "In6.Cu" "In8.Cu")
		(net 1)
	)
	(via
		(at 80.855532 108.155)
		(size 0.45)
		(drill 0.1)
		(layers "F.Cu" "B.Cu")
		(net 1)
	)
	(via
		(at 211.4 95.9)
		(size 0.45)
		(drill 0.1)
		(layers "F.Cu" "B.Cu")
		(net 1)
	)
	(via
		(at 154.8 96.8)
		(size 0.45)
		(drill 0.1)
		(layers "F.Cu" "B.Cu")
		(net 1)
	)
	(via
		(at 175.99 93)
		(size 0.45)
		(drill 0.1)
		(layers "F.Cu" "B.Cu")
		(remove_unused_layers yes)
		(keep_end_layers yes)
		(free yes)
		(zone_layer_connections "In1.Cu" "In3.Cu" "In6.Cu" "In8.Cu")
		(net 1)
	)
	(via
		(at 70.695532 95.455)
		(size 0.45)
		(drill 0.1)
		(layers "F.Cu" "B.Cu")
		(net 1)
	)
	(via
		(at 102.230532 78.15)
		(size 0.45)
		(drill 0.1)
		(layers "F.Cu" "B.Cu")
		(net 1)
	)
	(via
		(at 84.665532 86.565)
		(size 0.45)
		(drill 0.1)
		(layers "F.Cu" "B.Cu")
		(net 1)
	)
	(via
		(at 166.25 54.6)
		(size 0.45)
		(drill 0.1)
		(layers "F.Cu" "B.Cu")
		(net 1)
	)
	(via
		(at 101.530532 85.65)
		(size 0.45)
		(drill 0.1)
		(layers "F.Cu" "B.Cu")
		(net 1)
	)
	(via
		(at 135.6 66.6)
		(size 0.45)
		(drill 0.1)
		(layers "F.Cu" "B.Cu")
		(net 1)
	)
	(via
		(at 93.35 88.9)
		(size 0.45)
		(drill 0.1)
		(layers "F.Cu" "B.Cu")
		(net 1)
	)
	(via
		(at 165.77 58.99)
		(size 0.45)
		(drill 0.1)
		(layers "F.Cu" "B.Cu")
		(net 1)
	)
	(via
		(at 73.235532 103.075)
		(size 0.45)
		(drill 0.1)
		(layers "F.Cu" "B.Cu")
		(net 1)
	)
	(via
		(at 210.2 81.8)
		(size 0.45)
		(drill 0.1)
		(layers "F.Cu" "B.Cu")
		(net 1)
	)
	(via
		(at 222.4 102.4)
		(size 0.45)
		(drill 0.1)
		(layers "F.Cu" "B.Cu")
		(net 1)
	)
	(via
		(at 74.505532 89.105)
		(size 0.45)
		(drill 0.1)
		(layers "F.Cu" "B.Cu")
		(net 1)
	)
	(via
		(at 187.6 124.4)
		(size 0.45)
		(drill 0.1)
		(layers "F.Cu" "B.Cu")
		(net 1)
	)
	(via
		(at 132.825 56.75)
		(size 0.45)
		(drill 0.1)
		(layers "F.Cu" "B.Cu")
		(remove_unused_layers yes)
		(keep_end_layers yes)
		(zone_layer_connections "In1.Cu" "In3.Cu" "In6.Cu" "In8.Cu")
		(net 1)
	)
	(via
		(at 229.07 104.1)
		(size 0.45)
		(drill 0.1)
		(layers "F.Cu" "B.Cu")
		(net 1)
	)
	(via
		(at 71 134)
		(size 0.45)
		(drill 0.1)
		(layers "F.Cu" "B.Cu")
		(free yes)
		(net 1)
	)
	(via
		(at 208.55 105.45)
		(size 0.45)
		(drill 0.1)
		(layers "F.Cu" "B.Cu")
		(net 1)
	)
	(via
		(at 223.25 116.25)
		(size 0.45)
		(drill 0.1)
		(layers "F.Cu" "B.Cu")
		(net 1)
	)
	(via
		(at 62 153)
		(size 0.45)
		(drill 0.1)
		(layers "F.Cu" "B.Cu")
		(free yes)
		(net 1)
	)
	(via
		(at 112.5 121.75)
		(size 0.45)
		(drill 0.1)
		(layers "F.Cu" "B.Cu")
		(net 1)
	)
	(via
		(at 60.6 144.000001)
		(size 0.45)
		(drill 0.1)
		(layers "F.Cu" "B.Cu")
		(free yes)
		(net 1)
	)
	(via
		(at 98.5 144)
		(size 0.45)
		(drill 0.1)
		(layers "F.Cu" "B.Cu")
		(free yes)
		(net 1)
	)
	(via
		(at 117.530532 73.65)
		(size 0.45)
		(drill 0.1)
		(layers "F.Cu" "B.Cu")
		(net 1)
	)
	(via
		(at 187.25 54.5)
		(size 0.45)
		(drill 0.1)
		(layers "F.Cu" "B.Cu")
		(net 1)
	)
	(via
		(at 112.1 95.261)
		(size 0.45)
		(drill 0.1)
		(layers "F.Cu" "B.Cu")
		(net 1)
	)
	(via
		(at 123.4 143.1)
		(size 0.45)
		(drill 0.1)
		(layers "F.Cu" "B.Cu")
		(net 1)
	)
	(via
		(at 95.25 63.5)
		(size 0.45)
		(drill 0.1)
		(layers "F.Cu" "B.Cu")
		(net 1)
	)
	(via
		(at 85.935532 108.155)
		(size 0.45)
		(drill 0.1)
		(layers "F.Cu" "B.Cu")
		(net 1)
	)
	(via
		(at 196.4 116.6)
		(size 0.45)
		(drill 0.1)
		(layers "F.Cu" "B.Cu")
		(net 1)
	)
	(via
		(at 101 67.5)
		(size 0.45)
		(drill 0.1)
		(layers "F.Cu" "B.Cu")
		(net 1)
	)
	(via
		(at 75.775532 128.475)
		(size 0.45)
		(drill 0.1)
		(layers "F.Cu" "B.Cu")
		(net 1)
	)
	(via
		(at 206.6 101.8)
		(size 0.45)
		(drill 0.1)
		(layers "F.Cu" "B.Cu")
		(net 1)
	)
	(via
		(at 125.070001 56.61)
		(size 0.45)
		(drill 0.1)
		(layers "F.Cu" "B.Cu")
		(net 1)
	)
	(via
		(at 169.78 69.94)
		(size 0.45)
		(drill 0.1)
		(layers "F.Cu" "B.Cu")
		(remove_unused_layers yes)
		(keep_end_layers yes)
		(free yes)
		(zone_layer_connections "In1.Cu" "In3.Cu" "In6.Cu" "In8.Cu")
		(net 1)
	)
	(via
		(at 93 97.9)
		(size 0.45)
		(drill 0.1)
		(layers "F.Cu" "B.Cu")
		(net 1)
	)
	(via
		(at 206.8 84)
		(size 0.45)
		(drill 0.1)
		(layers "F.Cu" "B.Cu")
		(net 1)
	)
	(via
		(at 80.855532 78.945)
		(size 0.45)
		(drill 0.1)
		(layers "F.Cu" "B.Cu")
		(net 1)
	)
	(via
		(at 113.8 74.4)
		(size 0.45)
		(drill 0.1)
		(layers "F.Cu" "B.Cu")
		(net 1)
	)
	(via
		(at 186.95 126.6)
		(size 0.45)
		(drill 0.1)
		(layers "F.Cu" "B.Cu")
		(remove_unused_layers yes)
		(keep_end_layers yes)
		(zone_layer_connections "In1.Cu" "In3.Cu" "In6.Cu" "In8.Cu")
		(net 1)
	)
	(via
		(at 112.5 98.761)
		(size 0.45)
		(drill 0.1)
		(layers "F.Cu" "B.Cu")
		(net 1)
	)
	(via
		(at 126.1 112)
		(size 0.45)
		(drill 0.1)
		(layers "F.Cu" "B.Cu")
		(net 1)
	)
	(via
		(at 193.375001 83.025)
		(size 0.45)
		(drill 0.1)
		(layers "F.Cu" "B.Cu")
		(net 1)
	)
	(via
		(at 97.75 144)
		(size 0.45)
		(drill 0.1)
		(layers "F.Cu" "B.Cu")
		(free yes)
		(net 1)
	)
	(via
		(at 137.85 98.65)
		(size 0.45)
		(drill 0.1)
		(layers "F.Cu" "B.Cu")
		(net 1)
	)
	(via
		(at 235.47 91.65)
		(size 0.45)
		(drill 0.1)
		(layers "F.Cu" "B.Cu")
		(net 1)
	)
	(via
		(at 88.66 86.55)
		(size 0.45)
		(drill 0.1)
		(layers "F.Cu" "B.Cu")
		(net 1)
	)
	(via
		(at 234.17 105.3)
		(size 0.45)
		(drill 0.1)
		(layers "F.Cu" "B.Cu")
		(net 1)
	)
	(via
		(at 210.75 133.7)
		(size 0.45)
		(drill 0.1)
		(layers "F.Cu" "B.Cu")
		(net 1)
	)
	(via
		(at 116.230532 70.65)
		(size 0.45)
		(drill 0.1)
		(layers "F.Cu" "B.Cu")
		(net 1)
	)
	(via
		(at 125.330532 75.15)
		(size 0.45)
		(drill 0.1)
		(layers "F.Cu" "B.Cu")
		(net 1)
	)
	(via
		(at 133.8 151.2)
		(size 0.45)
		(drill 0.1)
		(layers "F.Cu" "B.Cu")
		(net 1)
	)
	(via
		(at 166.99 93.1)
		(size 0.45)
		(drill 0.1)
		(layers "F.Cu" "B.Cu")
		(remove_unused_layers yes)
		(keep_end_layers yes)
		(free yes)
		(zone_layer_connections "In1.Cu" "In3.Cu" "In6.Cu" "In8.Cu")
		(net 1)
	)
	(via
		(at 70.695532 110.695)
		(size 0.45)
		(drill 0.1)
		(layers "F.Cu" "B.Cu")
		(net 1)
	)
	(via
		(at 69.425532 109.425)
		(size 0.45)
		(drill 0.1)
		(layers "F.Cu" "B.Cu")
		(net 1)
	)
	(via
		(at 66.7 97.4)
		(size 0.45)
		(drill 0.1)
		(layers "F.Cu" "B.Cu")
		(net 1)
	)
	(via
		(at 235 70.4)
		(size 0.45)
		(drill 0.1)
		(layers "F.Cu" "B.Cu")
		(net 1)
	)
	(via
		(at 223.75 114.45)
		(size 0.45)
		(drill 0.1)
		(layers "F.Cu" "B.Cu")
		(net 1)
	)
	(via
		(at 144.030532 76.65)
		(size 0.45)
		(drill 0.1)
		(layers "F.Cu" "B.Cu")
		(net 1)
	)
	(via
		(at 164.54 93.1)
		(size 0.45)
		(drill 0.1)
		(layers "F.Cu" "B.Cu")
		(remove_unused_layers yes)
		(keep_end_layers yes)
		(free yes)
		(zone_layer_connections "In1.Cu" "In3.Cu" "In6.Cu" "In8.Cu")
		(net 1)
	)
	(via
		(at 161 93.05)
		(size 0.45)
		(drill 0.1)
		(layers "F.Cu" "B.Cu")
		(remove_unused_layers yes)
		(keep_end_layers yes)
		(free yes)
		(zone_layer_connections "In1.Cu" "In3.Cu" "In6.Cu" "In8.Cu")
		(net 1)
	)
	(via
		(at 193.2 69)
		(size 0.45)
		(drill 0.1)
		(layers "F.Cu" "B.Cu")
		(net 1)
	)
	(via
		(at 199.126 146.3)
		(size 0.45)
		(drill 0.1)
		(layers "F.Cu" "B.Cu")
		(net 1)
	)
	(via
		(at 171.5 61.25)
		(size 0.45)
		(drill 0.1)
		(layers "F.Cu" "B.Cu")
		(net 1)
	)
	(via
		(at 71 144)
		(size 0.45)
		(drill 0.1)
		(layers "F.Cu" "B.Cu")
		(free yes)
		(net 1)
	)
	(via
		(at 82.125532 86.565)
		(size 0.45)
		(drill 0.1)
		(layers "F.Cu" "B.Cu")
		(net 1)
	)
	(via
		(at 85.935532 92.915)
		(size 0.45)
		(drill 0.1)
		(layers "F.Cu" "B.Cu")
		(net 1)
	)
	(via
		(at 173.34 91.4)
		(size 0.45)
		(drill 0.1)
		(layers "F.Cu" "B.Cu")
		(remove_unused_layers yes)
		(keep_end_layers yes)
		(free yes)
		(zone_layer_connections "In1.Cu" "In3.Cu" "In6.Cu" "In8.Cu")
		(net 1)
	)
	(via
		(at 121.530532 85.65)
		(size 0.45)
		(drill 0.1)
		(layers "F.Cu" "B.Cu")
		(net 1)
	)
	(via
		(at 138.9 110)
		(size 0.45)
		(drill 0.1)
		(layers "F.Cu" "B.Cu")
		(net 1)
	)
	(via
		(at 174.95 112.9)
		(size 0.45)
		(drill 0.1)
		(layers "F.Cu" "B.Cu")
		(remove_unused_layers yes)
		(keep_end_layers yes)
		(free yes)
		(zone_layer_connections "In1.Cu" "In3.Cu" "In6.Cu" "In8.Cu")
		(net 1)
	)
	(via
		(at 203.7 134.9)
		(size 0.45)
		(drill 0.1)
		(layers "F.Cu" "B.Cu")
		(net 1)
	)
	(via
		(at 133.430532 84.15)
		(size 0.45)
		(drill 0.1)
		(layers "F.Cu" "B.Cu")
		(net 1)
	)
	(via
		(at 115.530532 78.15)
		(size 0.45)
		(drill 0.1)
		(layers "F.Cu" "B.Cu")
		(net 1)
	)
	(via
		(at 174.2 91.045856)
		(size 0.45)
		(drill 0.1)
		(layers "F.Cu" "B.Cu")
		(remove_unused_layers yes)
		(keep_end_layers yes)
		(free yes)
		(zone_layer_connections "In1.Cu" "In3.Cu" "In6.Cu" "In8.Cu")
		(net 1)
	)
	(via
		(at 171.36 72.2)
		(size 0.45)
		(drill 0.1)
		(layers "F.Cu" "B.Cu")
		(remove_unused_layers yes)
		(keep_end_layers yes)
		(free yes)
		(zone_layer_connections "In1.Cu" "In3.Cu" "In6.Cu" "In8.Cu")
		(net 1)
	)
	(via
		(at 63.5 114.6)
		(size 0.45)
		(drill 0.1)
		(layers "F.Cu" "B.Cu")
		(net 1)
	)
	(via
		(at 60.6 104.7)
		(size 0.45)
		(drill 0.1)
		(layers "F.Cu" "B.Cu")
		(net 1)
	)
	(via
		(at 110.230532 81.15)
		(size 0.45)
		(drill 0.1)
		(layers "F.Cu" "B.Cu")
		(net 1)
	)
	(via
		(at 181.75 106.67)
		(size 0.45)
		(drill 0.1)
		(layers "F.Cu" "B.Cu")
		(remove_unused_layers yes)
		(keep_end_layers yes)
		(zone_layer_connections "In1.Cu" "In3.Cu" "In6.Cu" "In8.Cu")
		(net 1)
	)
	(via
		(at 229.92 99.9)
		(size 0.45)
		(drill 0.1)
		(layers "F.Cu" "B.Cu")
		(net 1)
	)
	(via
		(at 112.230532 73.65)
		(size 0.45)
		(drill 0.1)
		(layers "F.Cu" "B.Cu")
		(free yes)
		(net 1)
	)
	(via
		(at 184.04 126.67)
		(size 0.45)
		(drill 0.1)
		(layers "F.Cu" "B.Cu")
		(remove_unused_layers yes)
		(keep_end_layers yes)
		(zone_layer_connections "In1.Cu" "In3.Cu" "In6.Cu" "In8.Cu")
		(net 1)
	)
	(via
		(at 89.230532 72.15)
		(size 0.45)
		(drill 0.1)
		(layers "F.Cu" "B.Cu")
		(net 1)
	)
	(via
		(at 71.965532 111.965)
		(size 0.45)
		(drill 0.1)
		(layers "F.Cu" "B.Cu")
		(net 1)
	)
	(via
		(at 87.1 130.8)
		(size 0.45)
		(drill 0.1)
		(layers "F.Cu" "B.Cu")
		(net 1)
	)
	(via
		(at 196.2 125.3)
		(size 0.45)
		(drill 0.1)
		(layers "F.Cu" "B.Cu")
		(net 1)
	)
	(via
		(at 71.965532 80.215)
		(size 0.45)
		(drill 0.1)
		(layers "F.Cu" "B.Cu")
		(net 1)
	)
	(via
		(at 91.25 59.5)
		(size 0.45)
		(drill 0.1)
		(layers "F.Cu" "B.Cu")
		(net 1)
	)
	(via
		(at 229.97 115.2)
		(size 0.45)
		(drill 0.1)
		(layers "F.Cu" "B.Cu")
		(net 1)
	)
	(via
		(at 171.76 91.045856)
		(size 0.45)
		(drill 0.1)
		(layers "F.Cu" "B.Cu")
		(remove_unused_layers yes)
		(keep_end_layers yes)
		(free yes)
		(zone_layer_connections "In1.Cu" "In3.Cu" "In6.Cu" "In8.Cu")
		(net 1)
	)
	(via
		(at 112.749995 55.64)
		(size 0.45)
		(drill 0.1)
		(layers "F.Cu" "B.Cu")
		(net 1)
	)
	(via
		(at 79.585532 101.805)
		(size 0.45)
		(drill 0.1)
		(layers "F.Cu" "B.Cu")
		(net 1)
	)
	(via
		(at 97.75 138.25)
		(size 0.45)
		(drill 0.1)
		(layers "F.Cu" "B.Cu")
		(free yes)
		(net 1)
	)
	(via
		(at 142.4 127.4)
		(size 0.45)
		(drill 0.1)
		(layers "F.Cu" "B.Cu")
		(remove_unused_layers yes)
		(keep_end_layers yes)
		(zone_layer_connections "In1.Cu" "In3.Cu" "In6.Cu" "In8.Cu")
		(net 1)
	)
	(via
		(at 106.349999 55.25)
		(size 0.45)
		(drill 0.1)
		(layers "F.Cu" "B.Cu")
		(net 1)
	)
	(via
		(at 131.8 143.7)
		(size 0.45)
		(drill 0.1)
		(layers "F.Cu" "B.Cu")
		(net 1)
	)
	(via
		(at 172.35 144.96)
		(size 0.45)
		(drill 0.1)
		(layers "F.Cu" "B.Cu")
		(remove_unused_layers yes)
		(keep_end_layers yes)
		(free yes)
		(zone_layer_connections "In1.Cu" "In3.Cu" "In6.Cu" "In8.Cu")
		(net 1)
	)
	(via
		(at 63.6 112.9)
		(size 0.45)
		(drill 0.1)
		(layers "F.Cu" "B.Cu")
		(net 1)
	)
	(via
		(at 206.746 139.6)
		(size 0.45)
		(drill 0.1)
		(layers "F.Cu" "B.Cu")
		(net 1)
	)
	(via
		(at 211.25 54.575)
		(size 0.45)
		(drill 0.1)
		(layers "F.Cu" "B.Cu")
		(net 1)
	)
	(via
		(at 82.125532 85.295)
		(size 0.45)
		(drill 0.1)
		(layers "F.Cu" "B.Cu")
		(net 1)
	)
	(via
		(at 171.14 145.5)
		(size 0.45)
		(drill 0.1)
		(layers "F.Cu" "B.Cu")
		(remove_unused_layers yes)
		(keep_end_layers yes)
		(free yes)
		(zone_layer_connections "In1.Cu" "In3.Cu" "In6.Cu" "In8.Cu")
		(net 1)
	)
	(via
		(at 71 135.5)
		(size 0.45)
		(drill 0.1)
		(layers "F.Cu" "B.Cu")
		(free yes)
		(net 1)
	)
	(via
		(at 84.665532 80.215)
		(size 0.45)
		(drill 0.1)
		(layers "F.Cu" "B.Cu")
		(net 1)
	)
	(via
		(at 224.8 97.65)
		(size 0.45)
		(drill 0.1)
		(layers "F.Cu" "B.Cu")
		(net 1)
	)
	(via
		(at 110.010004 55.640001)
		(size 0.45)
		(drill 0.1)
		(layers "F.Cu" "B.Cu")
		(net 1)
	)
	(via
		(at 75.775532 99.265)
		(size 0.45)
		(drill 0.1)
		(layers "F.Cu" "B.Cu")
		(net 1)
	)
	(via
		(at 93.530532 79.65)
		(size 0.45)
		(drill 0.1)
		(layers "F.Cu" "B.Cu")
		(net 1)
	)
	(via
		(at 223.7 88.1)
		(size 0.45)
		(drill 0.1)
		(layers "F.Cu" "B.Cu")
		(net 1)
	)
	(via
		(at 229.77 125.9)
		(size 0.45)
		(drill 0.1)
		(layers "F.Cu" "B.Cu")
		(net 1)
	)
	(via
		(at 80.855532 84.025)
		(size 0.45)
		(drill 0.1)
		(layers "F.Cu" "B.Cu")
		(net 1)
	)
	(via
		(at 126.4 61.87)
		(size 0.45)
		(drill 0.1)
		(layers "F.Cu" "B.Cu")
		(net 1)
	)
	(via
		(at 111.530532 78.15)
		(size 0.45)
		(drill 0.1)
		(layers "F.Cu" "B.Cu")
		(net 1)
	)
	(via
		(at 92.95 94.75)
		(size 0.45)
		(drill 0.1)
		(layers "F.Cu" "B.Cu")
		(net 1)
	)
	(via
		(at 210.6 103.3)
		(size 0.45)
		(drill 0.1)
		(layers "F.Cu" "B.Cu")
		(net 1)
	)
	(via
		(at 213.6 129.6)
		(size 0.45)
		(drill 0.1)
		(layers "F.Cu" "B.Cu")
		(net 1)
	)
	(via
		(at 126.2 137.6)
		(size 0.45)
		(drill 0.1)
		(layers "F.Cu" "B.Cu")
		(net 1)
	)
	(via
		(at 211.85 74.35)
		(size 0.45)
		(drill 0.1)
		(layers "F.Cu" "B.Cu")
		(net 1)
	)
	(via
		(at 229.93 128.2)
		(size 0.45)
		(drill 0.1)
		(layers "F.Cu" "B.Cu")
		(net 1)
	)
	(via
		(at 60.6 81.4)
		(size 0.45)
		(drill 0.1)
		(layers "F.Cu" "B.Cu")
		(net 1)
	)
	(via
		(at 180.95 110.55)
		(size 0.45)
		(drill 0.1)
		(layers "F.Cu" "B.Cu")
		(remove_unused_layers yes)
		(keep_end_layers yes)
		(free yes)
		(zone_layer_connections "In1.Cu" "In3.Cu" "In6.Cu" "In8.Cu")
		(net 1)
	)
	(via
		(at 181.09 128.4)
		(size 0.45)
		(drill 0.1)
		(layers "F.Cu" "B.Cu")
		(remove_unused_layers yes)
		(keep_end_layers yes)
		(free yes)
		(zone_layer_connections "In1.Cu" "In3.Cu" "In6.Cu" "In8.Cu")
		(net 1)
	)
	(via
		(at 110.879997 55.640001)
		(size 0.45)
		(drill 0.1)
		(layers "F.Cu" "B.Cu")
		(net 1)
	)
	(via
		(at 174.79 145.52)
		(size 0.45)
		(drill 0.1)
		(layers "F.Cu" "B.Cu")
		(remove_unused_layers yes)
		(keep_end_layers yes)
		(free yes)
		(zone_layer_connections "In1.Cu" "In3.Cu" "In6.Cu" "In8.Cu")
		(net 1)
	)
	(via
		(at 86.8 105.5)
		(size 0.45)
		(drill 0.1)
		(layers "F.Cu" "B.Cu")
		(net 1)
	)
	(via
		(at 214.4 87.7)
		(size 0.45)
		(drill 0.1)
		(layers "F.Cu" "B.Cu")
		(net 1)
	)
	(via
		(at 60.6 130.500001)
		(size 0.45)
		(drill 0.1)
		(layers "F.Cu" "B.Cu")
		(free yes)
		(net 1)
	)
	(via
		(at 112.5 100.261)
		(size 0.45)
		(drill 0.1)
		(layers "F.Cu" "B.Cu")
		(net 1)
	)
	(via
		(at 150.5 106.85)
		(size 0.45)
		(drill 0.1)
		(layers "F.Cu" "B.Cu")
		(net 1)
	)
	(via
		(at 85.71 82.82)
		(size 0.45)
		(drill 0.1)
		(layers "F.Cu" "B.Cu")
		(net 1)
	)
	(via
		(at 60.6 150)
		(size 0.45)
		(drill 0.1)
		(layers "F.Cu" "B.Cu")
		(free yes)
		(net 1)
	)
	(via
		(at 137.4 104.2)
		(size 0.45)
		(drill 0.1)
		(layers "F.Cu" "B.Cu")
		(net 1)
	)
	(via
		(at 127.78 61.94)
		(size 0.45)
		(drill 0.1)
		(layers "F.Cu" "B.Cu")
		(net 1)
	)
	(via
		(at 95.25 57.5)
		(size 0.45)
		(drill 0.1)
		(layers "F.Cu" "B.Cu")
		(net 1)
	)
	(via
		(at 162.75 61)
		(size 0.45)
		(drill 0.1)
		(layers "F.Cu" "B.Cu")
		(net 1)
	)
	(via
		(at 179.5 71)
		(size 0.45)
		(drill 0.1)
		(layers "F.Cu" "B.Cu")
		(remove_unused_layers yes)
		(keep_end_layers yes)
		(free yes)
		(zone_layer_connections "In1.Cu" "In3.Cu" "In6.Cu" "In8.Cu")
		(net 1)
	)
	(via
		(at 151.3 114.8)
		(size 0.45)
		(drill 0.1)
		(layers "F.Cu" "B.Cu")
		(net 1)
	)
	(via
		(at 146.1 128.25)
		(size 0.45)
		(drill 0.1)
		(layers "F.Cu" "B.Cu")
		(remove_unused_layers yes)
		(keep_end_layers yes)
		(zone_layer_connections "In1.Cu" "In3.Cu" "In6.Cu" "In8.Cu")
		(net 1)
	)
	(via
		(at 208 94)
		(size 0.45)
		(drill 0.1)
		(layers "F.Cu" "B.Cu")
		(net 1)
	)
	(via
		(at 60.6 151.5)
		(size 0.45)
		(drill 0.1)
		(layers "F.Cu" "B.Cu")
		(free yes)
		(net 1)
	)
	(via
		(at 74.505532 108.155)
		(size 0.45)
		(drill 0.1)
		(layers "F.Cu" "B.Cu")
		(net 1)
	)
	(via
		(at 97.75 142.5)
		(size 0.45)
		(drill 0.1)
		(layers "F.Cu" "B.Cu")
		(free yes)
		(net 1)
	)
	(via
		(at 222.45 86.55)
		(size 0.45)
		(drill 0.1)
		(layers "F.Cu" "B.Cu")
		(net 1)
	)
	(via
		(at 126.930532 76.65)
		(size 0.45)
		(drill 0.1)
		(layers "F.Cu" "B.Cu")
		(net 1)
	)
	(via
		(at 77.045532 111.965)
		(size 0.45)
		(drill 0.1)
		(layers "F.Cu" "B.Cu")
		(net 1)
	)
	(via
		(at 65.6 101.5)
		(size 0.45)
		(drill 0.1)
		(layers "F.Cu" "B.Cu")
		(net 1)
	)
	(via
		(at 135.030532 79.65)
		(size 0.45)
		(drill 0.1)
		(layers "F.Cu" "B.Cu")
		(net 1)
	)
	(via
		(at 178.75 91.05)
		(size 0.45)
		(drill 0.1)
		(layers "F.Cu" "B.Cu")
		(remove_unused_layers yes)
		(keep_end_layers yes)
		(free yes)
		(zone_layer_connections "In1.Cu" "In3.Cu" "In6.Cu" "In8.Cu")
		(net 1)
	)
	(via
		(at 100.24 79.64)
		(size 0.45)
		(drill 0.1)
		(layers "F.Cu" "B.Cu")
		(net 1)
	)
	(via
		(at 174.79 93)
		(size 0.45)
		(drill 0.1)
		(layers "F.Cu" "B.Cu")
		(remove_unused_layers yes)
		(keep_end_layers yes)
		(free yes)
		(zone_layer_connections "In1.Cu" "In3.Cu" "In6.Cu" "In8.Cu")
		(net 1)
	)
	(via
		(at 98.230532 75.15)
		(size 0.45)
		(drill 0.1)
		(layers "F.Cu" "B.Cu")
		(net 1)
	)
	(via
		(at 108.230532 73.65)
		(size 0.45)
		(drill 0.1)
		(layers "F.Cu" "B.Cu")
		(net 1)
	)
	(via
		(at 179.55 89.65)
		(size 0.45)
		(drill 0.1)
		(layers "F.Cu" "B.Cu")
		(remove_unused_layers yes)
		(keep_end_layers yes)
		(free yes)
		(zone_layer_connections "In1.Cu" "In3.Cu" "In6.Cu" "In8.Cu")
		(net 1)
	)
	(via
		(at 77.045532 115.775)
		(size 0.45)
		(drill 0.1)
		(layers "F.Cu" "B.Cu")
		(net 1)
	)
	(via
		(at 109.86 65.13)
		(size 0.45)
		(drill 0.1)
		(layers "F.Cu" "B.Cu")
		(net 1)
	)
	(via
		(at 83.395532 103.075)
		(size 0.45)
		(drill 0.1)
		(layers "F.Cu" "B.Cu")
		(net 1)
	)
	(via
		(at 188.25 126.6)
		(size 0.45)
		(drill 0.1)
		(layers "F.Cu" "B.Cu")
		(remove_unused_layers yes)
		(keep_end_layers yes)
		(zone_layer_connections "In1.Cu" "In3.Cu" "In6.Cu" "In8.Cu")
		(net 1)
	)
	(via
		(at 60.6 136.5)
		(size 0.45)
		(drill 0.1)
		(layers "F.Cu" "B.Cu")
		(free yes)
		(net 1)
	)
	(via
		(at 89.230532 84.15)
		(size 0.45)
		(drill 0.1)
		(layers "F.Cu" "B.Cu")
		(net 1)
	)
	(via
		(at 75.775532 84.025)
		(size 0.45)
		(drill 0.1)
		(layers "F.Cu" "B.Cu")
		(net 1)
	)
	(via
		(at 71.965532 108.155)
		(size 0.45)
		(drill 0.1)
		(layers "F.Cu" "B.Cu")
		(net 1)
	)
	(via
		(at 225 109.3)
		(size 0.45)
		(drill 0.1)
		(layers "F.Cu" "B.Cu")
		(net 1)
	)
	(via
		(at 236.9 122)
		(size 0.45)
		(drill 0.1)
		(layers "F.Cu" "B.Cu")
		(net 1)
	)
	(via
		(at 230.62 92.55)
		(size 0.45)
		(drill 0.1)
		(layers "F.Cu" "B.Cu")
		(net 1)
	)
	(via
		(at 73.235532 118.315)
		(size 0.45)
		(drill 0.1)
		(layers "F.Cu" "B.Cu")
		(net 1)
	)
	(via
		(at 124.569997 56.61)
		(size 0.45)
		(drill 0.1)
		(layers "F.Cu" "B.Cu")
		(net 1)
	)
	(via
		(at 83.395532 109.425)
		(size 0.45)
		(drill 0.1)
		(layers "F.Cu" "B.Cu")
		(net 1)
	)
	(via
		(at 165.35 72.25)
		(size 0.45)
		(drill 0.1)
		(layers "F.Cu" "B.Cu")
		(remove_unused_layers yes)
		(keep_end_layers yes)
		(free yes)
		(zone_layer_connections "In1.Cu" "In3.Cu" "In6.Cu" "In8.Cu")
		(net 1)
	)
	(via
		(at 75.775532 103.075)
		(size 0.45)
		(drill 0.1)
		(layers "F.Cu" "B.Cu")
		(net 1)
	)
	(via
		(at 191.8 127)
		(size 0.45)
		(drill 0.1)
		(layers "F.Cu" "B.Cu")
		(remove_unused_layers yes)
		(keep_end_layers yes)
		(zone_layer_connections "In1.Cu" "In3.Cu" "In6.Cu" "In8.Cu")
		(net 1)
	)
	(via
		(at 60.6 138)
		(size 0.45)
		(drill 0.1)
		(layers "F.Cu" "B.Cu")
		(free yes)
		(net 1)
	)
	(via
		(at 103.1 106.3)
		(size 0.45)
		(drill 0.1)
		(layers "F.Cu" "B.Cu")
		(net 1)
	)
	(via
		(at 236.9 123)
		(size 0.45)
		(drill 0.1)
		(layers "F.Cu" "B.Cu")
		(net 1)
	)
	(via
		(at 206.5 77.9)
		(size 0.45)
		(drill 0.1)
		(layers "F.Cu" "B.Cu")
		(net 1)
	)
	(via
		(at 74.505532 127.205)
		(size 0.45)
		(drill 0.1)
		(layers "F.Cu" "B.Cu")
		(net 1)
	)
	(via
		(at 113.5 114.75)
		(size 0.45)
		(drill 0.1)
		(layers "F.Cu" "B.Cu")
		(net 1)
	)
	(via
		(at 145.130532 81.15)
		(size 0.45)
		(drill 0.1)
		(layers "F.Cu" "B.Cu")
		(net 1)
	)
	(via
		(at 163.11 92.695856)
		(size 0.45)
		(drill 0.1)
		(layers "F.Cu" "B.Cu")
		(remove_unused_layers yes)
		(keep_end_layers yes)
		(free yes)
		(zone_layer_connections "In1.Cu" "In3.Cu" "In6.Cu" "In8.Cu")
		(net 1)
	)
	(via
		(at 80.855532 118.315)
		(size 0.45)
		(drill 0.1)
		(layers "F.Cu" "B.Cu")
		(net 1)
	)
	(via
		(at 71 148.5)
		(size 0.45)
		(drill 0.1)
		(layers "F.Cu" "B.Cu")
		(free yes)
		(net 1)
	)
	(via
		(at 129.630532 82.65)
		(size 0.45)
		(drill 0.1)
		(layers "F.Cu" "B.Cu")
		(net 1)
	)
	(via
		(at 73.235532 99.265)
		(size 0.45)
		(drill 0.1)
		(layers "F.Cu" "B.Cu")
		(net 1)
	)
	(via
		(at 97 142.5)
		(size 0.45)
		(drill 0.1)
		(layers "F.Cu" "B.Cu")
		(free yes)
		(net 1)
	)
	(via
		(at 82.125532 81.485)
		(size 0.45)
		(drill 0.1)
		(layers "F.Cu" "B.Cu")
		(net 1)
	)
	(via
		(at 236.9 108.6)
		(size 0.45)
		(drill 0.1)
		(layers "F.Cu" "B.Cu")
		(net 1)
	)
	(via
		(at 180.55 111.4)
		(size 0.45)
		(drill 0.1)
		(layers "F.Cu" "B.Cu")
		(remove_unused_layers yes)
		(keep_end_layers yes)
		(free yes)
		(zone_layer_connections "In1.Cu" "In3.Cu" "In6.Cu" "In8.Cu")
		(net 1)
	)
	(via
		(at 93.155 54.877)
		(size 0.45)
		(drill 0.1)
		(layers "F.Cu" "B.Cu")
		(net 1)
	)
	(via
		(at 132.330532 85.65)
		(size 0.45)
		(drill 0.1)
		(layers "F.Cu" "B.Cu")
		(net 1)
	)
	(via
		(at 178.95 71)
		(size 0.45)
		(drill 0.1)
		(layers "F.Cu" "B.Cu")
		(remove_unused_layers yes)
		(keep_end_layers yes)
		(free yes)
		(zone_layer_connections "In1.Cu" "In3.Cu" "In6.Cu" "In8.Cu")
		(net 1)
	)
	(via
		(at 118.230532 75.15)
		(size 0.45)
		(drill 0.1)
		(layers "F.Cu" "B.Cu")
		(net 1)
	)
	(via
		(at 196.202 54.602001)
		(size 0.45)
		(drill 0.1)
		(layers "F.Cu" "B.Cu")
		(net 1)
	)
	(via
		(at 60.6 145.5)
		(size 0.45)
		(drill 0.1)
		(layers "F.Cu" "B.Cu")
		(free yes)
		(net 1)
	)
	(via
		(at 175.55 80.95)
		(size 0.45)
		(drill 0.1)
		(layers "F.Cu" "B.Cu")
		(remove_unused_layers yes)
		(keep_end_layers yes)
		(free yes)
		(zone_layer_connections "In1.Cu" "In3.Cu" "In6.Cu" "In8.Cu")
		(net 1)
	)
	(via
		(at 84.665532 106.885)
		(size 0.45)
		(drill 0.1)
		(layers "F.Cu" "B.Cu")
		(net 1)
	)
	(via
		(at 84.1 66)
		(size 0.45)
		(drill 0.1)
		(layers "F.Cu" "B.Cu")
		(net 1)
	)
	(via
		(at 175.3 101.15)
		(size 0.45)
		(drill 0.1)
		(layers "F.Cu" "B.Cu")
		(remove_unused_layers yes)
		(keep_end_layers yes)
		(free yes)
		(zone_layer_connections "In1.Cu" "In3.Cu" "In6.Cu" "In8.Cu")
		(net 1)
	)
	(via
		(at 221.9 111.4)
		(size 0.45)
		(drill 0.1)
		(layers "F.Cu" "B.Cu")
		(net 1)
	)
	(via
		(at 229.92 104.45)
		(size 0.45)
		(drill 0.1)
		(layers "F.Cu" "B.Cu")
		(net 1)
	)
	(via
		(at 218.4 94.2)
		(size 0.45)
		(drill 0.1)
		(layers "F.Cu" "B.Cu")
		(net 1)
	)
	(via
		(at 212.325 82.4)
		(size 0.45)
		(drill 0.1)
		(layers "F.Cu" "B.Cu")
		(net 1)
	)
	(via
		(at 216.306 145.4)
		(size 0.45)
		(drill 0.1)
		(layers "F.Cu" "B.Cu")
		(net 1)
	)
	(via
		(at 106.230532 84.15)
		(size 0.45)
		(drill 0.1)
		(layers "F.Cu" "B.Cu")
		(net 1)
	)
	(via
		(at 114.230532 72.15)
		(size 0.45)
		(drill 0.1)
		(layers "F.Cu" "B.Cu")
		(net 1)
	)
	(via
		(at 97.530532 73.65)
		(size 0.45)
		(drill 0.1)
		(layers "F.Cu" "B.Cu")
		(net 1)
	)
	(via
		(at 125.330532 72.15)
		(size 0.45)
		(drill 0.1)
		(layers "F.Cu" "B.Cu")
		(net 1)
	)
	(via
		(at 75.775532 106.885)
		(size 0.45)
		(drill 0.1)
		(layers "F.Cu" "B.Cu")
		(net 1)
	)
	(via
		(at 179.4 111.95)
		(size 0.45)
		(drill 0.1)
		(layers "F.Cu" "B.Cu")
		(remove_unused_layers yes)
		(keep_end_layers yes)
		(free yes)
		(zone_layer_connections "In1.Cu" "In3.Cu" "In6.Cu" "In8.Cu")
		(net 1)
	)
	(via
		(at 96.230532 85.65)
		(size 0.45)
		(drill 0.1)
		(layers "F.Cu" "B.Cu")
		(free yes)
		(net 1)
	)
	(via
		(at 129.630532 70.65)
		(size 0.45)
		(drill 0.1)
		(layers "F.Cu" "B.Cu")
		(net 1)
	)
	(via
		(at 69.425532 108.155)
		(size 0.45)
		(drill 0.1)
		(layers "F.Cu" "B.Cu")
		(net 1)
	)
	(via
		(at 175 71.05)
		(size 0.45)
		(drill 0.1)
		(layers "F.Cu" "B.Cu")
		(remove_unused_layers yes)
		(keep_end_layers yes)
		(free yes)
		(zone_layer_connections "In1.Cu" "In3.Cu" "In6.Cu" "In8.Cu")
		(net 1)
	)
	(via
		(at 109.009997 55.640001)
		(size 0.45)
		(drill 0.1)
		(layers "F.Cu" "B.Cu")
		(net 1)
	)
	(via
		(at 82.125532 106.885)
		(size 0.45)
		(drill 0.1)
		(layers "F.Cu" "B.Cu")
		(net 1)
	)
	(via
		(at 92.7 109.2)
		(size 0.45)
		(drill 0.1)
		(layers "F.Cu" "B.Cu")
		(net 1)
	)
	(via
		(at 128.930532 72.15)
		(size 0.45)
		(drill 0.1)
		(layers "F.Cu" "B.Cu")
		(net 1)
	)
	(via
		(at 62.9 110.5)
		(size 0.45)
		(drill 0.1)
		(layers "F.Cu" "B.Cu")
		(net 1)
	)
	(via
		(at 111.530532 72.15)
		(size 0.45)
		(drill 0.1)
		(layers "F.Cu" "B.Cu")
		(net 1)
	)
	(via
		(at 145.130532 75.15)
		(size 0.45)
		(drill 0.1)
		(layers "F.Cu" "B.Cu")
		(net 1)
	)
	(via
		(at 70.695532 115.775)
		(size 0.45)
		(drill 0.1)
		(layers "F.Cu" "B.Cu")
		(net 1)
	)
	(via
		(at 84.665532 90.375)
		(size 0.45)
		(drill 0.1)
		(layers "F.Cu" "B.Cu")
		(net 1)
	)
	(via
		(at 202.6 89.6)
		(size 0.45)
		(drill 0.1)
		(layers "F.Cu" "B.Cu")
		(net 1)
	)
	(via
		(at 223.35 131.55)
		(size 0.45)
		(drill 0.1)
		(layers "F.Cu" "B.Cu")
		(net 1)
	)
	(via
		(at 197.2 115)
		(size 0.45)
		(drill 0.1)
		(layers "F.Cu" "B.Cu")
		(free yes)
		(net 1)
	)
	(via
		(at 84.665532 115.775)
		(size 0.45)
		(drill 0.1)
		(layers "F.Cu" "B.Cu")
		(net 1)
	)
	(via
		(at 192.050993 64.552317)
		(size 0.45)
		(drill 0.1)
		(layers "F.Cu" "B.Cu")
		(net 1)
	)
	(via
		(at 85.3 130.9)
		(size 0.45)
		(drill 0.1)
		(layers "F.Cu" "B.Cu")
		(net 1)
	)
	(via
		(at 118.230532 81.15)
		(size 0.45)
		(drill 0.1)
		(layers "F.Cu" "B.Cu")
		(net 1)
	)
	(via
		(at 205.7 65)
		(size 0.45)
		(drill 0.1)
		(layers "F.Cu" "B.Cu")
		(net 1)
	)
	(via
		(at 93.530532 82.65)
		(size 0.45)
		(drill 0.1)
		(layers "F.Cu" "B.Cu")
		(net 1)
	)
	(via
		(at 215.2 105.6)
		(size 0.45)
		(drill 0.1)
		(layers "F.Cu" "B.Cu")
		(net 1)
	)
	(via
		(at 215.8 83.125)
		(size 0.45)
		(drill 0.1)
		(layers "F.Cu" "B.Cu")
		(net 1)
	)
	(via
		(at 131.4 144.8)
		(size 0.45)
		(drill 0.1)
		(layers "F.Cu" "B.Cu")
		(net 1)
	)
	(via
		(at 177.1 60.2)
		(size 0.45)
		(drill 0.1)
		(layers "F.Cu" "B.Cu")
		(net 1)
	)
	(via
		(at 224.65 89.25)
		(size 0.45)
		(drill 0.1)
		(layers "F.Cu" "B.Cu")
		(net 1)
	)
	(via
		(at 107.530532 84.15)
		(size 0.45)
		(drill 0.1)
		(layers "F.Cu" "B.Cu")
		(net 1)
	)
	(via
		(at 179.4 111.4)
		(size 0.45)
		(drill 0.1)
		(layers "F.Cu" "B.Cu")
		(remove_unused_layers yes)
		(keep_end_layers yes)
		(free yes)
		(zone_layer_connections "In1.Cu" "In3.Cu" "In6.Cu" "In8.Cu")
		(net 1)
	)
	(via
		(at 97.1 99.5)
		(size 0.45)
		(drill 0.1)
		(layers "F.Cu" "B.Cu")
		(net 1)
	)
	(via
		(at 113.530532 76.65)
		(size 0.45)
		(drill 0.1)
		(layers "F.Cu" "B.Cu")
		(net 1)
	)
	(via
		(at 182.764468 91.15)
		(size 0.45)
		(drill 0.1)
		(layers "F.Cu" "B.Cu")
		(remove_unused_layers yes)
		(keep_end_layers yes)
		(zone_layer_connections "In1.Cu" "In3.Cu" "In6.Cu" "In8.Cu")
		(net 1)
	)
	(via
		(at 121.530532 70.65)
		(size 0.45)
		(drill 0.1)
		(layers "F.Cu" "B.Cu")
		(net 1)
	)
	(via
		(at 205.7 66)
		(size 0.45)
		(drill 0.1)
		(layers "F.Cu" "B.Cu")
		(net 1)
	)
	(via
		(at 71 150)
		(size 0.45)
		(drill 0.1)
		(layers "F.Cu" "B.Cu")
		(free yes)
		(net 1)
	)
	(via
		(at 95.25 147)
		(size 0.45)
		(drill 0.1)
		(layers "F.Cu" "B.Cu")
		(free yes)
		(net 1)
	)
	(via
		(at 190.676 141.85)
		(size 0.45)
		(drill 0.1)
		(layers "F.Cu" "B.Cu")
		(free yes)
		(net 1)
	)
	(via
		(at 70.695532 117.045)
		(size 0.45)
		(drill 0.1)
		(layers "F.Cu" "B.Cu")
		(net 1)
	)
	(via
		(at 205.4 62.275)
		(size 0.45)
		(drill 0.1)
		(layers "F.Cu" "B.Cu")
		(net 1)
	)
	(via
		(at 97 144)
		(size 0.45)
		(drill 0.1)
		(layers "F.Cu" "B.Cu")
		(free yes)
		(net 1)
	)
	(via
		(at 123.55 78.14)
		(size 0.45)
		(drill 0.1)
		(layers "F.Cu" "B.Cu")
		(net 1)
	)
	(via
		(at 174.45 92.645856)
		(size 0.45)
		(drill 0.1)
		(layers "F.Cu" "B.Cu")
		(remove_unused_layers yes)
		(keep_end_layers yes)
		(free yes)
		(zone_layer_connections "In1.Cu" "In3.Cu" "In6.Cu" "In8.Cu")
		(net 1)
	)
	(via
		(at 106.26 81.15)
		(size 0.45)
		(drill 0.1)
		(layers "F.Cu" "B.Cu")
		(free yes)
		(net 1)
	)
	(via
		(at 207 75)
		(size 0.45)
		(drill 0.1)
		(layers "F.Cu" "B.Cu")
		(net 1)
	)
	(via
		(at 205.3 129.1)
		(size 0.45)
		(drill 0.1)
		(layers "F.Cu" "B.Cu")
		(net 1)
	)
	(via
		(at 197.2 108.4)
		(size 0.45)
		(drill 0.1)
		(layers "F.Cu" "B.Cu")
		(free yes)
		(net 1)
	)
	(via
		(at 85.935532 87.835)
		(size 0.45)
		(drill 0.1)
		(layers "F.Cu" "B.Cu")
		(net 1)
	)
	(via
		(at 134.8 66.6)
		(size 0.45)
		(drill 0.1)
		(layers "F.Cu" "B.Cu")
		(net 1)
	)
	(via
		(at 97.75 137.5)
		(size 0.45)
		(drill 0.1)
		(layers "F.Cu" "B.Cu")
		(free yes)
		(net 1)
	)
	(via
		(at 165.55 100.65)
		(size 0.45)
		(drill 0.1)
		(layers "F.Cu" "B.Cu")
		(remove_unused_layers yes)
		(keep_end_layers yes)
		(free yes)
		(zone_layer_connections "In1.Cu" "In3.Cu" "In6.Cu" "In8.Cu")
		(net 1)
	)
	(via
		(at 88.130532 82.65)
		(size 0.45)
		(drill 0.1)
		(layers "F.Cu" "B.Cu")
		(net 1)
	)
	(via
		(at 69.425532 123.395)
		(size 0.45)
		(drill 0.1)
		(layers "F.Cu" "B.Cu")
		(net 1)
	)
	(via
		(at 180.54 128.95)
		(size 0.45)
		(drill 0.1)
		(layers "F.Cu" "B.Cu")
		(remove_unused_layers yes)
		(keep_end_layers yes)
		(free yes)
		(zone_layer_connections "In1.Cu" "In3.Cu" "In6.Cu" "In8.Cu")
		(net 1)
	)
	(via
		(at 147.1 129)
		(size 0.45)
		(drill 0.1)
		(layers "F.Cu" "B.Cu")
		(remove_unused_layers yes)
		(keep_end_layers yes)
		(zone_layer_connections "In1.Cu" "In3.Cu" "In6.Cu" "In8.Cu")
		(net 1)
	)
	(via
		(at 124.230532 70.65)
		(size 0.45)
		(drill 0.1)
		(layers "F.Cu" "B.Cu")
		(net 1)
	)
	(via
		(at 166.2 67.2)
		(size 0.45)
		(drill 0.1)
		(layers "F.Cu" "B.Cu")
		(net 1)
	)
	(via
		(at 151.3 109.5)
		(size 0.45)
		(drill 0.1)
		(layers "F.Cu" "B.Cu")
		(net 1)
	)
	(via
		(at 77.045532 96.725)
		(size 0.45)
		(drill 0.1)
		(layers "F.Cu" "B.Cu")
		(net 1)
	)
	(via
		(at 97 147)
		(size 0.45)
		(drill 0.1)
		(layers "F.Cu" "B.Cu")
		(free yes)
		(net 1)
	)
	(via
		(at 125.330532 81.15)
		(size 0.45)
		(drill 0.1)
		(layers "F.Cu" "B.Cu")
		(net 1)
	)
	(via
		(at 130.730532 84.15)
		(size 0.45)
		(drill 0.1)
		(layers "F.Cu" "B.Cu")
		(net 1)
	)
	(via
		(at 62.7 100.5)
		(size 0.45)
		(drill 0.1)
		(layers "F.Cu" "B.Cu")
		(net 1)
	)
	(via
		(at 83.395532 114.505)
		(size 0.45)
		(drill 0.1)
		(layers "F.Cu" "B.Cu")
		(net 1)
	)
	(via
		(at 112.5 106.261)
		(size 0.45)
		(drill 0.1)
		(layers "F.Cu" "B.Cu")
		(net 1)
	)
	(via
		(at 197.146 139.8)
		(size 0.45)
		(drill 0.1)
		(layers "F.Cu" "B.Cu")
		(net 1)
	)
	(via
		(at 124.230532 73.65)
		(size 0.45)
		(drill 0.1)
		(layers "F.Cu" "B.Cu")
		(net 1)
	)
	(via
		(at 60.6 148.5)
		(size 0.45)
		(drill 0.1)
		(layers "F.Cu" "B.Cu")
		(free yes)
		(net 1)
	)
	(via
		(at 169.51 92.645856)
		(size 0.45)
		(drill 0.1)
		(layers "F.Cu" "B.Cu")
		(remove_unused_layers yes)
		(keep_end_layers yes)
		(free yes)
		(zone_layer_connections "In1.Cu" "In3.Cu" "In6.Cu" "In8.Cu")
		(net 1)
	)
	(via
		(at 60.6 63.2)
		(size 0.45)
		(drill 0.1)
		(layers "F.Cu" "B.Cu")
		(net 1)
	)
	(via
		(at 126.2 121.4)
		(size 0.45)
		(drill 0.1)
		(layers "F.Cu" "B.Cu")
		(net 1)
	)
	(via
		(at 173.03 70.52)
		(size 0.45)
		(drill 0.1)
		(layers "F.Cu" "B.Cu")
		(remove_unused_layers yes)
		(keep_end_layers yes)
		(free yes)
		(zone_layer_connections "In1.Cu" "In3.Cu" "In6.Cu" "In8.Cu")
		(net 1)
	)
	(via
		(at 114.230532 78.15)
		(size 0.45)
		(drill 0.1)
		(layers "F.Cu" "B.Cu")
		(net 1)
	)
	(via
		(at 79.585532 80.215)
		(size 0.45)
		(drill 0.1)
		(layers "F.Cu" "B.Cu")
		(net 1)
	)
	(via
		(at 228.97 113.2)
		(size 0.45)
		(drill 0.1)
		(layers "F.Cu" "B.Cu")
		(net 1)
	)
	(via
		(at 170.53 144.95)
		(size 0.45)
		(drill 0.1)
		(layers "F.Cu" "B.Cu")
		(remove_unused_layers yes)
		(keep_end_layers yes)
		(free yes)
		(zone_layer_connections "In1.Cu" "In3.Cu" "In6.Cu" "In8.Cu")
		(net 1)
	)
	(via
		(at 179.2 81.6)
		(size 0.45)
		(drill 0.1)
		(layers "F.Cu" "B.Cu")
		(net 1)
	)
	(via
		(at 98.230532 72.15)
		(size 0.45)
		(drill 0.1)
		(layers "F.Cu" "B.Cu")
		(net 1)
	)
	(via
		(at 222.4 89.6)
		(size 0.45)
		(drill 0.1)
		(layers "F.Cu" "B.Cu")
		(net 1)
	)
	(via
		(at 235.47 86.9)
		(size 0.45)
		(drill 0.1)
		(layers "F.Cu" "B.Cu")
		(net 1)
	)
	(via
		(at 65.6 108.96)
		(size 0.45)
		(drill 0.1)
		(layers "F.Cu" "B.Cu")
		(net 1)
	)
	(via
		(at 161.7 70.5)
		(size 0.45)
		(drill 0.1)
		(layers "F.Cu" "B.Cu")
		(net 1)
	)
	(via
		(at 92.275 110.575)
		(size 0.45)
		(drill 0.1)
		(layers "F.Cu" "B.Cu")
		(net 1)
	)
	(via
		(at 73.235532 84.025)
		(size 0.45)
		(drill 0.1)
		(layers "F.Cu" "B.Cu")
		(net 1)
	)
	(via
		(at 69.425532 128.475)
		(size 0.45)
		(drill 0.1)
		(layers "F.Cu" "B.Cu")
		(net 1)
	)
	(via
		(at 159.15 145.3)
		(size 0.45)
		(drill 0.1)
		(layers "F.Cu" "B.Cu")
		(net 1)
	)
	(via
		(at 236.95 109.85)
		(size 0.45)
		(drill 0.1)
		(layers "F.Cu" "B.Cu")
		(net 1)
	)
	(via
		(at 74.505532 104.345)
		(size 0.45)
		(drill 0.1)
		(layers "F.Cu" "B.Cu")
		(net 1)
	)
	(via
		(at 82.125532 117.045)
		(size 0.45)
		(drill 0.1)
		(layers "F.Cu" "B.Cu")
		(net 1)
	)
	(via
		(at 229.82 86.9)
		(size 0.45)
		(drill 0.1)
		(layers "F.Cu" "B.Cu")
		(net 1)
	)
	(via
		(at 209.976 147)
		(size 0.45)
		(drill 0.1)
		(layers "F.Cu" "B.Cu")
		(net 1)
	)
	(via
		(at 222.425 91.2)
		(size 0.45)
		(drill 0.1)
		(layers "F.Cu" "B.Cu")
		(net 1)
	)
	(via
		(at 181.69 128.4)
		(size 0.45)
		(drill 0.1)
		(layers "F.Cu" "B.Cu")
		(remove_unused_layers yes)
		(keep_end_layers yes)
		(free yes)
		(zone_layer_connections "In1.Cu" "In3.Cu" "In6.Cu" "In8.Cu")
		(net 1)
	)
	(via
		(at 102.230532 84.15)
		(size 0.45)
		(drill 0.1)
		(layers "F.Cu" "B.Cu")
		(net 1)
	)
	(via
		(at 71.25 57.25)
		(size 0.45)
		(drill 0.1)
		(layers "F.Cu" "B.Cu")
		(net 1)
	)
	(via
		(at 181 59.9)
		(size 0.45)
		(drill 0.1)
		(layers "F.Cu" "B.Cu")
		(net 1)
	)
	(via
		(at 190.1 66)
		(size 0.45)
		(drill 0.1)
		(layers "F.Cu" "B.Cu")
		(net 1)
	)
	(via
		(at 65.6 113.5)
		(size 0.45)
		(drill 0.1)
		(layers "F.Cu" "B.Cu")
		(net 1)
	)
	(via
		(at 211.1 117.5)
		(size 0.45)
		(drill 0.1)
		(layers "F.Cu" "B.Cu")
		(net 1)
	)
	(via
		(at 201.15 63.8)
		(size 0.45)
		(drill 0.1)
		(layers "F.Cu" "B.Cu")
		(net 1)
	)
	(via
		(at 82.125532 125.935)
		(size 0.45)
		(drill 0.1)
		(layers "F.Cu" "B.Cu")
		(net 1)
	)
	(via
		(at 161.86 92.695856)
		(size 0.45)
		(drill 0.1)
		(layers "F.Cu" "B.Cu")
		(remove_unused_layers yes)
		(keep_end_layers yes)
		(free yes)
		(zone_layer_connections "In1.Cu" "In3.Cu" "In6.Cu" "In8.Cu")
		(net 1)
	)
	(via
		(at 97.530532 85.65)
		(size 0.45)
		(drill 0.1)
		(layers "F.Cu" "B.Cu")
		(net 1)
	)
	(via
		(at 96 88.625)
		(size 0.45)
		(drill 0.1)
		(layers "F.Cu" "B.Cu")
		(net 1)
	)
	(via
		(at 60.6 139.5)
		(size 0.45)
		(drill 0.1)
		(layers "F.Cu" "B.Cu")
		(free yes)
		(net 1)
	)
	(via
		(at 162.2 93.05)
		(size 0.45)
		(drill 0.1)
		(layers "F.Cu" "B.Cu")
		(remove_unused_layers yes)
		(keep_end_layers yes)
		(free yes)
		(zone_layer_connections "In1.Cu" "In3.Cu" "In6.Cu" "In8.Cu")
		(net 1)
	)
	(via
		(at 63.8 117)
		(size 0.45)
		(drill 0.1)
		(layers "F.Cu" "B.Cu")
		(net 1)
	)
	(via
		(at 212.2 121.3)
		(size 0.45)
		(drill 0.1)
		(layers "F.Cu" "B.Cu")
		(net 1)
	)
	(via
		(at 196.55 132.9)
		(size 0.45)
		(drill 0.1)
		(layers "F.Cu" "B.Cu")
		(net 1)
	)
	(via
		(at 179.39 128.95)
		(size 0.45)
		(drill 0.1)
		(layers "F.Cu" "B.Cu")
		(remove_unused_layers yes)
		(keep_end_layers yes)
		(free yes)
		(zone_layer_connections "In1.Cu" "In3.Cu" "In6.Cu" "In8.Cu")
		(net 1)
	)
	(via
		(at 154.4 97.6)
		(size 0.45)
		(drill 0.1)
		(layers "F.Cu" "B.Cu")
		(net 1)
	)
	(via
		(at 142 55.2)
		(size 0.45)
		(drill 0.1)
		(layers "F.Cu" "B.Cu")
		(net 1)
	)
	(via
		(at 71 145.500001)
		(size 0.45)
		(drill 0.1)
		(layers "F.Cu" "B.Cu")
		(free yes)
		(net 1)
	)
	(via
		(at 85.935532 89.105)
		(size 0.45)
		(drill 0.1)
		(layers "F.Cu" "B.Cu")
		(net 1)
	)
	(via
		(at 207.25 135.95)
		(size 0.45)
		(drill 0.1)
		(layers "F.Cu" "B.Cu")
		(net 1)
	)
	(via
		(at 126.2 139)
		(size 0.45)
		(drill 0.1)
		(layers "F.Cu" "B.Cu")
		(net 1)
	)
	(via
		(at 126.15 97.85)
		(size 0.45)
		(drill 0.1)
		(layers "F.Cu" "B.Cu")
		(net 1)
	)
	(via
		(at 92.630532 73.65)
		(size 0.45)
		(drill 0.1)
		(layers "F.Cu" "B.Cu")
		(net 1)
	)
	(via
		(at 193.2 122.45)
		(size 0.45)
		(drill 0.1)
		(layers "F.Cu" "B.Cu")
		(remove_unused_layers yes)
		(keep_end_layers yes)
		(free yes)
		(zone_layer_connections "In1.Cu" "In3.Cu" "In6.Cu" "In8.Cu")
		(net 1)
	)
	(via
		(at 79.585532 94.185)
		(size 0.45)
		(drill 0.1)
		(layers "F.Cu" "B.Cu")
		(net 1)
	)
	(via
		(at 169.1 89.9)
		(size 0.45)
		(drill 0.1)
		(layers "F.Cu" "B.Cu")
		(remove_unused_layers yes)
		(keep_end_layers yes)
		(free yes)
		(zone_layer_connections "In1.Cu" "In3.Cu" "In6.Cu" "In8.Cu")
		(net 1)
	)
	(via
		(at 78.315532 99.265)
		(size 0.45)
		(drill 0.1)
		(layers "F.Cu" "B.Cu")
		(net 1)
	)
	(via
		(at 77.045532 89.105)
		(size 0.45)
		(drill 0.1)
		(layers "F.Cu" "B.Cu")
		(net 1)
	)
	(via
		(at 163.3 72.25)
		(size 0.45)
		(drill 0.1)
		(layers "F.Cu" "B.Cu")
		(remove_unused_layers yes)
		(keep_end_layers yes)
		(free yes)
		(zone_layer_connections "In1.Cu" "In3.Cu" "In6.Cu" "In8.Cu")
		(net 1)
	)
	(via
		(at 109.530532 76.65)
		(size 0.45)
		(drill 0.1)
		(layers "F.Cu" "B.Cu")
		(net 1)
	)
	(via
		(at 223.25 119.05)
		(size 0.45)
		(drill 0.1)
		(layers "F.Cu" "B.Cu")
		(net 1)
	)
	(via
		(at 199.126 143.9)
		(size 0.45)
		(drill 0.1)
		(layers "F.Cu" "B.Cu")
		(net 1)
	)
	(via
		(at 230.2 108.6)
		(size 0.45)
		(drill 0.1)
		(layers "F.Cu" "B.Cu")
		(net 1)
	)
	(via
		(at 235.47 89.2)
		(size 0.45)
		(drill 0.1)
		(layers "F.Cu" "B.Cu")
		(net 1)
	)
	(via
		(at 65.25 127)
		(size 0.45)
		(drill 0.1)
		(layers "F.Cu" "B.Cu")
		(free yes)
		(net 1)
	)
	(via
		(at 183.9675 141.6375)
		(size 0.45)
		(drill 0.1)
		(layers "F.Cu" "B.Cu")
		(remove_unused_layers yes)
		(keep_end_layers yes)
		(zone_layer_connections "In1.Cu" "In3.Cu" "In6.Cu" "In8.Cu")
		(net 1)
	)
	(via
		(at 73.235532 91.645)
		(size 0.45)
		(drill 0.1)
		(layers "F.Cu" "B.Cu")
		(net 1)
	)
	(via
		(at 191.1 70.4)
		(size 0.45)
		(drill 0.1)
		(layers "F.Cu" "B.Cu")
		(net 1)
	)
	(via
		(at 178.25 91.35)
		(size 0.45)
		(drill 0.1)
		(layers "F.Cu" "B.Cu")
		(remove_unused_layers yes)
		(keep_end_layers yes)
		(free yes)
		(zone_layer_connections "In1.Cu" "In3.Cu" "In6.Cu" "In8.Cu")
		(net 1)
	)
	(via
		(at 233.35 85.82)
		(size 0.45)
		(drill 0.1)
		(layers "F.Cu" "B.Cu")
		(net 1)
	)
	(via
		(at 126.300008 58.71)
		(size 0.45)
		(drill 0.1)
		(layers "F.Cu" "B.Cu")
		(net 1)
	)
	(via
		(at 201.8 54.598)
		(size 0.45)
		(drill 0.1)
		(layers "F.Cu" "B.Cu")
		(net 1)
	)
	(via
		(at 175.7 70.45)
		(size 0.45)
		(drill 0.1)
		(layers "F.Cu" "B.Cu")
		(remove_unused_layers yes)
		(keep_end_layers yes)
		(free yes)
		(zone_layer_connections "In1.Cu" "In3.Cu" "In6.Cu" "In8.Cu")
		(net 1)
	)
	(via
		(at 71.965532 100.535)
		(size 0.45)
		(drill 0.1)
		(layers "F.Cu" "B.Cu")
		(net 1)
	)
	(via
		(at 143.22 56.624999)
		(size 0.45)
		(drill 0.1)
		(layers "F.Cu" "B.Cu")
		(net 1)
	)
	(via
		(at 170.9 70.85)
		(size 0.45)
		(drill 0.1)
		(layers "F.Cu" "B.Cu")
		(remove_unused_layers yes)
		(keep_end_layers yes)
		(free yes)
		(zone_layer_connections "In1.Cu" "In3.Cu" "In6.Cu" "In8.Cu")
		(net 1)
	)
	(via
		(at 215.2 132.8)
		(size 0.45)
		(drill 0.1)
		(layers "F.Cu" "B.Cu")
		(net 1)
	)
	(via
		(at 69.425532 119.585)
		(size 0.45)
		(drill 0.1)
		(layers "F.Cu" "B.Cu")
		(net 1)
	)
	(via
		(at 78.315532 78.945)
		(size 0.45)
		(drill 0.1)
		(layers "F.Cu" "B.Cu")
		(net 1)
	)
	(via
		(at 71.965532 104.345)
		(size 0.45)
		(drill 0.1)
		(layers "F.Cu" "B.Cu")
		(net 1)
	)
	(via
		(at 69.425532 82.755)
		(size 0.45)
		(drill 0.1)
		(layers "F.Cu" "B.Cu")
		(net 1)
	)
	(via
		(at 120.230532 85.65)
		(size 0.45)
		(drill 0.1)
		(layers "F.Cu" "B.Cu")
		(free yes)
		(net 1)
	)
	(via
		(at 176.15 72.2)
		(size 0.45)
		(drill 0.1)
		(layers "F.Cu" "B.Cu")
		(remove_unused_layers yes)
		(keep_end_layers yes)
		(free yes)
		(zone_layer_connections "In1.Cu" "In3.Cu" "In6.Cu" "In8.Cu")
		(net 1)
	)
	(via
		(at 211 98.8)
		(size 0.45)
		(drill 0.1)
		(layers "F.Cu" "B.Cu")
		(net 1)
	)
	(via
		(at 85.935532 119.585)
		(size 0.45)
		(drill 0.1)
		(layers "F.Cu" "B.Cu")
		(net 1)
	)
	(via
		(at 214.225 83.1)
		(size 0.45)
		(drill 0.1)
		(layers "F.Cu" "B.Cu")
		(net 1)
	)
	(via
		(at 126.2 115.8)
		(size 0.45)
		(drill 0.1)
		(layers "F.Cu" "B.Cu")
		(net 1)
	)
	(via
		(at 80.855532 119.585)
		(size 0.45)
		(drill 0.1)
		(layers "F.Cu" "B.Cu")
		(net 1)
	)
	(via
		(at 191.2 66.8)
		(size 0.45)
		(drill 0.1)
		(layers "F.Cu" "B.Cu")
		(net 1)
	)
	(via
		(at 83.395532 82.755)
		(size 0.45)
		(drill 0.1)
		(layers "F.Cu" "B.Cu")
		(net 1)
	)
	(via
		(at 179.6 91.1)
		(size 0.45)
		(drill 0.1)
		(layers "F.Cu" "B.Cu")
		(remove_unused_layers yes)
		(keep_end_layers yes)
		(free yes)
		(zone_layer_connections "In1.Cu" "In3.Cu" "In6.Cu" "In8.Cu")
		(net 1)
	)
	(via
		(at 230.35 125.1)
		(size 0.45)
		(drill 0.1)
		(layers "F.Cu" "B.Cu")
		(net 1)
	)
	(via
		(at 180 111.4)
		(size 0.45)
		(drill 0.1)
		(layers "F.Cu" "B.Cu")
		(remove_unused_layers yes)
		(keep_end_layers yes)
		(free yes)
		(zone_layer_connections "In1.Cu" "In3.Cu" "In6.Cu" "In8.Cu")
		(net 1)
	)
	(via
		(at 74.505532 96.725)
		(size 0.45)
		(drill 0.1)
		(layers "F.Cu" "B.Cu")
		(net 1)
	)
	(via
		(at 162.3 84.15)
		(size 0.45)
		(drill 0.1)
		(layers "F.Cu" "B.Cu")
		(remove_unused_layers yes)
		(keep_end_layers yes)
		(zone_layer_connections "In1.Cu" "In3.Cu" "In6.Cu" "In8.Cu")
		(net 1)
	)
	(via
		(at 105.530532 79.65)
		(size 0.45)
		(drill 0.1)
		(layers "F.Cu" "B.Cu")
		(net 1)
	)
	(via
		(at 165.634 65.25)
		(size 0.45)
		(drill 0.1)
		(layers "F.Cu" "B.Cu")
		(net 1)
	)
	(via
		(at 113.530532 70.65)
		(size 0.45)
		(drill 0.1)
		(layers "F.Cu" "B.Cu")
		(net 1)
	)
	(via
		(at 220.5 94.4)
		(size 0.45)
		(drill 0.1)
		(layers "F.Cu" "B.Cu")
		(net 1)
	)
	(via
		(at 88.130532 79.65)
		(size 0.45)
		(drill 0.1)
		(layers "F.Cu" "B.Cu")
		(net 1)
	)
	(via
		(at 79.585532 127.205)
		(size 0.45)
		(drill 0.1)
		(layers "F.Cu" "B.Cu")
		(net 1)
	)
	(via
		(at 221.212 55.3)
		(size 0.45)
		(drill 0.1)
		(layers "F.Cu" "B.Cu")
		(net 1)
	)
	(via
		(at 236.87 77.5)
		(size 0.45)
		(drill 0.1)
		(layers "F.Cu" "B.Cu")
		(net 1)
	)
	(via
		(at 190.7 55.6)
		(size 0.45)
		(drill 0.1)
		(layers "F.Cu" "B.Cu")
		(net 1)
	)
	(via
		(at 119.530532 75.15)
		(size 0.45)
		(drill 0.1)
		(layers "F.Cu" "B.Cu")
		(net 1)
	)
	(via
		(at 156.89 144.95)
		(size 0.45)
		(drill 0.1)
		(layers "F.Cu" "B.Cu")
		(net 1)
	)
	(via
		(at 139.4 103.4)
		(size 0.45)
		(drill 0.1)
		(layers "F.Cu" "B.Cu")
		(net 1)
	)
	(via
		(at 61.7 103.7)
		(size 0.45)
		(drill 0.1)
		(layers "F.Cu" "B.Cu")
		(net 1)
	)
	(via
		(at 97.75 145.5)
		(size 0.45)
		(drill 0.1)
		(layers "F.Cu" "B.Cu")
		(free yes)
		(net 1)
	)
	(via
		(at 74.505532 81.485)
		(size 0.45)
		(drill 0.1)
		(layers "F.Cu" "B.Cu")
		(net 1)
	)
	(via
		(at 82.125532 95.455)
		(size 0.45)
		(drill 0.1)
		(layers "F.Cu" "B.Cu")
		(net 1)
	)
	(via
		(at 128.030532 84.15)
		(size 0.45)
		(drill 0.1)
		(layers "F.Cu" "B.Cu")
		(net 1)
	)
	(via
		(at 89.2 123.3)
		(size 0.45)
		(drill 0.1)
		(layers "F.Cu" "B.Cu")
		(net 1)
	)
	(via
		(at 207.35 129.35)
		(size 0.45)
		(drill 0.1)
		(layers "F.Cu" "B.Cu")
		(net 1)
	)
	(via
		(at 164.35 101.15)
		(size 0.45)
		(drill 0.1)
		(layers "F.Cu" "B.Cu")
		(remove_unused_layers yes)
		(keep_end_layers yes)
		(free yes)
		(zone_layer_connections "In1.Cu" "In3.Cu" "In6.Cu" "In8.Cu")
		(net 1)
	)
	(via
		(at 71 142.5)
		(size 0.45)
		(drill 0.1)
		(layers "F.Cu" "B.Cu")
		(free yes)
		(net 1)
	)
	(via
		(at 69.425532 113.235)
		(size 0.45)
		(drill 0.1)
		(layers "F.Cu" "B.Cu")
		(net 1)
	)
	(via
		(at 83.395532 108.155)
		(size 0.45)
		(drill 0.1)
		(layers "F.Cu" "B.Cu")
		(net 1)
	)
	(via
		(at 112.5 135.75)
		(size 0.45)
		(drill 0.1)
		(layers "F.Cu" "B.Cu")
		(net 1)
	)
	(via
		(at 215.506 152.2)
		(size 0.45)
		(drill 0.1)
		(layers "F.Cu" "B.Cu")
		(net 1)
	)
	(via
		(at 117.530532 82.65)
		(size 0.45)
		(drill 0.1)
		(layers "F.Cu" "B.Cu")
		(net 1)
	)
	(via
		(at 169.85 93)
		(size 0.45)
		(drill 0.1)
		(layers "F.Cu" "B.Cu")
		(remove_unused_layers yes)
		(keep_end_layers yes)
		(free yes)
		(zone_layer_connections "In1.Cu" "In3.Cu" "In6.Cu" "In8.Cu")
		(net 1)
	)
	(via
		(at 171.96 92.645856)
		(size 0.45)
		(drill 0.1)
		(layers "F.Cu" "B.Cu")
		(remove_unused_layers yes)
		(keep_end_layers yes)
		(free yes)
		(zone_layer_connections "In1.Cu" "In3.Cu" "In6.Cu" "In8.Cu")
		(net 1)
	)
	(via
		(at 163.75 100.65)
		(size 0.45)
		(drill 0.1)
		(layers "F.Cu" "B.Cu")
		(remove_unused_layers yes)
		(keep_end_layers yes)
		(free yes)
		(zone_layer_connections "In1.Cu" "In3.Cu" "In6.Cu" "In8.Cu")
		(net 1)
	)
	(via
		(at 169.6 150.4)
		(size 0.45)
		(drill 0.1)
		(layers "F.Cu" "B.Cu")
		(remove_unused_layers yes)
		(keep_end_layers yes)
		(zone_layer_connections "In1.Cu" "In3.Cu" "In6.Cu" "In8.Cu")
		(net 1)
	)
	(via
		(at 93.530532 85.65)
		(size 0.45)
		(drill 0.1)
		(layers "F.Cu" "B.Cu")
		(net 1)
	)
	(via
		(at 203.2 89.85)
		(size 0.45)
		(drill 0.1)
		(layers "F.Cu" "B.Cu")
		(net 1)
	)
	(via
		(at 97.530532 82.65)
		(size 0.45)
		(drill 0.1)
		(layers "F.Cu" "B.Cu")
		(net 1)
	)
	(via
		(at 182.04 127.55)
		(size 0.45)
		(drill 0.1)
		(layers "F.Cu" "B.Cu")
		(remove_unused_layers yes)
		(keep_end_layers yes)
		(free yes)
		(zone_layer_connections "In1.Cu" "In3.Cu" "In6.Cu" "In8.Cu")
		(net 1)
	)
	(via
		(at 201.5 59.7)
		(size 0.45)
		(drill 0.1)
		(layers "F.Cu" "B.Cu")
		(net 1)
	)
	(via
		(at 176.86 92.645856)
		(size 0.45)
		(drill 0.1)
		(layers "F.Cu" "B.Cu")
		(remove_unused_layers yes)
		(keep_end_layers yes)
		(free yes)
		(zone_layer_connections "In1.Cu" "In3.Cu" "In6.Cu" "In8.Cu")
		(net 1)
	)
	(via
		(at 92.830532 72.15)
		(size 0.45)
		(drill 0.1)
		(layers "F.Cu" "B.Cu")
		(net 1)
	)
	(via
		(at 112.5 112.5)
		(size 0.45)
		(drill 0.1)
		(layers "F.Cu" "B.Cu")
		(net 1)
	)
	(via
		(at 193.2 122.95)
		(size 0.45)
		(drill 0.1)
		(layers "F.Cu" "B.Cu")
		(remove_unused_layers yes)
		(keep_end_layers yes)
		(free yes)
		(zone_layer_connections "In1.Cu" "In3.Cu" "In6.Cu" "In8.Cu")
		(net 1)
	)
	(via
		(at 208 75)
		(size 0.45)
		(drill 0.1)
		(layers "F.Cu" "B.Cu")
		(net 1)
	)
	(via
		(at 214.9 97)
		(size 0.45)
		(drill 0.1)
		(layers "F.Cu" "B.Cu")
		(net 1)
	)
	(via
		(at 74.505532 111.965)
		(size 0.45)
		(drill 0.1)
		(layers "F.Cu" "B.Cu")
		(net 1)
	)
	(via
		(at 75.775532 118.315)
		(size 0.45)
		(drill 0.1)
		(layers "F.Cu" "B.Cu")
		(net 1)
	)
	(via
		(at 112.230532 76.65)
		(size 0.45)
		(drill 0.1)
		(layers "F.Cu" "B.Cu")
		(net 1)
	)
	(via
		(at 229.946 152.025)
		(size 0.45)
		(drill 0.1)
		(layers "F.Cu" "B.Cu")
		(net 1)
	)
	(via
		(at 115.530532 84.15)
		(size 0.45)
		(drill 0.1)
		(layers "F.Cu" "B.Cu")
		(net 1)
	)
	(via
		(at 235.57 117.4)
		(size 0.45)
		(drill 0.1)
		(layers "F.Cu" "B.Cu")
		(net 1)
	)
	(via
		(at 160.79 73.56)
		(size 0.45)
		(drill 0.1)
		(layers "F.Cu" "B.Cu")
		(net 1)
	)
	(via
		(at 204.75 134.95)
		(size 0.45)
		(drill 0.1)
		(layers "F.Cu" "B.Cu")
		(net 1)
	)
	(via
		(at 224.05 99.25)
		(size 0.45)
		(drill 0.1)
		(layers "F.Cu" "B.Cu")
		(net 1)
	)
	(via
		(at 91.930532 75.15)
		(size 0.45)
		(drill 0.1)
		(layers "F.Cu" "B.Cu")
		(net 1)
	)
	(via
		(at 70.695532 105.615)
		(size 0.45)
		(drill 0.1)
		(layers "F.Cu" "B.Cu")
		(net 1)
	)
	(via
		(at 183.23 138.49)
		(size 0.45)
		(drill 0.1)
		(layers "F.Cu" "B.Cu")
		(remove_unused_layers yes)
		(keep_end_layers yes)
		(zone_layer_connections "In1.Cu" "In3.Cu" "In6.Cu" "In8.Cu")
		(net 1)
	)
	(via
		(at 98.5 141.75)
		(size 0.45)
		(drill 0.1)
		(layers "F.Cu" "B.Cu")
		(free yes)
		(net 1)
	)
	(via
		(at 82.125532 127.205)
		(size 0.45)
		(drill 0.1)
		(layers "F.Cu" "B.Cu")
		(net 1)
	)
	(via
		(at 64.2 59.4)
		(size 0.45)
		(drill 0.1)
		(layers "F.Cu" "B.Cu")
		(net 1)
	)
	(via
		(at 181.1 111.4)
		(size 0.45)
		(drill 0.1)
		(layers "F.Cu" "B.Cu")
		(remove_unused_layers yes)
		(keep_end_layers yes)
		(free yes)
		(zone_layer_connections "In1.Cu" "In3.Cu" "In6.Cu" "In8.Cu")
		(net 1)
	)
	(via
		(at 126.2 114.6)
		(size 0.45)
		(drill 0.1)
		(layers "F.Cu" "B.Cu")
		(net 1)
	)
	(via
		(at 79.585532 85.295)
		(size 0.45)
		(drill 0.1)
		(layers "F.Cu" "B.Cu")
		(net 1)
	)
	(via
		(at 234.809468 62.975)
		(size 0.45)
		(drill 0.1)
		(layers "F.Cu" "B.Cu")
		(net 1)
	)
	(via
		(at 99.530532 75.15)
		(size 0.45)
		(drill 0.1)
		(layers "F.Cu" "B.Cu")
		(net 1)
	)
	(via
		(at 73.8 142.8)
		(size 0.45)
		(drill 0.1)
		(layers "F.Cu" "B.Cu")
		(net 1)
	)
	(via
		(at 174.7 100.65)
		(size 0.45)
		(drill 0.1)
		(layers "F.Cu" "B.Cu")
		(remove_unused_layers yes)
		(keep_end_layers yes)
		(free yes)
		(zone_layer_connections "In1.Cu" "In3.Cu" "In6.Cu" "In8.Cu")
		(net 1)
	)
	(via
		(at 83.395532 124.665)
		(size 0.45)
		(drill 0.1)
		(layers "F.Cu" "B.Cu")
		(net 1)
	)
	(via
		(at 107.530532 81.15)
		(size 0.45)
		(drill 0.1)
		(layers "F.Cu" "B.Cu")
		(net 1)
	)
	(via
		(at 177.935 128.186)
		(size 0.45)
		(drill 0.1)
		(layers "F.Cu" "B.Cu")
		(remove_unused_layers yes)
		(keep_end_layers yes)
		(free yes)
		(zone_layer_connections "In1.Cu" "In3.Cu" "In6.Cu" "In8.Cu")
		(net 1)
	)
	(via
		(at 222.7 127.1)
		(size 0.45)
		(drill 0.1)
		(layers "F.Cu" "B.Cu")
		(net 1)
	)
	(via
		(at 97 138.25)
		(size 0.45)
		(drill 0.1)
		(layers "F.Cu" "B.Cu")
		(free yes)
		(net 1)
	)
	(via
		(at 87.75 87.9)
		(size 0.45)
		(drill 0.1)
		(layers "F.Cu" "B.Cu")
		(net 1)
	)
	(via
		(at 153.8 116.1)
		(size 0.45)
		(drill 0.1)
		(layers "F.Cu" "B.Cu")
		(net 1)
	)
	(via
		(at 150 55.2)
		(size 0.45)
		(drill 0.1)
		(layers "F.Cu" "B.Cu")
		(net 1)
	)
	(via
		(at 75.775532 78.945)
		(size 0.45)
		(drill 0.1)
		(layers "F.Cu" "B.Cu")
		(net 1)
	)
	(via
		(at 176.45 111.75)
		(size 0.45)
		(drill 0.1)
		(layers "F.Cu" "B.Cu")
		(remove_unused_layers yes)
		(keep_end_layers yes)
		(free yes)
		(zone_layer_connections "In1.Cu" "In3.Cu" "In6.Cu" "In8.Cu")
		(net 1)
	)
	(via
		(at 170.85 91.4)
		(size 0.45)
		(drill 0.1)
		(layers "F.Cu" "B.Cu")
		(remove_unused_layers yes)
		(keep_end_layers yes)
		(free yes)
		(zone_layer_connections "In1.Cu" "In3.Cu" "In6.Cu" "In8.Cu")
		(net 1)
	)
	(via
		(at 63 62.8)
		(size 0.45)
		(drill 0.1)
		(layers "F.Cu" "B.Cu")
		(net 1)
	)
	(via
		(at 84.665532 122.125)
		(size 0.45)
		(drill 0.1)
		(layers "F.Cu" "B.Cu")
		(net 1)
	)
	(via
		(at 69.425532 124.665)
		(size 0.45)
		(drill 0.1)
		(layers "F.Cu" "B.Cu")
		(net 1)
	)
	(via
		(at 145.130532 72.15)
		(size 0.45)
		(drill 0.1)
		(layers "F.Cu" "B.Cu")
		(net 1)
	)
	(via
		(at 98.5 143.25)
		(size 0.45)
		(drill 0.1)
		(layers "F.Cu" "B.Cu")
		(free yes)
		(net 1)
	)
	(via
		(at 163.47 93.1)
		(size 0.45)
		(drill 0.1)
		(layers "F.Cu" "B.Cu")
		(remove_unused_layers yes)
		(keep_end_layers yes)
		(free yes)
		(zone_layer_connections "In1.Cu" "In3.Cu" "In6.Cu" "In8.Cu")
		(net 1)
	)
	(via
		(at 102.230532 75.15)
		(size 0.45)
		(drill 0.1)
		(layers "F.Cu" "B.Cu")
		(net 1)
	)
	(via
		(at 196.2 89.8)
		(size 0.45)
		(drill 0.1)
		(layers "F.Cu" "B.Cu")
		(net 1)
	)
	(via
		(at 62.91 111.9)
		(size 0.45)
		(drill 0.1)
		(layers "F.Cu" "B.Cu")
		(net 1)
	)
	(via
		(at 121.530532 82.65)
		(size 0.45)
		(drill 0.1)
		(layers "F.Cu" "B.Cu")
		(net 1)
	)
	(via
		(at 181.7 111.4)
		(size 0.45)
		(drill 0.1)
		(layers "F.Cu" "B.Cu")
		(remove_unused_layers yes)
		(keep_end_layers yes)
		(free yes)
		(zone_layer_connections "In1.Cu" "In3.Cu" "In6.Cu" "In8.Cu")
		(net 1)
	)
	(via
		(at 113.530532 82.65)
		(size 0.45)
		(drill 0.1)
		(layers "F.Cu" "B.Cu")
		(net 1)
	)
	(via
		(at 163.4 64.6)
		(size 0.45)
		(drill 0.1)
		(layers "F.Cu" "B.Cu")
		(net 1)
	)
	(via
		(at 83.395532 89.105)
		(size 0.45)
		(drill 0.1)
		(layers "F.Cu" "B.Cu")
		(net 1)
	)
	(via
		(at 115.7 99)
		(size 0.45)
		(drill 0.1)
		(layers "F.Cu" "B.Cu")
		(net 1)
	)
	(via
		(at 101.75 62.5)
		(size 0.45)
		(drill 0.1)
		(layers "F.Cu" "B.Cu")
		(net 1)
	)
	(via
		(at 82.125532 91.645)
		(size 0.45)
		(drill 0.1)
		(layers "F.Cu" "B.Cu")
		(net 1)
	)
	(via
		(at 132.330532 82.65)
		(size 0.45)
		(drill 0.1)
		(layers "F.Cu" "B.Cu")
		(net 1)
	)
	(via
		(at 139.730532 78.15)
		(size 0.45)
		(drill 0.1)
		(layers "F.Cu" "B.Cu")
		(net 1)
	)
	(via
		(at 171.26 89.545856)
		(size 0.45)
		(drill 0.1)
		(layers "F.Cu" "B.Cu")
		(remove_unused_layers yes)
		(keep_end_layers yes)
		(free yes)
		(zone_layer_connections "In1.Cu" "In3.Cu" "In6.Cu" "In8.Cu")
		(net 1)
	)
	(via
		(at 222.7 97.6)
		(size 0.45)
		(drill 0.1)
		(layers "F.Cu" "B.Cu")
		(net 1)
	)
	(via
		(at 200.226 146.75)
		(size 0.45)
		(drill 0.1)
		(layers "F.Cu" "B.Cu")
		(net 1)
	)
	(via
		(at 177.94 144.02)
		(size 0.45)
		(drill 0.1)
		(layers "F.Cu" "B.Cu")
		(remove_unused_layers yes)
		(keep_end_layers yes)
		(free yes)
		(zone_layer_connections "In1.Cu" "In3.Cu" "In6.Cu" "In8.Cu")
		(net 1)
	)
	(via
		(at 75.775532 114.505)
		(size 0.45)
		(drill 0.1)
		(layers "F.Cu" "B.Cu")
		(net 1)
	)
	(via
		(at 180.75 69.3)
		(size 0.45)
		(drill 0.1)
		(layers "F.Cu" "B.Cu")
		(remove_unused_layers yes)
		(keep_end_layers yes)
		(free yes)
		(zone_layer_connections "In1.Cu" "In3.Cu" "In6.Cu" "In8.Cu")
		(net 1)
	)
	(via
		(at 200.7 134.9)
		(size 0.45)
		(drill 0.1)
		(layers "F.Cu" "B.Cu")
		(net 1)
	)
	(via
		(at 191.126 143.4)
		(size 0.45)
		(drill 0.1)
		(layers "F.Cu" "B.Cu")
		(net 1)
	)
	(via
		(at 209.6 116.7)
		(size 0.45)
		(drill 0.1)
		(layers "F.Cu" "B.Cu")
		(net 1)
	)
	(via
		(at 143.2 55.975)
		(size 0.45)
		(drill 0.1)
		(layers "F.Cu" "B.Cu")
		(net 1)
	)
	(via
		(at 135.69 55.07)
		(size 0.45)
		(drill 0.1)
		(layers "F.Cu" "B.Cu")
		(net 1)
	)
	(via
		(at 229.4 121.6)
		(size 0.45)
		(drill 0.1)
		(layers "F.Cu" "B.Cu")
		(net 1)
	)
	(via
		(at 79.585532 86.565)
		(size 0.45)
		(drill 0.1)
		(layers "F.Cu" "B.Cu")
		(net 1)
	)
	(via
		(at 208.55 104.15)
		(size 0.45)
		(drill 0.1)
		(layers "F.Cu" "B.Cu")
		(net 1)
	)
	(via
		(at 132.330532 76.65)
		(size 0.45)
		(drill 0.1)
		(layers "F.Cu" "B.Cu")
		(net 1)
	)
	(via
		(at 129.630532 85.65)
		(size 0.45)
		(drill 0.1)
		(layers "F.Cu" "B.Cu")
		(net 1)
	)
	(via
		(at 222.3 131.6)
		(size 0.45)
		(drill 0.1)
		(layers "F.Cu" "B.Cu")
		(net 1)
	)
	(via
		(at 176.05 127.8)
		(size 0.45)
		(drill 0.1)
		(layers "F.Cu" "B.Cu")
		(remove_unused_layers yes)
		(keep_end_layers yes)
		(free yes)
		(zone_layer_connections "In1.Cu" "In3.Cu" "In6.Cu" "In8.Cu")
		(net 1)
	)
	(via
		(at 207.34 117.32)
		(size 0.45)
		(drill 0.1)
		(layers "F.Cu" "B.Cu")
		(net 1)
	)
	(via
		(at 119.530532 72.15)
		(size 0.45)
		(drill 0.1)
		(layers "F.Cu" "B.Cu")
		(net 1)
	)
	(via
		(at 173.8 72.25)
		(size 0.45)
		(drill 0.1)
		(layers "F.Cu" "B.Cu")
		(remove_unused_layers yes)
		(keep_end_layers yes)
		(free yes)
		(zone_layer_connections "In1.Cu" "In3.Cu" "In6.Cu" "In8.Cu")
		(net 1)
	)
	(via
		(at 162.8 149.35)
		(size 0.45)
		(drill 0.1)
		(layers "F.Cu" "B.Cu")
		(net 1)
	)
	(via
		(at 124.230532 82.65)
		(size 0.45)
		(drill 0.1)
		(layers "F.Cu" "B.Cu")
		(net 1)
	)
	(via
		(at 179.2 75.2)
		(size 0.45)
		(drill 0.1)
		(layers "F.Cu" "B.Cu")
		(net 1)
	)
	(via
		(at 110.230532 75.15)
		(size 0.45)
		(drill 0.1)
		(layers "F.Cu" "B.Cu")
		(net 1)
	)
	(via
		(at 122.230532 72.15)
		(size 0.45)
		(drill 0.1)
		(layers "F.Cu" "B.Cu")
		(net 1)
	)
	(via
		(at 198.2 85.3)
		(size 0.45)
		(drill 0.1)
		(layers "F.Cu" "B.Cu")
		(net 1)
	)
	(via
		(at 167.9 89.9)
		(size 0.45)
		(drill 0.1)
		(layers "F.Cu" "B.Cu")
		(remove_unused_layers yes)
		(keep_end_layers yes)
		(free yes)
		(zone_layer_connections "In1.Cu" "In3.Cu" "In6.Cu" "In8.Cu")
		(net 1)
	)
	(via
		(at 77.045532 81.485)
		(size 0.45)
		(drill 0.1)
		(layers "F.Cu" "B.Cu")
		(net 1)
	)
	(via
		(at 136.130532 81.15)
		(size 0.45)
		(drill 0.1)
		(layers "F.Cu" "B.Cu")
		(net 1)
	)
	(via
		(at 105.530532 82.65)
		(size 0.45)
		(drill 0.1)
		(layers "F.Cu" "B.Cu")
		(net 1)
	)
	(via
		(at 144.230532 78.15)
		(size 0.45)
		(drill 0.1)
		(layers "F.Cu" "B.Cu")
		(net 1)
	)
	(via
		(at 203.2 91.1)
		(size 0.45)
		(drill 0.1)
		(layers "F.Cu" "B.Cu")
		(net 1)
	)
	(via
		(at 70.695532 90.375)
		(size 0.45)
		(drill 0.1)
		(layers "F.Cu" "B.Cu")
		(net 1)
	)
	(via
		(at 205.55 136.25)
		(size 0.45)
		(drill 0.1)
		(layers "F.Cu" "B.Cu")
		(net 1)
	)
	(via
		(at 99.639949 116.489949)
		(size 0.45)
		(drill 0.1)
		(layers "F.Cu" "B.Cu")
		(net 1)
	)
	(via
		(at 223.35 133.05)
		(size 0.45)
		(drill 0.1)
		(layers "F.Cu" "B.Cu")
		(net 1)
	)
	(via
		(at 171.65 101.15)
		(size 0.45)
		(drill 0.1)
		(layers "F.Cu" "B.Cu")
		(remove_unused_layers yes)
		(keep_end_layers yes)
		(free yes)
		(zone_layer_connections "In1.Cu" "In3.Cu" "In6.Cu" "In8.Cu")
		(net 1)
	)
	(via
		(at 168.76 89.545856)
		(size 0.45)
		(drill 0.1)
		(layers "F.Cu" "B.Cu")
		(remove_unused_layers yes)
		(keep_end_layers yes)
		(free yes)
		(zone_layer_connections "In1.Cu" "In3.Cu" "In6.Cu" "In8.Cu")
		(net 1)
	)
	(via
		(at 71.965532 89.105)
		(size 0.45)
		(drill 0.1)
		(layers "F.Cu" "B.Cu")
		(net 1)
	)
	(via
		(at 179.99 128.95)
		(size 0.45)
		(drill 0.1)
		(layers "F.Cu" "B.Cu")
		(remove_unused_layers yes)
		(keep_end_layers yes)
		(free yes)
		(zone_layer_connections "In1.Cu" "In3.Cu" "In6.Cu" "In8.Cu")
		(net 1)
	)
	(via
		(at 124.230532 85.65)
		(size 0.45)
		(drill 0.1)
		(layers "F.Cu" "B.Cu")
		(net 1)
	)
	(via
		(at 231.4 79.2)
		(size 0.45)
		(drill 0.1)
		(layers "F.Cu" "B.Cu")
		(net 1)
	)
	(via
		(at 171.6 89.9)
		(size 0.45)
		(drill 0.1)
		(layers "F.Cu" "B.Cu")
		(remove_unused_layers yes)
		(keep_end_layers yes)
		(free yes)
		(zone_layer_connections "In1.Cu" "In3.Cu" "In6.Cu" "In8.Cu")
		(net 1)
	)
	(via
		(at 235.52 104.5)
		(size 0.45)
		(drill 0.1)
		(layers "F.Cu" "B.Cu")
		(net 1)
	)
	(via
		(at 228.97 100.9)
		(size 0.45)
		(drill 0.1)
		(layers "F.Cu" "B.Cu")
		(net 1)
	)
	(via
		(at 125.800004 58.71)
		(size 0.45)
		(drill 0.1)
		(layers "F.Cu" "B.Cu")
		(net 1)
	)
	(via
		(at 84.665532 95.455)
		(size 0.45)
		(drill 0.1)
		(layers "F.Cu" "B.Cu")
		(net 1)
	)
	(via
		(at 139.530532 79.65)
		(size 0.45)
		(drill 0.1)
		(layers "F.Cu" "B.Cu")
		(net 1)
	)
	(via
		(at 226.3 83)
		(size 0.45)
		(drill 0.1)
		(layers "F.Cu" "B.Cu")
		(net 1)
	)
	(via
		(at 60.6 129)
		(size 0.45)
		(drill 0.1)
		(layers "F.Cu" "B.Cu")
		(free yes)
		(net 1)
	)
	(via
		(at 182.05 110.55)
		(size 0.45)
		(drill 0.1)
		(layers "F.Cu" "B.Cu")
		(remove_unused_layers yes)
		(keep_end_layers yes)
		(free yes)
		(zone_layer_connections "In1.Cu" "In3.Cu" "In6.Cu" "In8.Cu")
		(net 1)
	)
	(via
		(at 78.315532 125.935)
		(size 0.45)
		(drill 0.1)
		(layers "F.Cu" "B.Cu")
		(net 1)
	)
	(via
		(at 115.530532 75.15)
		(size 0.45)
		(drill 0.1)
		(layers "F.Cu" "B.Cu")
		(net 1)
	)
	(via
		(at 189.376 141.85)
		(size 0.45)
		(drill 0.1)
		(layers "F.Cu" "B.Cu")
		(free yes)
		(net 1)
	)
	(via
		(at 97 137.5)
		(size 0.45)
		(drill 0.1)
		(layers "F.Cu" "B.Cu")
		(free yes)
		(net 1)
	)
	(via
		(at 229.87 91.6)
		(size 0.45)
		(drill 0.1)
		(layers "F.Cu" "B.Cu")
		(net 1)
	)
	(via
		(at 69.425532 118.315)
		(size 0.45)
		(drill 0.1)
		(layers "F.Cu" "B.Cu")
		(net 1)
	)
	(via
		(at 112.5 113.25)
		(size 0.45)
		(drill 0.1)
		(layers "F.Cu" "B.Cu")
		(net 1)
	)
	(via
		(at 225.5 76.2)
		(size 0.45)
		(drill 0.1)
		(layers "F.Cu" "B.Cu")
		(net 1)
	)
	(via
		(at 80.855532 94.185)
		(size 0.45)
		(drill 0.1)
		(layers "F.Cu" "B.Cu")
		(net 1)
	)
	(via
		(at 176.04 144.97)
		(size 0.45)
		(drill 0.1)
		(layers "F.Cu" "B.Cu")
		(remove_unused_layers yes)
		(keep_end_layers yes)
		(free yes)
		(zone_layer_connections "In1.Cu" "In3.Cu" "In6.Cu" "In8.Cu")
		(net 1)
	)
	(via
		(at 180 70.4)
		(size 0.45)
		(drill 0.1)
		(layers "F.Cu" "B.Cu")
		(remove_unused_layers yes)
		(keep_end_layers yes)
		(free yes)
		(zone_layer_connections "In1.Cu" "In3.Cu" "In6.Cu" "In8.Cu")
		(net 1)
	)
	(via
		(at 214.7 127.2)
		(size 0.45)
		(drill 0.1)
		(layers "F.Cu" "B.Cu")
		(net 1)
	)
	(via
		(at 167.56 89.545856)
		(size 0.45)
		(drill 0.1)
		(layers "F.Cu" "B.Cu")
		(remove_unused_layers yes)
		(keep_end_layers yes)
		(free yes)
		(zone_layer_connections "In1.Cu" "In3.Cu" "In6.Cu" "In8.Cu")
		(net 1)
	)
	(via
		(at 174.04 89.9)
		(size 0.45)
		(drill 0.1)
		(layers "F.Cu" "B.Cu")
		(remove_unused_layers yes)
		(keep_end_layers yes)
		(free yes)
		(zone_layer_connections "In1.Cu" "In3.Cu" "In6.Cu" "In8.Cu")
		(net 1)
	)
	(via
		(at 160.25 64.75)
		(size 0.45)
		(drill 0.1)
		(layers "F.Cu" "B.Cu")
		(net 1)
	)
	(via
		(at 184.04 128.57)
		(size 0.45)
		(drill 0.1)
		(layers "F.Cu" "B.Cu")
		(remove_unused_layers yes)
		(keep_end_layers yes)
		(zone_layer_connections "In1.Cu" "In3.Cu" "In6.Cu" "In8.Cu")
		(net 1)
	)
	(via
		(at 237.2 135)
		(size 0.45)
		(drill 0.1)
		(layers "F.Cu" "B.Cu")
		(net 1)
	)
	(via
		(at 112.5 134.25)
		(size 0.45)
		(drill 0.1)
		(layers "F.Cu" "B.Cu")
		(net 1)
	)
	(via
		(at 173.55 112.95)
		(size 0.45)
		(drill 0.1)
		(layers "F.Cu" "B.Cu")
		(remove_unused_layers yes)
		(keep_end_layers yes)
		(free yes)
		(zone_layer_connections "In1.Cu" "In3.Cu" "In6.Cu" "In8.Cu")
		(net 1)
	)
	(via
		(at 74.505532 119.585)
		(size 0.45)
		(drill 0.1)
		(layers "F.Cu" "B.Cu")
		(net 1)
	)
	(via
		(at 100.3 117.3)
		(size 0.45)
		(drill 0.1)
		(layers "F.Cu" "B.Cu")
		(net 1)
	)
	(via
		(at 103 65.25)
		(size 0.45)
		(drill 0.1)
		(layers "F.Cu" "B.Cu")
		(net 1)
	)
	(via
		(at 238.9 72.6)
		(size 0.45)
		(drill 0.1)
		(layers "F.Cu" "B.Cu")
		(net 1)
	)
	(via
		(at 191 85.3)
		(size 0.45)
		(drill 0.1)
		(layers "F.Cu" "B.Cu")
		(net 1)
	)
	(via
		(at 229.1 94.600001)
		(size 0.45)
		(drill 0.1)
		(layers "F.Cu" "B.Cu")
		(net 1)
	)
	(via
		(at 201.199 74.45)
		(size 0.45)
		(drill 0.1)
		(layers "F.Cu" "B.Cu")
		(net 1)
	)
	(via
		(at 228.97 126.4)
		(size 0.45)
		(drill 0.1)
		(layers "F.Cu" "B.Cu")
		(net 1)
	)
	(via
		(at 85.935532 104.345)
		(size 0.45)
		(drill 0.1)
		(layers "F.Cu" "B.Cu")
		(net 1)
	)
	(via
		(at 103.530532 81.15)
		(size 0.45)
		(drill 0.1)
		(layers "F.Cu" "B.Cu")
		(net 1)
	)
	(via
		(at 132.9 141.8)
		(size 0.45)
		(drill 0.1)
		(layers "F.Cu" "B.Cu")
		(net 1)
	)
	(via
		(at 109.530532 79.65)
		(size 0.45)
		(drill 0.1)
		(layers "F.Cu" "B.Cu")
		(net 1)
	)
	(via
		(at 60.6 91)
		(size 0.45)
		(drill 0.1)
		(layers "F.Cu" "B.Cu")
		(net 1)
	)
	(via
		(at 85.935532 109.425)
		(size 0.45)
		(drill 0.1)
		(layers "F.Cu" "B.Cu")
		(net 1)
	)
	(via
		(at 104.230532 79.65)
		(size 0.45)
		(drill 0.1)
		(layers "F.Cu" "B.Cu")
		(net 1)
	)
	(via
		(at 224.3 94.1)
		(size 0.45)
		(drill 0.1)
		(layers "F.Cu" "B.Cu")
		(net 1)
	)
	(via
		(at 99.1 126.4)
		(size 0.45)
		(drill 0.1)
		(layers "F.Cu" "B.Cu")
		(net 1)
	)
	(via
		(at 75.775532 82.755)
		(size 0.45)
		(drill 0.1)
		(layers "F.Cu" "B.Cu")
		(net 1)
	)
	(via
		(at 129.630532 73.65)
		(size 0.45)
		(drill 0.1)
		(layers "F.Cu" "B.Cu")
		(net 1)
	)
	(via
		(at 191.75 71.95)
		(size 0.45)
		(drill 0.1)
		(layers "F.Cu" "B.Cu")
		(net 1)
	)
	(via
		(at 125.330532 78.15)
		(size 0.45)
		(drill 0.1)
		(layers "F.Cu" "B.Cu")
		(net 1)
	)
	(via
		(at 100.05 55.9)
		(size 0.45)
		(drill 0.1)
		(layers "F.Cu" "B.Cu")
		(net 1)
	)
	(via
		(at 99.2 54.4)
		(size 0.45)
		(drill 0.1)
		(layers "F.Cu" "B.Cu")
		(net 1)
	)
	(via
		(at 90.25 145.93)
		(size 0.45)
		(drill 0.1)
		(layers "F.Cu" "B.Cu")
		(net 1)
	)
	(via
		(at 133.430532 78.15)
		(size 0.45)
		(drill 0.1)
		(layers "F.Cu" "B.Cu")
		(net 1)
	)
	(via
		(at 126.930532 85.65)
		(size 0.45)
		(drill 0.1)
		(layers "F.Cu" "B.Cu")
		(net 1)
	)
	(via
		(at 103.55 75.14)
		(size 0.45)
		(drill 0.1)
		(layers "F.Cu" "B.Cu")
		(net 1)
	)
	(via
		(at 117.530532 76.65)
		(size 0.45)
		(drill 0.1)
		(layers "F.Cu" "B.Cu")
		(net 1)
	)
	(via
		(at 171.4 70.35)
		(size 0.45)
		(drill 0.1)
		(layers "F.Cu" "B.Cu")
		(remove_unused_layers yes)
		(keep_end_layers yes)
		(free yes)
		(zone_layer_connections "In1.Cu" "In3.Cu" "In6.Cu" "In8.Cu")
		(net 1)
	)
	(via
		(at 224.15 100.85)
		(size 0.45)
		(drill 0.1)
		(layers "F.Cu" "B.Cu")
		(net 1)
	)
	(via
		(at 169.8 80.5)
		(size 0.45)
		(drill 0.1)
		(layers "F.Cu" "B.Cu")
		(remove_unused_layers yes)
		(keep_end_layers yes)
		(free yes)
		(zone_layer_connections "In1.Cu" "In3.Cu" "In6.Cu" "In8.Cu")
		(net 1)
	)
	(via
		(at 78.315532 128.475)
		(size 0.45)
		(drill 0.1)
		(layers "F.Cu" "B.Cu")
		(net 1)
	)
	(via
		(at 126.930532 73.65)
		(size 0.45)
		(drill 0.1)
		(layers "F.Cu" "B.Cu")
		(net 1)
	)
	(via
		(at 68 153)
		(size 0.45)
		(drill 0.1)
		(layers "F.Cu" "B.Cu")
		(free yes)
		(net 1)
	)
	(via
		(at 126.930532 70.65)
		(size 0.45)
		(drill 0.1)
		(layers "F.Cu" "B.Cu")
		(net 1)
	)
	(via
		(at 73.235532 110.695)
		(size 0.45)
		(drill 0.1)
		(layers "F.Cu" "B.Cu")
		(net 1)
	)
	(via
		(at 161.3 144.2)
		(size 0.45)
		(drill 0.1)
		(layers "F.Cu" "B.Cu")
		(net 1)
	)
	(via
		(at 70.695532 120.855)
		(size 0.45)
		(drill 0.1)
		(layers "F.Cu" "B.Cu")
		(net 1)
	)
	(via
		(at 214.946 137.8)
		(size 0.45)
		(drill 0.1)
		(layers "F.Cu" "B.Cu")
		(net 1)
	)
	(via
		(at 191.75 63.1)
		(size 0.45)
		(drill 0.1)
		(layers "F.Cu" "B.Cu")
		(net 1)
	)
	(via
		(at 179.949468 65.99)
		(size 0.45)
		(drill 0.1)
		(layers "F.Cu" "B.Cu")
		(remove_unused_layers yes)
		(keep_end_layers yes)
		(zone_layer_connections "In1.Cu" "In3.Cu" "In6.Cu" "In8.Cu")
		(net 1)
	)
	(via
		(at 143.725 59.125)
		(size 0.45)
		(drill 0.1)
		(layers "F.Cu" "B.Cu")
		(net 1)
	)
	(via
		(at 171 128.35)
		(size 0.45)
		(drill 0.1)
		(layers "F.Cu" "B.Cu")
		(remove_unused_layers yes)
		(keep_end_layers yes)
		(free yes)
		(zone_layer_connections "In1.Cu" "In3.Cu" "In6.Cu" "In8.Cu")
		(net 1)
	)
	(via
		(at 104.230532 82.65)
		(size 0.45)
		(drill 0.1)
		(layers "F.Cu" "B.Cu")
		(net 1)
	)
	(via
		(at 150.8 97.6)
		(size 0.45)
		(drill 0.1)
		(layers "F.Cu" "B.Cu")
		(net 1)
	)
	(via
		(at 170.58 143.95)
		(size 0.45)
		(drill 0.1)
		(layers "F.Cu" "B.Cu")
		(remove_unused_layers yes)
		(keep_end_layers yes)
		(free yes)
		(zone_layer_connections "In1.Cu" "In3.Cu" "In6.Cu" "In8.Cu")
		(net 1)
	)
	(via
		(at 70.695532 122.125)
		(size 0.45)
		(drill 0.1)
		(layers "F.Cu" "B.Cu")
		(net 1)
	)
	(via
		(at 61.8 105.7)
		(size 0.45)
		(drill 0.1)
		(layers "F.Cu" "B.Cu")
		(net 1)
	)
	(via
		(at 180.51 144.02)
		(size 0.45)
		(drill 0.1)
		(layers "F.Cu" "B.Cu")
		(remove_unused_layers yes)
		(keep_end_layers yes)
		(free yes)
		(zone_layer_connections "In1.Cu" "In3.Cu" "In6.Cu" "In8.Cu")
		(net 1)
	)
	(via
		(at 143.402 133.952)
		(size 0.45)
		(drill 0.1)
		(layers "F.Cu" "B.Cu")
		(net 1)
	)
	(via
		(at 199.126 141.5)
		(size 0.45)
		(drill 0.1)
		(layers "F.Cu" "B.Cu")
		(net 1)
	)
	(via
		(at 85.854 56.805)
		(size 0.45)
		(drill 0.1)
		(layers "F.Cu" "B.Cu")
		(net 1)
	)
	(via
		(at 147.9 147.4)
		(size 0.45)
		(drill 0.1)
		(layers "F.Cu" "B.Cu")
		(net 1)
	)
	(via
		(at 207.326 141.1)
		(size 0.45)
		(drill 0.1)
		(layers "F.Cu" "B.Cu")
		(net 1)
	)
	(via
		(at 71.965532 96.725)
		(size 0.45)
		(drill 0.1)
		(layers "F.Cu" "B.Cu")
		(net 1)
	)
	(via
		(at 71.965532 123.395)
		(size 0.45)
		(drill 0.1)
		(layers "F.Cu" "B.Cu")
		(net 1)
	)
	(via
		(at 223.05 88.1)
		(size 0.45)
		(drill 0.1)
		(layers "F.Cu" "B.Cu")
		(net 1)
	)
	(via
		(at 95.505329 59.425)
		(size 0.45)
		(drill 0.1)
		(layers "F.Cu" "B.Cu")
		(net 1)
	)
	(via
		(at 221.4 83.65)
		(size 0.45)
		(drill 0.1)
		(layers "F.Cu" "B.Cu")
		(net 1)
	)
	(via
		(at 193.798 54.595999)
		(size 0.45)
		(drill 0.1)
		(layers "F.Cu" "B.Cu")
		(net 1)
	)
	(via
		(at 214.5 123.7)
		(size 0.45)
		(drill 0.1)
		(layers "F.Cu" "B.Cu")
		(net 1)
	)
	(via
		(at 95.530532 72.15)
		(size 0.45)
		(drill 0.1)
		(layers "F.Cu" "B.Cu")
		(net 1)
	)
	(via
		(at 222.7 109.3)
		(size 0.45)
		(drill 0.1)
		(layers "F.Cu" "B.Cu")
		(net 1)
	)
	(via
		(at 176.65 145.52)
		(size 0.45)
		(drill 0.1)
		(layers "F.Cu" "B.Cu")
		(remove_unused_layers yes)
		(keep_end_layers yes)
		(free yes)
		(zone_layer_connections "In1.Cu" "In3.Cu" "In6.Cu" "In8.Cu")
		(net 1)
	)
	(via
		(at 172.6 111.75)
		(size 0.45)
		(drill 0.1)
		(layers "F.Cu" "B.Cu")
		(remove_unused_layers yes)
		(keep_end_layers yes)
		(free yes)
		(zone_layer_connections "In1.Cu" "In3.Cu" "In6.Cu" "In8.Cu")
		(net 1)
	)
	(via
		(at 206.52 62.483)
		(size 0.45)
		(drill 0.1)
		(layers "F.Cu" "B.Cu")
		(net 1)
	)
	(via
		(at 209.15 136.45)
		(size 0.45)
		(drill 0.1)
		(layers "F.Cu" "B.Cu")
		(net 1)
	)
	(via
		(at 88.130532 70.65)
		(size 0.45)
		(drill 0.1)
		(layers "F.Cu" "B.Cu")
		(net 1)
	)
	(via
		(at 91.930532 81.15)
		(size 0.45)
		(drill 0.1)
		(layers "F.Cu" "B.Cu")
		(net 1)
	)
	(via
		(at 60.6 61.2)
		(size 0.45)
		(drill 0.1)
		(layers "F.Cu" "B.Cu")
		(net 1)
	)
	(via
		(at 173.5 101.2)
		(size 0.45)
		(drill 0.1)
		(layers "F.Cu" "B.Cu")
		(remove_unused_layers yes)
		(keep_end_layers yes)
		(free yes)
		(zone_layer_connections "In1.Cu" "In3.Cu" "In6.Cu" "In8.Cu")
		(net 1)
	)
	(via
		(at 233.4 81.796)
		(size 0.45)
		(drill 0.1)
		(layers "F.Cu" "B.Cu")
		(net 1)
	)
	(via
		(at 199.158 59.8)
		(size 0.45)
		(drill 0.1)
		(layers "F.Cu" "B.Cu")
		(net 1)
	)
	(via
		(at 120.2 152.9)
		(size 0.45)
		(drill 0.1)
		(layers "F.Cu" "B.Cu")
		(net 1)
	)
	(via
		(at 184.05 109.67)
		(size 0.45)
		(drill 0.1)
		(layers "F.Cu" "B.Cu")
		(remove_unused_layers yes)
		(keep_end_layers yes)
		(zone_layer_connections "In1.Cu" "In3.Cu" "In6.Cu" "In8.Cu")
		(net 1)
	)
	(via
		(at 196 122.9)
		(size 0.45)
		(drill 0.1)
		(layers "F.Cu" "B.Cu")
		(remove_unused_layers yes)
		(keep_end_layers yes)
		(zone_layer_connections "In1.Cu" "In3.Cu" "In6.Cu" "In8.Cu")
		(net 1)
	)
	(via
		(at 99.2 60.3)
		(size 0.45)
		(drill 0.1)
		(layers "F.Cu" "B.Cu")
		(net 1)
	)
	(via
		(at 82.125532 80.215)
		(size 0.45)
		(drill 0.1)
		(layers "F.Cu" "B.Cu")
		(net 1)
	)
	(via
		(at 99.530532 84.15)
		(size 0.45)
		(drill 0.1)
		(layers "F.Cu" "B.Cu")
		(net 1)
	)
	(via
		(at 189.026 141.4)
		(size 0.45)
		(drill 0.1)
		(layers "F.Cu" "B.Cu")
		(net 1)
	)
	(via
		(at 77.045532 100.535)
		(size 0.45)
		(drill 0.1)
		(layers "F.Cu" "B.Cu")
		(net 1)
	)
	(via
		(at 174.05 127.8)
		(size 0.45)
		(drill 0.1)
		(layers "F.Cu" "B.Cu")
		(remove_unused_layers yes)
		(keep_end_layers yes)
		(free yes)
		(zone_layer_connections "In1.Cu" "In3.Cu" "In6.Cu" "In8.Cu")
		(net 1)
	)
	(via
		(at 84.665532 81.485)
		(size 0.45)
		(drill 0.1)
		(layers "F.Cu" "B.Cu")
		(net 1)
	)
	(via
		(at 73.235532 106.885)
		(size 0.45)
		(drill 0.1)
		(layers "F.Cu" "B.Cu")
		(net 1)
	)
	(via
		(at 220.3 75.7)
		(size 0.45)
		(drill 0.1)
		(layers "F.Cu" "B.Cu")
		(net 1)
	)
	(via
		(at 84.665532 127.205)
		(size 0.45)
		(drill 0.1)
		(layers "F.Cu" "B.Cu")
		(net 1)
	)
	(via
		(at 174.45 111.75)
		(size 0.45)
		(drill 0.1)
		(layers "F.Cu" "B.Cu")
		(remove_unused_layers yes)
		(keep_end_layers yes)
		(free yes)
		(zone_layer_connections "In1.Cu" "In3.Cu" "In6.Cu" "In8.Cu")
		(net 1)
	)
	(via
		(at 131.7 141.9)
		(size 0.45)
		(drill 0.1)
		(layers "F.Cu" "B.Cu")
		(net 1)
	)
	(via
		(at 169.3 81)
		(size 0.45)
		(drill 0.1)
		(layers "F.Cu" "B.Cu")
		(remove_unused_layers yes)
		(keep_end_layers yes)
		(free yes)
		(zone_layer_connections "In1.Cu" "In3.Cu" "In6.Cu" "In8.Cu")
		(net 1)
	)
	(via
		(at 70.695532 106.885)
		(size 0.45)
		(drill 0.1)
		(layers "F.Cu" "B.Cu")
		(net 1)
	)
	(via
		(at 73.235532 122.125)
		(size 0.45)
		(drill 0.1)
		(layers "F.Cu" "B.Cu")
		(net 1)
	)
	(via
		(at 60.6 132)
		(size 0.45)
		(drill 0.1)
		(layers "F.Cu" "B.Cu")
		(free yes)
		(net 1)
	)
	(via
		(at 88.130532 73.65)
		(size 0.45)
		(drill 0.1)
		(layers "F.Cu" "B.Cu")
		(net 1)
	)
	(via
		(at 97 145.5)
		(size 0.45)
		(drill 0.1)
		(layers "F.Cu" "B.Cu")
		(free yes)
		(net 1)
	)
	(via
		(at 116.8 87.9)
		(size 0.45)
		(drill 0.1)
		(layers "F.Cu" "B.Cu")
		(net 1)
	)
	(via
		(at 228.67 116.6)
		(size 0.45)
		(drill 0.1)
		(layers "F.Cu" "B.Cu")
		(net 1)
	)
	(via
		(at 130.729993 56.61)
		(size 0.45)
		(drill 0.1)
		(layers "F.Cu" "B.Cu")
		(net 1)
	)
	(via
		(at 89.230532 81.15)
		(size 0.45)
		(drill 0.1)
		(layers "F.Cu" "B.Cu")
		(net 1)
	)
	(via
		(at 73.235532 128.475)
		(size 0.45)
		(drill 0.1)
		(layers "F.Cu" "B.Cu")
		(net 1)
	)
	(via
		(at 170.01 89.545856)
		(size 0.45)
		(drill 0.1)
		(layers "F.Cu" "B.Cu")
		(remove_unused_layers yes)
		(keep_end_layers yes)
		(free yes)
		(zone_layer_connections "In1.Cu" "In3.Cu" "In6.Cu" "In8.Cu")
		(net 1)
	)
	(via
		(at 171.05 93)
		(size 0.45)
		(drill 0.1)
		(layers "F.Cu" "B.Cu")
		(remove_unused_layers yes)
		(keep_end_layers yes)
		(free yes)
		(zone_layer_connections "In1.Cu" "In3.Cu" "In6.Cu" "In8.Cu")
		(net 1)
	)
	(via
		(at 112.6 128.3)
		(size 0.45)
		(drill 0.1)
		(layers "F.Cu" "B.Cu")
		(net 1)
	)
	(via
		(at 175.75 91.4)
		(size 0.45)
		(drill 0.1)
		(layers "F.Cu" "B.Cu")
		(remove_unused_layers yes)
		(keep_end_layers yes)
		(free yes)
		(zone_layer_connections "In1.Cu" "In3.Cu" "In6.Cu" "In8.Cu")
		(net 1)
	)
	(via
		(at 74.505532 123.395)
		(size 0.45)
		(drill 0.1)
		(layers "F.Cu" "B.Cu")
		(net 1)
	)
	(via
		(at 199.075 110)
		(size 0.45)
		(drill 0.1)
		(layers "F.Cu" "B.Cu")
		(net 1)
	)
	(via
		(at 214.4 91.7)
		(size 0.45)
		(drill 0.1)
		(layers "F.Cu" "B.Cu")
		(net 1)
	)
	(via
		(at 172.05 111.2)
		(size 0.45)
		(drill 0.1)
		(layers "F.Cu" "B.Cu")
		(remove_unused_layers yes)
		(keep_end_layers yes)
		(free yes)
		(zone_layer_connections "In1.Cu" "In3.Cu" "In6.Cu" "In8.Cu")
		(net 1)
	)
	(via
		(at 222 125.4)
		(size 0.45)
		(drill 0.1)
		(layers "F.Cu" "B.Cu")
		(net 1)
	)
	(via
		(at 96.230532 73.65)
		(size 0.45)
		(drill 0.1)
		(layers "F.Cu" "B.Cu")
		(net 1)
	)
	(via
		(at 135.6 61.8)
		(size 0.45)
		(drill 0.1)
		(layers "F.Cu" "B.Cu")
		(net 1)
	)
	(via
		(at 99.530532 78.15)
		(size 0.45)
		(drill 0.1)
		(layers "F.Cu" "B.Cu")
		(net 1)
	)
	(via
		(at 198.25 72.75)
		(size 0.45)
		(drill 0.1)
		(layers "F.Cu" "B.Cu")
		(net 1)
	)
	(via
		(at 130.730532 75.15)
		(size 0.45)
		(drill 0.1)
		(layers "F.Cu" "B.Cu")
		(net 1)
	)
	(via
		(at 210.4 63.1)
		(size 0.45)
		(drill 0.1)
		(layers "F.Cu" "B.Cu")
		(net 1)
	)
	(via
		(at 79.585532 109.425)
		(size 0.45)
		(drill 0.1)
		(layers "F.Cu" "B.Cu")
		(net 1)
	)
	(via
		(at 139.248 131.648)
		(size 0.45)
		(drill 0.1)
		(layers "F.Cu" "B.Cu")
		(net 1)
	)
	(via
		(at 176.737807 70.977807)
		(size 0.45)
		(drill 0.1)
		(layers "F.Cu" "B.Cu")
		(remove_unused_layers yes)
		(keep_end_layers yes)
		(free yes)
		(zone_layer_connections "In1.Cu" "In3.Cu" "In6.Cu" "In8.Cu")
		(net 1)
	)
	(via
		(at 164.17 92.695856)
		(size 0.45)
		(drill 0.1)
		(layers "F.Cu" "B.Cu")
		(remove_unused_layers yes)
		(keep_end_layers yes)
		(free yes)
		(zone_layer_connections "In1.Cu" "In3.Cu" "In6.Cu" "In8.Cu")
		(net 1)
	)
	(via
		(at 99.55 68.9)
		(size 0.45)
		(drill 0.1)
		(layers "F.Cu" "B.Cu")
		(net 1)
	)
	(via
		(at 180.94 127)
		(size 0.45)
		(drill 0.1)
		(layers "F.Cu" "B.Cu")
		(remove_unused_layers yes)
		(keep_end_layers yes)
		(free yes)
		(zone_layer_connections "In1.Cu" "In3.Cu" "In6.Cu" "In8.Cu")
		(net 1)
	)
	(via
		(at 83.395532 113.235)
		(size 0.45)
		(drill 0.1)
		(layers "F.Cu" "B.Cu")
		(net 1)
	)
	(via
		(at 157.85 141.85)
		(size 0.45)
		(drill 0.1)
		(layers "F.Cu" "B.Cu")
		(net 1)
	)
	(via
		(at 139.530532 76.65)
		(size 0.45)
		(drill 0.1)
		(layers "F.Cu" "B.Cu")
		(net 1)
	)
	(via
		(at 208.09027 67.329)
		(size 0.45)
		(drill 0.1)
		(layers "F.Cu" "B.Cu")
		(net 1)
	)
	(via
		(at 83.395532 78.945)
		(size 0.45)
		(drill 0.1)
		(layers "F.Cu" "B.Cu")
		(net 1)
	)
	(via
		(at 132.330532 73.65)
		(size 0.45)
		(drill 0.1)
		(layers "F.Cu" "B.Cu")
		(net 1)
	)
	(via
		(at 116.230532 82.65)
		(size 0.45)
		(drill 0.1)
		(layers "F.Cu" "B.Cu")
		(net 1)
	)
	(via
		(at 160.849468 79.51)
		(size 0.45)
		(drill 0.1)
		(layers "F.Cu" "B.Cu")
		(remove_unused_layers yes)
		(keep_end_layers yes)
		(zone_layer_connections "In1.Cu" "In3.Cu" "In6.Cu" "In8.Cu")
		(net 1)
	)
	(via
		(at 177.81 90.995856)
		(size 0.45)
		(drill 0.1)
		(layers "F.Cu" "B.Cu")
		(remove_unused_layers yes)
		(keep_end_layers yes)
		(free yes)
		(zone_layer_connections "In1.Cu" "In3.Cu" "In6.Cu" "In8.Cu")
		(net 1)
	)
	(via
		(at 192.9 67.4)
		(size 0.45)
		(drill 0.1)
		(layers "F.Cu" "B.Cu")
		(net 1)
	)
	(via
		(at 71.965532 127.205)
		(size 0.45)
		(drill 0.1)
		(layers "F.Cu" "B.Cu")
		(net 1)
	)
	(via
		(at 68.2 62.4)
		(size 0.45)
		(drill 0.1)
		(layers "F.Cu" "B.Cu")
		(net 1)
	)
	(via
		(at 112.5 137.25)
		(size 0.45)
		(drill 0.1)
		(layers "F.Cu" "B.Cu")
		(net 1)
	)
	(via
		(at 168.42 82.07)
		(size 0.45)
		(drill 0.1)
		(layers "F.Cu" "B.Cu")
		(remove_unused_layers yes)
		(keep_end_layers yes)
		(free yes)
		(zone_layer_connections "In1.Cu" "In3.Cu" "In6.Cu" "In8.Cu")
		(net 1)
	)
	(via
		(at 174.85 129.45)
		(size 0.45)
		(drill 0.1)
		(layers "F.Cu" "B.Cu")
		(remove_unused_layers yes)
		(keep_end_layers yes)
		(free yes)
		(zone_layer_connections "In1.Cu" "In3.Cu" "In6.Cu" "In8.Cu")
		(net 1)
	)
	(via
		(at 201.2 82.9)
		(size 0.45)
		(drill 0.1)
		(layers "F.Cu" "B.Cu")
		(net 1)
	)
	(via
		(at 178.62 144.01)
		(size 0.45)
		(drill 0.1)
		(layers "F.Cu" "B.Cu")
		(remove_unused_layers yes)
		(keep_end_layers yes)
		(free yes)
		(zone_layer_connections "In1.Cu" "In3.Cu" "In6.Cu" "In8.Cu")
		(net 1)
	)
	(via
		(at 120.230532 82.65)
		(size 0.45)
		(drill 0.1)
		(layers "F.Cu" "B.Cu")
		(net 1)
	)
	(via
		(at 85.854 54.877)
		(size 0.45)
		(drill 0.1)
		(layers "F.Cu" "B.Cu")
		(net 1)
	)
	(via
		(at 179.2 91.45)
		(size 0.45)
		(drill 0.1)
		(layers "F.Cu" "B.Cu")
		(remove_unused_layers yes)
		(keep_end_layers yes)
		(free yes)
		(zone_layer_connections "In1.Cu" "In3.Cu" "In6.Cu" "In8.Cu")
		(net 1)
	)
	(via
		(at 69.425532 97.995)
		(size 0.45)
		(drill 0.1)
		(layers "F.Cu" "B.Cu")
		(net 1)
	)
	(via
		(at 77.045532 92.915)
		(size 0.45)
		(drill 0.1)
		(layers "F.Cu" "B.Cu")
		(net 1)
	)
	(via
		(at 85.935532 118.315)
		(size 0.45)
		(drill 0.1)
		(layers "F.Cu" "B.Cu")
		(net 1)
	)
	(via
		(at 226.8 78.3)
		(size 0.45)
		(drill 0.1)
		(layers "F.Cu" "B.Cu")
		(net 1)
	)
	(via
		(at 100.5 58.82)
		(size 0.45)
		(drill 0.1)
		(layers "F.Cu" "B.Cu")
		(net 1)
	)
	(via
		(at 95.530532 78.15)
		(size 0.45)
		(drill 0.1)
		(layers "F.Cu" "B.Cu")
		(net 1)
	)
	(via
		(at 78.315532 95.455)
		(size 0.45)
		(drill 0.1)
		(layers "F.Cu" "B.Cu")
		(net 1)
	)
	(via
		(at 78.315532 110.695)
		(size 0.45)
		(drill 0.1)
		(layers "F.Cu" "B.Cu")
		(net 1)
	)
	(via
		(at 101.54 76.65)
		(size 0.45)
		(drill 0.1)
		(layers "F.Cu" "B.Cu")
		(net 1)
	)
	(via
		(at 214 96.9)
		(size 0.45)
		(drill 0.1)
		(layers "F.Cu" "B.Cu")
		(net 1)
	)
	(via
		(at 115.12 55.64)
		(size 0.45)
		(drill 0.1)
		(layers "F.Cu" "B.Cu")
		(net 1)
	)
	(via
		(at 160.9 61.6)
		(size 0.45)
		(drill 0.1)
		(layers "F.Cu" "B.Cu")
		(net 1)
	)
	(via
		(at 102 117)
		(size 0.45)
		(drill 0.1)
		(layers "F.Cu" "B.Cu")
		(net 1)
	)
	(via
		(at 114.230532 81.15)
		(size 0.45)
		(drill 0.1)
		(layers "F.Cu" "B.Cu")
		(net 1)
	)
	(via
		(at 111.530532 84.15)
		(size 0.45)
		(drill 0.1)
		(layers "F.Cu" "B.Cu")
		(net 1)
	)
	(via
		(at 183.5 70.65)
		(size 0.45)
		(drill 0.1)
		(layers "F.Cu" "B.Cu")
		(remove_unused_layers yes)
		(keep_end_layers yes)
		(zone_layer_connections "In1.Cu" "In3.Cu" "In6.Cu" "In8.Cu")
		(net 1)
	)
	(via
		(at 166.61 92.695856)
		(size 0.45)
		(drill 0.1)
		(layers "F.Cu" "B.Cu")
		(remove_unused_layers yes)
		(keep_end_layers yes)
		(free yes)
		(zone_layer_connections "In1.Cu" "In3.Cu" "In6.Cu" "In8.Cu")
		(net 1)
	)
	(via
		(at 217.6 97.8)
		(size 0.45)
		(drill 0.1)
		(layers "F.Cu" "B.Cu")
		(net 1)
	)
	(via
		(at 60.6 141)
		(size 0.45)
		(drill 0.1)
		(layers "F.Cu" "B.Cu")
		(free yes)
		(net 1)
	)
	(via
		(at 150.9 101.3)
		(size 0.45)
		(drill 0.1)
		(layers "F.Cu" "B.Cu")
		(net 1)
	)
	(via
		(at 238.55 84.3)
		(size 0.45)
		(drill 0.1)
		(layers "F.Cu" "B.Cu")
		(net 1)
	)
	(via
		(at 219.3 89.65)
		(size 0.45)
		(drill 0.1)
		(layers "F.Cu" "B.Cu")
		(net 1)
	)
	(via
		(at 63.5 153)
		(size 0.45)
		(drill 0.1)
		(layers "F.Cu" "B.Cu")
		(free yes)
		(net 1)
	)
	(via
		(at 213.3 134.7)
		(size 0.45)
		(drill 0.1)
		(layers "F.Cu" "B.Cu")
		(net 1)
	)
	(via
		(at 78.315532 103.075)
		(size 0.45)
		(drill 0.1)
		(layers "F.Cu" "B.Cu")
		(net 1)
	)
	(via
		(at 221.9 128.6)
		(size 0.45)
		(drill 0.1)
		(layers "F.Cu" "B.Cu")
		(net 1)
	)
	(via
		(at 72.2 142.8)
		(size 0.45)
		(drill 0.1)
		(layers "F.Cu" "B.Cu")
		(net 1)
	)
	(via
		(at 74.505532 85.295)
		(size 0.45)
		(drill 0.1)
		(layers "F.Cu" "B.Cu")
		(net 1)
	)
	(via
		(at 176.61 91.045856)
		(size 0.45)
		(drill 0.1)
		(layers "F.Cu" "B.Cu")
		(remove_unused_layers yes)
		(keep_end_layers yes)
		(free yes)
		(zone_layer_connections "In1.Cu" "In3.Cu" "In6.Cu" "In8.Cu")
		(net 1)
	)
	(via
		(at 176.6 128.35)
		(size 0.45)
		(drill 0.1)
		(layers "F.Cu" "B.Cu")
		(remove_unused_layers yes)
		(keep_end_layers yes)
		(free yes)
		(zone_layer_connections "In1.Cu" "In3.Cu" "In6.Cu" "In8.Cu")
		(net 1)
	)
	(via
		(at 77.045532 104.345)
		(size 0.45)
		(drill 0.1)
		(layers "F.Cu" "B.Cu")
		(net 1)
	)
	(via
		(at 126.2 120)
		(size 0.45)
		(drill 0.1)
		(layers "F.Cu" "B.Cu")
		(net 1)
	)
	(via
		(at 98.5 145.5)
		(size 0.45)
		(drill 0.1)
		(layers "F.Cu" "B.Cu")
		(free yes)
		(net 1)
	)
	(via
		(at 82.125532 120.855)
		(size 0.45)
		(drill 0.1)
		(layers "F.Cu" "B.Cu")
		(net 1)
	)
	(via
		(at 178.84 128.4)
		(size 0.45)
		(drill 0.1)
		(layers "F.Cu" "B.Cu")
		(remove_unused_layers yes)
		(keep_end_layers yes)
		(free yes)
		(zone_layer_connections "In1.Cu" "In3.Cu" "In6.Cu" "In8.Cu")
		(net 1)
	)
	(via
		(at 208.225 59.425)
		(size 0.45)
		(drill 0.1)
		(layers "F.Cu" "B.Cu")
		(net 1)
	)
	(via
		(at 112.230532 70.65)
		(size 0.45)
		(drill 0.1)
		(layers "F.Cu" "B.Cu")
		(net 1)
	)
	(via
		(at 146.4 65.6)
		(size 0.45)
		(drill 0.1)
		(layers "F.Cu" "B.Cu")
		(net 1)
	)
	(via
		(at 162.95 140.5)
		(size 0.45)
		(drill 0.1)
		(layers "F.Cu" "B.Cu")
		(net 1)
	)
	(via
		(at 83.9 66.6)
		(size 0.45)
		(drill 0.1)
		(layers "F.Cu" "B.Cu")
		(net 1)
	)
	(via
		(at 98.230532 81.15)
		(size 0.45)
		(drill 0.1)
		(layers "F.Cu" "B.Cu")
		(net 1)
	)
	(via
		(at 110.230532 72.15)
		(size 0.45)
		(drill 0.1)
		(layers "F.Cu" "B.Cu")
		(net 1)
	)
	(via
		(at 69.5 153)
		(size 0.45)
		(drill 0.1)
		(layers "F.Cu" "B.Cu")
		(free yes)
		(net 1)
	)
	(via
		(at 169.5 72.25)
		(size 0.45)
		(drill 0.1)
		(layers "F.Cu" "B.Cu")
		(remove_unused_layers yes)
		(keep_end_layers yes)
		(free yes)
		(zone_layer_connections "In1.Cu" "In3.Cu" "In6.Cu" "In8.Cu")
		(net 1)
	)
	(via
		(at 135.030532 85.65)
		(size 0.45)
		(drill 0.1)
		(layers "F.Cu" "B.Cu")
		(net 1)
	)
	(via
		(at 200.658 59.8)
		(size 0.45)
		(drill 0.1)
		(layers "F.Cu" "B.Cu")
		(net 1)
	)
	(via
		(at 150.4 96)
		(size 0.45)
		(drill 0.1)
		(layers "F.Cu" "B.Cu")
		(net 1)
	)
	(via
		(at 69.425532 99.265)
		(size 0.45)
		(drill 0.1)
		(layers "F.Cu" "B.Cu")
		(net 1)
	)
	(via
		(at 116.230532 73.65)
		(size 0.45)
		(drill 0.1)
		(layers "F.Cu" "B.Cu")
		(free yes)
		(net 1)
	)
	(via
		(at 181.551652 123.717356)
		(size 0.45)
		(drill 0.1)
		(layers "F.Cu" "B.Cu")
		(remove_unused_layers yes)
		(keep_end_layers yes)
		(zone_layer_connections "In1.Cu" "In3.Cu" "In6.Cu" "In8.Cu")
		(net 1)
	)
	(via
		(at 112.5 97.261)
		(size 0.45)
		(drill 0.1)
		(layers "F.Cu" "B.Cu")
		(net 1)
	)
	(via
		(at 233.6 83.6)
		(size 0.45)
		(drill 0.1)
		(layers "F.Cu" "B.Cu")
		(net 1)
	)
	(via
		(at 105.530532 73.65)
		(size 0.45)
		(drill 0.1)
		(layers "F.Cu" "B.Cu")
		(net 1)
	)
	(via
		(at 143.8 127.45)
		(size 0.45)
		(drill 0.1)
		(layers "F.Cu" "B.Cu")
		(remove_unused_layers yes)
		(keep_end_layers yes)
		(zone_layer_connections "In1.Cu" "In3.Cu" "In6.Cu" "In8.Cu")
		(net 1)
	)
	(via
		(at 69.425532 89.105)
		(size 0.45)
		(drill 0.1)
		(layers "F.Cu" "B.Cu")
		(net 1)
	)
	(via
		(at 104.230532 73.65)
		(size 0.45)
		(drill 0.1)
		(layers "F.Cu" "B.Cu")
		(net 1)
	)
	(via
		(at 182.84 69.11)
		(size 0.45)
		(drill 0.1)
		(layers "F.Cu" "B.Cu")
		(remove_unused_layers yes)
		(keep_end_layers yes)
		(zone_layer_connections "In1.Cu" "In3.Cu" "In6.Cu" "In8.Cu")
		(net 1)
	)
	(via
		(at 172.75 128.35)
		(size 0.45)
		(drill 0.1)
		(layers "F.Cu" "B.Cu")
		(remove_unused_layers yes)
		(keep_end_layers yes)
		(free yes)
		(zone_layer_connections "In1.Cu" "In3.Cu" "In6.Cu" "In8.Cu")
		(net 1)
	)
	(via
		(at 172.9 100.7)
		(size 0.45)
		(drill 0.1)
		(layers "F.Cu" "B.Cu")
		(remove_unused_layers yes)
		(keep_end_layers yes)
		(free yes)
		(zone_layer_connections "In1.Cu" "In3.Cu" "In6.Cu" "In8.Cu")
		(net 1)
	)
	(via
		(at 170.51 91.045856)
		(size 0.45)
		(drill 0.1)
		(layers "F.Cu" "B.Cu")
		(remove_unused_layers yes)
		(keep_end_layers yes)
		(free yes)
		(zone_layer_connections "In1.Cu" "In3.Cu" "In6.Cu" "In8.Cu")
		(net 1)
	)
	(via
		(at 155 107.5)
		(size 0.45)
		(drill 0.1)
		(layers "F.Cu" "B.Cu")
		(net 1)
	)
	(via
		(at 84.665532 111.965)
		(size 0.45)
		(drill 0.1)
		(layers "F.Cu" "B.Cu")
		(net 1)
	)
	(via
		(at 169.25 100.65)
		(size 0.45)
		(drill 0.1)
		(layers "F.Cu" "B.Cu")
		(remove_unused_layers yes)
		(keep_end_layers yes)
		(free yes)
		(zone_layer_connections "In1.Cu" "In3.Cu" "In6.Cu" "In8.Cu")
		(net 1)
	)
	(via
		(at 107.530532 78.15)
		(size 0.45)
		(drill 0.1)
		(layers "F.Cu" "B.Cu")
		(net 1)
	)
	(via
		(at 82.125532 90.375)
		(size 0.45)
		(drill 0.1)
		(layers "F.Cu" "B.Cu")
		(net 1)
	)
	(via
		(at 202.6 91.4)
		(size 0.45)
		(drill 0.1)
		(layers "F.Cu" "B.Cu")
		(net 1)
	)
	(via
		(at 181.5 110)
		(size 0.45)
		(drill 0.1)
		(layers "F.Cu" "B.Cu")
		(remove_unused_layers yes)
		(keep_end_layers yes)
		(free yes)
		(zone_layer_connections "In1.Cu" "In3.Cu" "In6.Cu" "In8.Cu")
		(net 1)
	)
	(via
		(at 175.65 92.645856)
		(size 0.45)
		(drill 0.1)
		(layers "F.Cu" "B.Cu")
		(remove_unused_layers yes)
		(keep_end_layers yes)
		(free yes)
		(zone_layer_connections "In1.Cu" "In3.Cu" "In6.Cu" "In8.Cu")
		(net 1)
	)
	(via
		(at 214.8 108.2)
		(size 0.45)
		(drill 0.1)
		(layers "F.Cu" "B.Cu")
		(net 1)
	)
	(via
		(at 101.530532 73.65)
		(size 0.45)
		(drill 0.1)
		(layers "F.Cu" "B.Cu")
		(net 1)
	)
	(via
		(at 93.9 108)
		(size 0.45)
		(drill 0.1)
		(layers "F.Cu" "B.Cu")
		(net 1)
	)
	(via
		(at 98.5 142.5)
		(size 0.45)
		(drill 0.1)
		(layers "F.Cu" "B.Cu")
		(free yes)
		(net 1)
	)
	(via
		(at 103.05 87.65)
		(size 0.45)
		(drill 0.1)
		(layers "F.Cu" "B.Cu")
		(net 1)
	)
	(via
		(at 80.855532 92.915)
		(size 0.45)
		(drill 0.1)
		(layers "F.Cu" "B.Cu")
		(net 1)
	)
	(via
		(at 125.330532 84.15)
		(size 0.45)
		(drill 0.1)
		(layers "F.Cu" "B.Cu")
		(net 1)
	)
	(via
		(at 79.585532 90.375)
		(size 0.45)
		(drill 0.1)
		(layers "F.Cu" "B.Cu")
		(net 1)
	)
	(via
		(at 178.85 111.4)
		(size 0.45)
		(drill 0.1)
		(layers "F.Cu" "B.Cu")
		(remove_unused_layers yes)
		(keep_end_layers yes)
		(free yes)
		(zone_layer_connections "In1.Cu" "In3.Cu" "In6.Cu" "In8.Cu")
		(net 1)
	)
	(via
		(at 121.530532 79.65)
		(size 0.45)
		(drill 0.1)
		(layers "F.Cu" "B.Cu")
		(net 1)
	)
	(via
		(at 82.125532 105.615)
		(size 0.45)
		(drill 0.1)
		(layers "F.Cu" "B.Cu")
		(net 1)
	)
	(via
		(at 117.530532 85.65)
		(size 0.45)
		(drill 0.1)
		(layers "F.Cu" "B.Cu")
		(free yes)
		(net 1)
	)
	(via
		(at 85.935532 103.075)
		(size 0.45)
		(drill 0.1)
		(layers "F.Cu" "B.Cu")
		(net 1)
	)
	(via
		(at 60.6 133.5)
		(size 0.45)
		(drill 0.1)
		(layers "F.Cu" "B.Cu")
		(free yes)
		(net 1)
	)
	(via
		(at 109 120.4)
		(size 0.45)
		(drill 0.1)
		(layers "F.Cu" "B.Cu")
		(net 1)
	)
	(via
		(at 71.965532 81.485)
		(size 0.45)
		(drill 0.1)
		(layers "F.Cu" "B.Cu")
		(net 1)
	)
	(via
		(at 89.230532 75.15)
		(size 0.45)
		(drill 0.1)
		(layers "F.Cu" "B.Cu")
		(net 1)
	)
	(via
		(at 107.530532 72.15)
		(size 0.45)
		(drill 0.1)
		(layers "F.Cu" "B.Cu")
		(net 1)
	)
	(via
		(at 184.05 111.57)
		(size 0.45)
		(drill 0.1)
		(layers "F.Cu" "B.Cu")
		(remove_unused_layers yes)
		(keep_end_layers yes)
		(zone_layer_connections "In1.Cu" "In3.Cu" "In6.Cu" "In8.Cu")
		(net 1)
	)
	(via
		(at 80.855532 109.425)
		(size 0.45)
		(drill 0.1)
		(layers "F.Cu" "B.Cu")
		(net 1)
	)
	(via
		(at 100.230532 73.65)
		(size 0.45)
		(drill 0.1)
		(layers "F.Cu" "B.Cu")
		(net 1)
	)
	(via
		(at 137.3 60.3)
		(size 0.45)
		(drill 0.1)
		(layers "F.Cu" "B.Cu")
		(net 1)
	)
	(via
		(at 63.5 127)
		(size 0.45)
		(drill 0.1)
		(layers "F.Cu" "B.Cu")
		(free yes)
		(net 1)
	)
	(via
		(at 126.1 113.5)
		(size 0.45)
		(drill 0.1)
		(layers "F.Cu" "B.Cu")
		(net 1)
	)
	(via
		(at 213.75 82.4)
		(size 0.45)
		(drill 0.1)
		(layers "F.Cu" "B.Cu")
		(net 1)
	)
	(via
		(at 118.230532 78.15)
		(size 0.45)
		(drill 0.1)
		(layers "F.Cu" "B.Cu")
		(net 1)
	)
	(via
		(at 195.476532 137.36)
		(size 0.45)
		(drill 0.1)
		(layers "F.Cu" "B.Cu")
		(net 1)
	)
	(via
		(at 60.6 147)
		(size 0.45)
		(drill 0.1)
		(layers "F.Cu" "B.Cu")
		(free yes)
		(net 1)
	)
	(via
		(at 82.125532 115.775)
		(size 0.45)
		(drill 0.1)
		(layers "F.Cu" "B.Cu")
		(net 1)
	)
	(via
		(at 215.2 130.8)
		(size 0.45)
		(drill 0.1)
		(layers "F.Cu" "B.Cu")
		(net 1)
	)
	(via
		(at 212.8 119)
		(size 0.45)
		(drill 0.1)
		(layers "F.Cu" "B.Cu")
		(net 1)
	)
	(via
		(at 80.855532 99.265)
		(size 0.45)
		(drill 0.1)
		(layers "F.Cu" "B.Cu")
		(net 1)
	)
	(via
		(at 111.688 91.012)
		(size 0.45)
		(drill 0.1)
		(layers "F.Cu" "B.Cu")
		(net 1)
	)
	(via
		(at 79.585532 97.995)
		(size 0.45)
		(drill 0.1)
		(layers "F.Cu" "B.Cu")
		(net 1)
	)
	(via
		(at 127.06 61.96)
		(size 0.45)
		(drill 0.1)
		(layers "F.Cu" "B.Cu")
		(net 1)
	)
	(via
		(at 110.1 91.1)
		(size 0.45)
		(drill 0.1)
		(layers "F.Cu" "B.Cu")
		(net 1)
	)
	(via
		(at 169.85 101.15)
		(size 0.45)
		(drill 0.1)
		(layers "F.Cu" "B.Cu")
		(remove_unused_layers yes)
		(keep_end_layers yes)
		(free yes)
		(zone_layer_connections "In1.Cu" "In3.Cu" "In6.Cu" "In8.Cu")
		(net 1)
	)
	(via
		(at 101.95 88.8)
		(size 0.45)
		(drill 0.1)
		(layers "F.Cu" "B.Cu")
		(net 1)
	)
	(via
		(at 217.6 111.4)
		(size 0.45)
		(drill 0.1)
		(layers "F.Cu" "B.Cu")
		(net 1)
	)
	(via
		(at 138.8 63)
		(size 0.45)
		(drill 0.1)
		(layers "F.Cu" "B.Cu")
		(net 1)
	)
	(via
		(at 69.425532 92.915)
		(size 0.45)
		(drill 0.1)
		(layers "F.Cu" "B.Cu")
		(net 1)
	)
	(via
		(at 103.530532 84.15)
		(size 0.45)
		(drill 0.1)
		(layers "F.Cu" "B.Cu")
		(net 1)
	)
	(via
		(at 96.230532 79.65)
		(size 0.45)
		(drill 0.1)
		(layers "F.Cu" "B.Cu")
		(net 1)
	)
	(via
		(at 170.71 92.645856)
		(size 0.45)
		(drill 0.1)
		(layers "F.Cu" "B.Cu")
		(remove_unused_layers yes)
		(keep_end_layers yes)
		(free yes)
		(zone_layer_connections "In1.Cu" "In3.Cu" "In6.Cu" "In8.Cu")
		(net 1)
	)
	(via
		(at 120.230532 70.65)
		(size 0.45)
		(drill 0.1)
		(layers "F.Cu" "B.Cu")
		(net 1)
	)
	(via
		(at 83.395532 92.915)
		(size 0.45)
		(drill 0.1)
		(layers "F.Cu" "B.Cu")
		(net 1)
	)
	(via
		(at 172.2 127.8)
		(size 0.45)
		(drill 0.1)
		(layers "F.Cu" "B.Cu")
		(remove_unused_layers yes)
		(keep_end_layers yes)
		(free yes)
		(zone_layer_connections "In1.Cu" "In3.Cu" "In6.Cu" "In8.Cu")
		(net 1)
	)
	(via
		(at 215.35 70.7)
		(size 0.45)
		(drill 0.1)
		(layers "F.Cu" "B.Cu")
		(net 1)
	)
	(via
		(at 171.05 100.65)
		(size 0.45)
		(drill 0.1)
		(layers "F.Cu" "B.Cu")
		(remove_unused_layers yes)
		(keep_end_layers yes)
		(free yes)
		(zone_layer_connections "In1.Cu" "In3.Cu" "In6.Cu" "In8.Cu")
		(net 1)
	)
	(via
		(at 93.155 56.805)
		(size 0.45)
		(drill 0.1)
		(layers "F.Cu" "B.Cu")
		(net 1)
	)
	(via
		(at 130.6 134.1)
		(size 0.45)
		(drill 0.1)
		(layers "F.Cu" "B.Cu")
		(net 1)
	)
	(via
		(at 141.002 133.952)
		(size 0.45)
		(drill 0.1)
		(layers "F.Cu" "B.Cu")
		(net 1)
	)
	(via
		(at 212.875 62.45)
		(size 0.45)
		(drill 0.1)
		(layers "F.Cu" "B.Cu")
		(net 1)
	)
	(via
		(at 227.7 56.25)
		(size 0.45)
		(drill 0.1)
		(layers "F.Cu" "B.Cu")
		(net 1)
	)
	(via
		(at 176.35 112.9)
		(size 0.45)
		(drill 0.1)
		(layers "F.Cu" "B.Cu")
		(remove_unused_layers yes)
		(keep_end_layers yes)
		(free yes)
		(zone_layer_connections "In1.Cu" "In3.Cu" "In6.Cu" "In8.Cu")
		(net 1)
	)
	(via
		(at 78.315532 87.835)
		(size 0.45)
		(drill 0.1)
		(layers "F.Cu" "B.Cu")
		(net 1)
	)
	(via
		(at 232.77 125.4)
		(size 0.45)
		(drill 0.1)
		(layers "F.Cu" "B.Cu")
		(net 1)
	)
	(via
		(at 142.052 133.952)
		(size 0.45)
		(drill 0.1)
		(layers "F.Cu" "B.Cu")
		(net 1)
	)
	(via
		(at 97.75 147)
		(size 0.45)
		(drill 0.1)
		(layers "F.Cu" "B.Cu")
		(free yes)
		(net 1)
	)
	(via
		(at 194.8 79)
		(size 0.45)
		(drill 0.1)
		(layers "F.Cu" "B.Cu")
		(net 1)
	)
	(via
		(at 62.7 99.2)
		(size 0.45)
		(drill 0.1)
		(layers "F.Cu" "B.Cu")
		(net 1)
	)
	(via
		(at 70.695532 80.215)
		(size 0.45)
		(drill 0.1)
		(layers "F.Cu" "B.Cu")
		(net 1)
	)
	(via
		(at 229.97 89.2)
		(size 0.45)
		(drill 0.1)
		(layers "F.Cu" "B.Cu")
		(net 1)
	)
	(via
		(at 229.97 102.2)
		(size 0.45)
		(drill 0.1)
		(layers "F.Cu" "B.Cu")
		(net 1)
	)
	(via
		(at 84.665532 110.695)
		(size 0.45)
		(drill 0.1)
		(layers "F.Cu" "B.Cu")
		(net 1)
	)
	(via
		(at 162.55 72.25)
		(size 0.45)
		(drill 0.1)
		(layers "F.Cu" "B.Cu")
		(remove_unused_layers yes)
		(keep_end_layers yes)
		(free yes)
		(zone_layer_connections "In1.Cu" "In3.Cu" "In6.Cu" "In8.Cu")
		(net 1)
	)
	(via
		(at 105.88 58.32)
		(size 0.45)
		(drill 0.1)
		(layers "F.Cu" "B.Cu")
		(net 1)
	)
	(via
		(at 112.5 103.261)
		(size 0.45)
		(drill 0.1)
		(layers "F.Cu" "B.Cu")
		(net 1)
	)
	(via
		(at 85.44 149.29)
		(size 0.45)
		(drill 0.1)
		(layers "F.Cu" "B.Cu")
		(net 1)
	)
	(via
		(at 224.946 137.86)
		(size 0.45)
		(drill 0.1)
		(layers "F.Cu" "B.Cu")
		(net 1)
	)
	(via
		(at 139.730532 84.15)
		(size 0.45)
		(drill 0.1)
		(layers "F.Cu" "B.Cu")
		(net 1)
	)
	(via
		(at 75.775532 122.125)
		(size 0.45)
		(drill 0.1)
		(layers "F.Cu" "B.Cu")
		(net 1)
	)
	(via
		(at 107.530532 75.15)
		(size 0.45)
		(drill 0.1)
		(layers "F.Cu" "B.Cu")
		(net 1)
	)
	(via
		(at 180 111.95)
		(size 0.45)
		(drill 0.1)
		(layers "F.Cu" "B.Cu")
		(remove_unused_layers yes)
		(keep_end_layers yes)
		(free yes)
		(zone_layer_connections "In1.Cu" "In3.Cu" "In6.Cu" "In8.Cu")
		(net 1)
	)
	(via
		(at 236.3 97.4)
		(size 0.45)
		(drill 0.1)
		(layers "F.Cu" "B.Cu")
		(net 1)
	)
	(via
		(at 131.630532 72.15)
		(size 0.45)
		(drill 0.1)
		(layers "F.Cu" "B.Cu")
		(net 1)
	)
	(via
		(at 66.14 108.21)
		(size 0.45)
		(drill 0.1)
		(layers "F.Cu" "B.Cu")
		(net 1)
	)
	(via
		(at 84.665532 100.535)
		(size 0.45)
		(drill 0.1)
		(layers "F.Cu" "B.Cu")
		(net 1)
	)
	(via
		(at 235.57 113)
		(size 0.45)
		(drill 0.1)
		(layers "F.Cu" "B.Cu")
		(net 1)
	)
	(via
		(at 190.9 126.05)
		(size 0.45)
		(drill 0.1)
		(layers "F.Cu" "B.Cu")
		(remove_unused_layers yes)
		(keep_end_layers yes)
		(zone_layer_connections "In1.Cu" "In3.Cu" "In6.Cu" "In8.Cu")
		(net 1)
	)
	(via
		(at 189.376 140.95)
		(size 0.45)
		(drill 0.1)
		(layers "F.Cu" "B.Cu")
		(net 1)
	)
	(via
		(at 172.5 89.545856)
		(size 0.45)
		(drill 0.1)
		(layers "F.Cu" "B.Cu")
		(remove_unused_layers yes)
		(keep_end_layers yes)
		(free yes)
		(zone_layer_connections "In1.Cu" "In3.Cu" "In6.Cu" "In8.Cu")
		(net 1)
	)
	(via
		(at 180.95 110)
		(size 0.45)
		(drill 0.1)
		(layers "F.Cu" "B.Cu")
		(remove_unused_layers yes)
		(keep_end_layers yes)
		(free yes)
		(zone_layer_connections "In1.Cu" "In3.Cu" "In6.Cu" "In8.Cu")
		(net 1)
	)
	(via
		(at 115.475 119.15)
		(size 0.45)
		(drill 0.1)
		(layers "F.Cu" "B.Cu")
		(net 1)
	)
	(via
		(at 231.27 131.3)
		(size 0.45)
		(drill 0.1)
		(layers "F.Cu" "B.Cu")
		(net 1)
	)
	(via
		(at 104.33 107.27)
		(size 0.45)
		(drill 0.1)
		(layers "F.Cu" "B.Cu")
		(net 1)
	)
	(via
		(at 85.935532 97.995)
		(size 0.45)
		(drill 0.1)
		(layers "F.Cu" "B.Cu")
		(net 1)
	)
	(via
		(at 80.855532 104.345)
		(size 0.45)
		(drill 0.1)
		(layers "F.Cu" "B.Cu")
		(net 1)
	)
	(via
		(at 197.6 89.8)
		(size 0.45)
		(drill 0.1)
		(layers "F.Cu" "B.Cu")
		(net 1)
	)
	(via
		(at 144.030532 79.65)
		(size 0.45)
		(drill 0.1)
		(layers "F.Cu" "B.Cu")
		(net 1)
	)
	(via
		(at 130.730532 78.15)
		(size 0.45)
		(drill 0.1)
		(layers "F.Cu" "B.Cu")
		(net 1)
	)
	(via
		(at 111.530532 81.15)
		(size 0.45)
		(drill 0.1)
		(layers "F.Cu" "B.Cu")
		(net 1)
	)
	(via
		(at 236.57 74.6)
		(size 0.45)
		(drill 0.1)
		(layers "F.Cu" "B.Cu")
		(net 1)
	)
	(via
		(at 173.45 129.5)
		(size 0.45)
		(drill 0.1)
		(layers "F.Cu" "B.Cu")
		(remove_unused_layers yes)
		(keep_end_layers yes)
		(free yes)
		(zone_layer_connections "In1.Cu" "In3.Cu" "In6.Cu" "In8.Cu")
		(net 1)
	)
	(via
		(at 109.530532 82.65)
		(size 0.45)
		(drill 0.1)
		(layers "F.Cu" "B.Cu")
		(net 1)
	)
	(via
		(at 235.510532 102.21)
		(size 0.45)
		(drill 0.1)
		(layers "F.Cu" "B.Cu")
		(net 1)
	)
	(via
		(at 154 101.4)
		(size 0.45)
		(drill 0.1)
		(layers "F.Cu" "B.Cu")
		(net 1)
	)
	(via
		(at 119.530532 84.15)
		(size 0.45)
		(drill 0.1)
		(layers "F.Cu" "B.Cu")
		(net 1)
	)
	(via
		(at 203.2 88.1)
		(size 0.45)
		(drill 0.1)
		(layers "F.Cu" "B.Cu")
		(net 1)
	)
	(via
		(at 176 143.97)
		(size 0.45)
		(drill 0.1)
		(layers "F.Cu" "B.Cu")
		(remove_unused_layers yes)
		(keep_end_layers yes)
		(free yes)
		(zone_layer_connections "In1.Cu" "In3.Cu" "In6.Cu" "In8.Cu")
		(net 1)
	)
	(via
		(at 209.8 60)
		(size 0.45)
		(drill 0.1)
		(layers "F.Cu" "B.Cu")
		(net 1)
	)
	(via
		(at 96.230532 70.65)
		(size 0.45)
		(drill 0.1)
		(layers "F.Cu" "B.Cu")
		(net 1)
	)
	(via
		(at 91.1 107.2)
		(size 0.45)
		(drill 0.1)
		(layers "F.Cu" "B.Cu")
		(net 1)
	)
	(via
		(at 208.6 101.15)
		(size 0.45)
		(drill 0.1)
		(layers "F.Cu" "B.Cu")
		(net 1)
	)
	(via
		(at 132.945349 62.97)
		(size 0.45)
		(drill 0.1)
		(layers "F.Cu" "B.Cu")
		(net 1)
	)
	(via
		(at 147.05 92.75)
		(size 0.45)
		(drill 0.1)
		(layers "F.Cu" "B.Cu")
		(net 1)
	)
	(via
		(at 221.3 122.5)
		(size 0.45)
		(drill 0.1)
		(layers "F.Cu" "B.Cu")
		(net 1)
	)
	(via
		(at 65.6 110.5)
		(size 0.45)
		(drill 0.1)
		(layers "F.Cu" "B.Cu")
		(net 1)
	)
	(via
		(at 95.25 145.5)
		(size 0.45)
		(drill 0.1)
		(layers "F.Cu" "B.Cu")
		(free yes)
		(net 1)
	)
	(via
		(at 175.5 72.4)
		(size 0.45)
		(drill 0.1)
		(layers "F.Cu" "B.Cu")
		(remove_unused_layers yes)
		(keep_end_layers yes)
		(free yes)
		(zone_layer_connections "In1.Cu" "In3.Cu" "In6.Cu" "In8.Cu")
		(net 1)
	)
	(via
		(at 176.68 143.96)
		(size 0.45)
		(drill 0.1)
		(layers "F.Cu" "B.Cu")
		(remove_unused_layers yes)
		(keep_end_layers yes)
		(free yes)
		(zone_layer_connections "In1.Cu" "In3.Cu" "In6.Cu" "In8.Cu")
		(net 1)
	)
	(via
		(at 191.126 142.1)
		(size 0.45)
		(drill 0.1)
		(layers "F.Cu" "B.Cu")
		(net 1)
	)
	(via
		(at 69.425532 114.505)
		(size 0.45)
		(drill 0.1)
		(layers "F.Cu" "B.Cu")
		(net 1)
	)
	(via
		(at 171.009468 119.216)
		(size 0.45)
		(drill 0.1)
		(layers "F.Cu" "B.Cu")
		(remove_unused_layers yes)
		(keep_end_layers yes)
		(zone_layer_connections "In1.Cu" "In3.Cu" "In6.Cu" "In8.Cu")
		(net 1)
	)
	(via
		(at 153.8 121.5)
		(size 0.45)
		(drill 0.1)
		(layers "F.Cu" "B.Cu")
		(net 1)
	)
	(via
		(at 100.85 68.9)
		(size 0.45)
		(drill 0.1)
		(layers "F.Cu" "B.Cu")
		(net 1)
	)
	(via
		(at 126.930532 79.65)
		(size 0.45)
		(drill 0.1)
		(layers "F.Cu" "B.Cu")
		(net 1)
	)
	(via
		(at 147.25 91.02)
		(size 0.45)
		(drill 0.1)
		(layers "F.Cu" "B.Cu")
		(net 1)
	)
	(via
		(at 235.47 76.2)
		(size 0.45)
		(drill 0.1)
		(layers "F.Cu" "B.Cu")
		(net 1)
	)
	(via
		(at 82.125532 111.965)
		(size 0.45)
		(drill 0.1)
		(layers "F.Cu" "B.Cu")
		(net 1)
	)
	(via
		(at 85.935532 128.475)
		(size 0.45)
		(drill 0.1)
		(layers "F.Cu" "B.Cu")
		(net 1)
	)
	(via
		(at 174.54 91.4)
		(size 0.45)
		(drill 0.1)
		(layers "F.Cu" "B.Cu")
		(remove_unused_layers yes)
		(keep_end_layers yes)
		(free yes)
		(zone_layer_connections "In1.Cu" "In3.Cu" "In6.Cu" "In8.Cu")
		(net 1)
	)
	(via
		(at 74.8 65.4)
		(size 0.45)
		(drill 0.1)
		(layers "F.Cu" "B.Cu")
		(net 1)
	)
	(via
		(at 235.42 99.95)
		(size 0.45)
		(drill 0.1)
		(layers "F.Cu" "B.Cu")
		(net 1)
	)
	(via
		(at 147.25 126.45)
		(size 0.45)
		(drill 0.1)
		(layers "F.Cu" "B.Cu")
		(remove_unused_layers yes)
		(keep_end_layers yes)
		(zone_layer_connections "In1.Cu" "In3.Cu" "In6.Cu" "In8.Cu")
		(net 1)
	)
	(via
		(at 235.47 130.6)
		(size 0.45)
		(drill 0.1)
		(layers "F.Cu" "B.Cu")
		(net 1)
	)
	(via
		(at 147.2 62)
		(size 0.45)
		(drill 0.1)
		(layers "F.Cu" "B.Cu")
		(net 1)
	)
	(via
		(at 100.230532 82.65)
		(size 0.45)
		(drill 0.1)
		(layers "F.Cu" "B.Cu")
		(net 1)
	)
	(via
		(at 176.95 91.4)
		(size 0.45)
		(drill 0.1)
		(layers "F.Cu" "B.Cu")
		(remove_unused_layers yes)
		(keep_end_layers yes)
		(free yes)
		(zone_layer_connections "In1.Cu" "In3.Cu" "In6.Cu" "In8.Cu")
		(net 1)
	)
	(via
		(at 176.25 129.45)
		(size 0.45)
		(drill 0.1)
		(layers "F.Cu" "B.Cu")
		(remove_unused_layers yes)
		(keep_end_layers yes)
		(free yes)
		(zone_layer_connections "In1.Cu" "In3.Cu" "In6.Cu" "In8.Cu")
		(net 1)
	)
	(via
		(at 65.6 111.9)
		(size 0.45)
		(drill 0.1)
		(layers "F.Cu" "B.Cu")
		(net 1)
	)
	(via
		(at 67.4 108.2)
		(size 0.45)
		(drill 0.1)
		(layers "F.Cu" "B.Cu")
		(net 1)
	)
	(via
		(at 128.030532 81.15)
		(size 0.45)
		(drill 0.1)
		(layers "F.Cu" "B.Cu")
		(net 1)
	)
	(via
		(at 93.05 101.35)
		(size 0.45)
		(drill 0.1)
		(layers "F.Cu" "B.Cu")
		(net 1)
	)
	(via
		(at 179.99 128.4)
		(size 0.45)
		(drill 0.1)
		(layers "F.Cu" "B.Cu")
		(remove_unused_layers yes)
		(keep_end_layers yes)
		(free yes)
		(zone_layer_connections "In1.Cu" "In3.Cu" "In6.Cu" "In8.Cu")
		(net 1)
	)
	(via
		(at 232.07 112.4)
		(size 0.45)
		(drill 0.1)
		(layers "F.Cu" "B.Cu")
		(net 1)
	)
	(via
		(at 132.330532 79.65)
		(size 0.45)
		(drill 0.1)
		(layers "F.Cu" "B.Cu")
		(net 1)
	)
	(via
		(at 196.7 127.9)
		(size 0.45)
		(drill 0.1)
		(layers "F.Cu" "B.Cu")
		(net 1)
	)
	(via
		(at 231.47 118.1)
		(size 0.45)
		(drill 0.1)
		(layers "F.Cu" "B.Cu")
		(net 1)
	)
	(via
		(at 181.49 127.55)
		(size 0.45)
		(drill 0.1)
		(layers "F.Cu" "B.Cu")
		(remove_unused_layers yes)
		(keep_end_layers yes)
		(free yes)
		(zone_layer_connections "In1.Cu" "In3.Cu" "In6.Cu" "In8.Cu")
		(net 1)
	)
	(via
		(at 73.235532 125.935)
		(size 0.45)
		(drill 0.1)
		(layers "F.Cu" "B.Cu")
		(net 1)
	)
	(via
		(at 98.5 137.5)
		(size 0.45)
		(drill 0.1)
		(layers "F.Cu" "B.Cu")
		(free yes)
		(net 1)
	)
	(via
		(at 174.14 143.95)
		(size 0.45)
		(drill 0.1)
		(layers "F.Cu" "B.Cu")
		(remove_unused_layers yes)
		(keep_end_layers yes)
		(free yes)
		(zone_layer_connections "In1.Cu" "In3.Cu" "In6.Cu" "In8.Cu")
		(net 1)
	)
	(via
		(at 78.315532 114.505)
		(size 0.45)
		(drill 0.1)
		(layers "F.Cu" "B.Cu")
		(net 1)
	)
	(via
		(at 163.81 70.52)
		(size 0.45)
		(drill 0.1)
		(layers "F.Cu" "B.Cu")
		(remove_unused_layers yes)
		(keep_end_layers yes)
		(free yes)
		(zone_layer_connections "In1.Cu" "In3.Cu" "In6.Cu" "In8.Cu")
		(net 1)
	)
	(via
		(at 114.619996 55.64)
		(size 0.45)
		(drill 0.1)
		(layers "F.Cu" "B.Cu")
		(net 1)
	)
	(via
		(at 196.4 96.366)
		(size 0.45)
		(drill 0.1)
		(layers "F.Cu" "B.Cu")
		(net 1)
	)
	(via
		(at 105.530532 70.65)
		(size 0.45)
		(drill 0.1)
		(layers "F.Cu" "B.Cu")
		(net 1)
	)
	(via
		(at 177.75 112.9)
		(size 0.45)
		(drill 0.1)
		(layers "F.Cu" "B.Cu")
		(remove_unused_layers yes)
		(keep_end_layers yes)
		(free yes)
		(zone_layer_connections "In1.Cu" "In3.Cu" "In6.Cu" "In8.Cu")
		(net 1)
	)
	(via
		(at 217.3 79.3)
		(size 0.45)
		(drill 0.1)
		(layers "F.Cu" "B.Cu")
		(net 1)
	)
	(via
		(at 115.1 100.6)
		(size 0.45)
		(drill 0.1)
		(layers "F.Cu" "B.Cu")
		(net 1)
	)
	(via
		(at 133.430532 75.15)
		(size 0.45)
		(drill 0.1)
		(layers "F.Cu" "B.Cu")
		(net 1)
	)
	(via
		(at 179.39 128.4)
		(size 0.45)
		(drill 0.1)
		(layers "F.Cu" "B.Cu")
		(remove_unused_layers yes)
		(keep_end_layers yes)
		(free yes)
		(zone_layer_connections "In1.Cu" "In3.Cu" "In6.Cu" "In8.Cu")
		(net 1)
	)
	(via
		(at 65.7 84.74)
		(size 0.45)
		(drill 0.1)
		(layers "F.Cu" "B.Cu")
		(net 1)
	)
	(via
		(at 187.815907 61.400242)
		(size 0.45)
		(drill 0.1)
		(layers "F.Cu" "B.Cu")
		(net 1)
	)
	(via
		(at 60.6 153)
		(size 0.45)
		(drill 0.1)
		(layers "F.Cu" "B.Cu")
		(free yes)
		(net 1)
	)
	(via
		(at 90.5 122.4)
		(size 0.45)
		(drill 0.1)
		(layers "F.Cu" "B.Cu")
		(net 1)
	)
	(via
		(at 120.230532 73.65)
		(size 0.45)
		(drill 0.1)
		(layers "F.Cu" "B.Cu")
		(net 1)
	)
	(via
		(at 63.6 107.46)
		(size 0.45)
		(drill 0.1)
		(layers "F.Cu" "B.Cu")
		(net 1)
	)
	(via
		(at 150.9 102.3)
		(size 0.45)
		(drill 0.1)
		(layers "F.Cu" "B.Cu")
		(net 1)
	)
	(via
		(at 173.7 89.545856)
		(size 0.45)
		(drill 0.1)
		(layers "F.Cu" "B.Cu")
		(remove_unused_layers yes)
		(keep_end_layers yes)
		(free yes)
		(zone_layer_connections "In1.Cu" "In3.Cu" "In6.Cu" "In8.Cu")
		(net 1)
	)
	(via
		(at 172.96 145.51)
		(size 0.45)
		(drill 0.1)
		(layers "F.Cu" "B.Cu")
		(remove_unused_layers yes)
		(keep_end_layers yes)
		(free yes)
		(zone_layer_connections "In1.Cu" "In3.Cu" "In6.Cu" "In8.Cu")
		(net 1)
	)
	(via
		(at 124.230532 79.64)
		(size 0.45)
		(drill 0.1)
		(layers "F.Cu" "B.Cu")
		(net 1)
	)
	(via
		(at 169.1 127.9)
		(size 0.45)
		(drill 0.1)
		(layers "F.Cu" "B.Cu")
		(remove_unused_layers yes)
		(keep_end_layers yes)
		(zone_layer_connections "In1.Cu" "In3.Cu" "In6.Cu" "In8.Cu")
		(net 1)
	)
	(via
		(at 63.7 100.71)
		(size 0.45)
		(drill 0.1)
		(layers "F.Cu" "B.Cu")
		(net 1)
	)
	(via
		(at 82.125532 96.725)
		(size 0.45)
		(drill 0.1)
		(layers "F.Cu" "B.Cu")
		(net 1)
	)
	(via
		(at 131.5 148.3)
		(size 0.45)
		(drill 0.1)
		(layers "F.Cu" "B.Cu")
		(net 1)
	)
	(via
		(at 206.642806 59.505002)
		(size 0.45)
		(drill 0.1)
		(layers "F.Cu" "B.Cu")
		(net 1)
	)
	(via
		(at 144.930532 85.65)
		(size 0.45)
		(drill 0.1)
		(layers "F.Cu" "B.Cu")
		(net 1)
	)
	(via
		(at 112 74.4)
		(size 0.45)
		(drill 0.1)
		(layers "F.Cu" "B.Cu")
		(net 1)
	)
	(via
		(at 73 143.6)
		(size 0.45)
		(drill 0.1)
		(layers "F.Cu" "B.Cu")
		(net 1)
	)
	(via
		(at 99.530532 72.15)
		(size 0.45)
		(drill 0.1)
		(layers "F.Cu" "B.Cu")
		(net 1)
	)
	(via
		(at 97.75 139.75)
		(size 0.45)
		(drill 0.1)
		(layers "F.Cu" "B.Cu")
		(free yes)
		(net 1)
	)
	(via
		(at 203.05 62.85)
		(size 0.45)
		(drill 0.1)
		(layers "F.Cu" "B.Cu")
		(net 1)
	)
	(via
		(at 99.530532 81.15)
		(size 0.45)
		(drill 0.1)
		(layers "F.Cu" "B.Cu")
		(net 1)
	)
	(via
		(at 112.5 107.761)
		(size 0.45)
		(drill 0.1)
		(layers "F.Cu" "B.Cu")
		(net 1)
	)
	(via
		(at 77.045532 108.155)
		(size 0.45)
		(drill 0.1)
		(layers "F.Cu" "B.Cu")
		(net 1)
	)
	(via
		(at 222.4 96.15)
		(size 0.45)
		(drill 0.1)
		(layers "F.Cu" "B.Cu")
		(net 1)
	)
	(via
		(at 145.51 91.04)
		(size 0.45)
		(drill 0.1)
		(layers "F.Cu" "B.Cu")
		(net 1)
	)
	(via
		(at 83.395532 104.345)
		(size 0.45)
		(drill 0.1)
		(layers "F.Cu" "B.Cu")
		(net 1)
	)
	(via
		(at 227 82)
		(size 0.45)
		(drill 0.1)
		(layers "F.Cu" "B.Cu")
		(net 1)
	)
	(via
		(at 189.8 115)
		(size 0.45)
		(drill 0.1)
		(layers "F.Cu" "B.Cu")
		(free yes)
		(net 1)
	)
	(via
		(at 91.730532 70.65)
		(size 0.45)
		(drill 0.1)
		(layers "F.Cu" "B.Cu")
		(net 1)
	)
	(via
		(at 215.5 74.7)
		(size 0.45)
		(drill 0.1)
		(layers "F.Cu" "B.Cu")
		(net 1)
	)
	(via
		(at 83.395532 123.395)
		(size 0.45)
		(drill 0.1)
		(layers "F.Cu" "B.Cu")
		(net 1)
	)
	(via
		(at 138.630532 73.65)
		(size 0.45)
		(drill 0.1)
		(layers "F.Cu" "B.Cu")
		(net 1)
	)
	(via
		(at 118.230532 72.15)
		(size 0.45)
		(drill 0.1)
		(layers "F.Cu" "B.Cu")
		(net 1)
	)
	(via
		(at 135.030532 76.65)
		(size 0.45)
		(drill 0.1)
		(layers "F.Cu" "B.Cu")
		(net 1)
	)
	(via
		(at 85.935532 123.395)
		(size 0.45)
		(drill 0.1)
		(layers "F.Cu" "B.Cu")
		(net 1)
	)
	(via
		(at 98.230532 78.15)
		(size 0.45)
		(drill 0.1)
		(layers "F.Cu" "B.Cu")
		(net 1)
	)
	(via
		(at 207.6 136.35)
		(size 0.45)
		(drill 0.1)
		(layers "F.Cu" "B.Cu")
		(net 1)
	)
	(via
		(at 73.235532 114.505)
		(size 0.45)
		(drill 0.1)
		(layers "F.Cu" "B.Cu")
		(net 1)
	)
	(via
		(at 214.25 114.4)
		(size 0.45)
		(drill 0.1)
		(layers "F.Cu" "B.Cu")
		(net 1)
	)
	(via
		(at 113.530532 85.65)
		(size 0.45)
		(drill 0.1)
		(layers "F.Cu" "B.Cu")
		(net 1)
	)
	(via
		(at 181.1 111.95)
		(size 0.45)
		(drill 0.1)
		(layers "F.Cu" "B.Cu")
		(remove_unused_layers yes)
		(keep_end_layers yes)
		(free yes)
		(zone_layer_connections "In1.Cu" "In3.Cu" "In6.Cu" "In8.Cu")
		(net 1)
	)
	(via
		(at 80.855532 128.475)
		(size 0.45)
		(drill 0.1)
		(layers "F.Cu" "B.Cu")
		(net 1)
	)
	(via
		(at 220 100.7)
		(size 0.45)
		(drill 0.1)
		(layers "F.Cu" "B.Cu")
		(net 1)
	)
	(via
		(at 116.230532 85.65)
		(size 0.45)
		(drill 0.1)
		(layers "F.Cu" "B.Cu")
		(free yes)
		(net 1)
	)
	(via
		(at 71 131.5)
		(size 0.45)
		(drill 0.1)
		(layers "F.Cu" "B.Cu")
		(free yes)
		(net 1)
	)
	(via
		(at 182.04 127)
		(size 0.45)
		(drill 0.1)
		(layers "F.Cu" "B.Cu")
		(remove_unused_layers yes)
		(keep_end_layers yes)
		(free yes)
		(zone_layer_connections "In1.Cu" "In3.Cu" "In6.Cu" "In8.Cu")
		(net 1)
	)
	(via
		(at 180.55 111.95)
		(size 0.45)
		(drill 0.1)
		(layers "F.Cu" "B.Cu")
		(remove_unused_layers yes)
		(keep_end_layers yes)
		(free yes)
		(zone_layer_connections "In1.Cu" "In3.Cu" "In6.Cu" "In8.Cu")
		(net 1)
	)
	(via
		(at 212.5 133.75)
		(size 0.45)
		(drill 0.1)
		(layers "F.Cu" "B.Cu")
		(net 1)
	)
	(via
		(at 184.69 144.1)
		(size 0.45)
		(drill 0.1)
		(layers "F.Cu" "B.Cu")
		(remove_unused_layers yes)
		(keep_end_layers yes)
		(zone_layer_connections "In1.Cu" "In3.Cu" "In6.Cu" "In8.Cu")
		(net 1)
	)
	(via
		(at 204.476 144)
		(size 0.45)
		(drill 0.1)
		(layers "F.Cu" "B.Cu")
		(net 1)
	)
	(via
		(at 204.9 135.7)
		(size 0.45)
		(drill 0.1)
		(layers "F.Cu" "B.Cu")
		(net 1)
	)
	(via
		(at 101.530532 70.65)
		(size 0.45)
		(drill 0.1)
		(layers "F.Cu" "B.Cu")
		(net 1)
	)
	(via
		(at 169.6 91.4)
		(size 0.45)
		(drill 0.1)
		(layers "F.Cu" "B.Cu")
		(remove_unused_layers yes)
		(keep_end_layers yes)
		(free yes)
		(zone_layer_connections "In1.Cu" "In3.Cu" "In6.Cu" "In8.Cu")
		(net 1)
	)
	(via
		(at 123.530532 72.15)
		(size 0.45)
		(drill 0.1)
		(layers "F.Cu" "B.Cu")
		(net 1)
	)
	(via
		(at 62.7 89.5)
		(size 0.45)
		(drill 0.1)
		(layers "F.Cu" "B.Cu")
		(net 1)
	)
	(via
		(at 137.2 133.95)
		(size 0.45)
		(drill 0.1)
		(layers "F.Cu" "B.Cu")
		(net 1)
	)
	(via
		(at 96.230532 82.65)
		(size 0.45)
		(drill 0.1)
		(layers "F.Cu" "B.Cu")
		(net 1)
	)
	(via
		(at 235.37 115.2)
		(size 0.45)
		(drill 0.1)
		(layers "F.Cu" "B.Cu")
		(net 1)
	)
	(via
		(at 100.230532 70.65)
		(size 0.45)
		(drill 0.1)
		(layers "F.Cu" "B.Cu")
		(net 1)
	)
	(via
		(at 175.15 81.45)
		(size 0.45)
		(drill 0.1)
		(layers "F.Cu" "B.Cu")
		(remove_unused_layers yes)
		(keep_end_layers yes)
		(free yes)
		(zone_layer_connections "In1.Cu" "In3.Cu" "In6.Cu" "In8.Cu")
		(net 1)
	)
	(via
		(at 237.2 133)
		(size 0.45)
		(drill 0.1)
		(layers "F.Cu" "B.Cu")
		(net 1)
	)
	(via
		(at 70.695532 100.535)
		(size 0.45)
		(drill 0.1)
		(layers "F.Cu" "B.Cu")
		(net 1)
	)
	(via
		(at 169.404468 134.56)
		(size 0.45)
		(drill 0.1)
		(layers "F.Cu" "B.Cu")
		(remove_unused_layers yes)
		(keep_end_layers yes)
		(zone_layer_connections "In1.Cu" "In3.Cu" "In6.Cu" "In8.Cu")
		(net 1)
	)
	(via
		(at 199.2 85.3)
		(size 0.45)
		(drill 0.1)
		(layers "F.Cu" "B.Cu")
		(net 1)
	)
	(via
		(at 145.3 60.4)
		(size 0.45)
		(drill 0.1)
		(layers "F.Cu" "B.Cu")
		(net 1)
	)
	(via
		(at 229.97 78.6)
		(size 0.45)
		(drill 0.1)
		(layers "F.Cu" "B.Cu")
		(net 1)
	)
	(via
		(at 69.425532 78.945)
		(size 0.45)
		(drill 0.1)
		(layers "F.Cu" "B.Cu")
		(net 1)
	)
	(via
		(at 93.530532 76.65)
		(size 0.45)
		(drill 0.1)
		(layers "F.Cu" "B.Cu")
		(net 1)
	)
	(via
		(at 202.6 86.6)
		(size 0.45)
		(drill 0.1)
		(layers "F.Cu" "B.Cu")
		(net 1)
	)
	(via
		(at 133.430532 81.15)
		(size 0.45)
		(drill 0.1)
		(layers "F.Cu" "B.Cu")
		(net 1)
	)
	(via
		(at 126.230532 72.15)
		(size 0.45)
		(drill 0.1)
		(layers "F.Cu" "B.Cu")
		(net 1)
	)
	(via
		(at 78.315532 91.645)
		(size 0.45)
		(drill 0.1)
		(layers "F.Cu" "B.Cu")
		(net 1)
	)
	(via
		(at 130.730532 81.15)
		(size 0.45)
		(drill 0.1)
		(layers "F.Cu" "B.Cu")
		(net 1)
	)
	(via
		(at 104.230532 70.7)
		(size 0.45)
		(drill 0.1)
		(layers "F.Cu" "B.Cu")
		(net 1)
	)
	(via
		(at 178.3 111.95)
		(size 0.45)
		(drill 0.1)
		(layers "F.Cu" "B.Cu")
		(remove_unused_layers yes)
		(keep_end_layers yes)
		(free yes)
		(zone_layer_connections "In1.Cu" "In3.Cu" "In6.Cu" "In8.Cu")
		(net 1)
	)
	(via
		(at 193.4 63.05)
		(size 0.45)
		(drill 0.1)
		(layers "F.Cu" "B.Cu")
		(net 1)
	)
	(via
		(at 108.230532 82.65)
		(size 0.45)
		(drill 0.1)
		(layers "F.Cu" "B.Cu")
		(net 1)
	)
	(via
		(at 63.5 102.825)
		(size 0.45)
		(drill 0.1)
		(layers "F.Cu" "B.Cu")
		(net 1)
	)
	(via
		(at 114.230532 84.15)
		(size 0.45)
		(drill 0.1)
		(layers "F.Cu" "B.Cu")
		(net 1)
	)
	(via
		(at 170.35 89.9)
		(size 0.45)
		(drill 0.1)
		(layers "F.Cu" "B.Cu")
		(remove_unused_layers yes)
		(keep_end_layers yes)
		(free yes)
		(zone_layer_connections "In1.Cu" "In3.Cu" "In6.Cu" "In8.Cu")
		(net 1)
	)
	(via
		(at 82.125532 100.535)
		(size 0.45)
		(drill 0.1)
		(layers "F.Cu" "B.Cu")
		(net 1)
	)
	(via
		(at 108.27 85.63)
		(size 0.45)
		(drill 0.1)
		(layers "F.Cu" "B.Cu")
		(free yes)
		(net 1)
	)
	(via
		(at 201.35 63.3)
		(size 0.45)
		(drill 0.1)
		(layers "F.Cu" "B.Cu")
		(net 1)
	)
	(via
		(at 204.965 117.4)
		(size 0.45)
		(drill 0.1)
		(layers "F.Cu" "B.Cu")
		(net 1)
	)
	(via
		(at 102.230532 72.15)
		(size 0.45)
		(drill 0.1)
		(layers "F.Cu" "B.Cu")
		(net 1)
	)
	(via
		(at 92.4 111.1)
		(size 0.45)
		(drill 0.1)
		(layers "F.Cu" "B.Cu")
		(net 1)
	)
	(via
		(at 231 125.1)
		(size 0.45)
		(drill 0.1)
		(layers "F.Cu" "B.Cu")
		(net 1)
	)
	(via
		(at 171.35 81)
		(size 0.45)
		(drill 0.1)
		(layers "F.Cu" "B.Cu")
		(remove_unused_layers yes)
		(keep_end_layers yes)
		(free yes)
		(zone_layer_connections "In1.Cu" "In3.Cu" "In6.Cu" "In8.Cu")
		(net 1)
	)
	(via
		(at 95.25 61.7)
		(size 0.45)
		(drill 0.1)
		(layers "F.Cu" "B.Cu")
		(net 1)
	)
	(via
		(at 233.27 112.4)
		(size 0.45)
		(drill 0.1)
		(layers "F.Cu" "B.Cu")
		(net 1)
	)
	(via
		(at 94 110.6)
		(size 0.45)
		(drill 0.1)
		(layers "F.Cu" "B.Cu")
		(net 1)
	)
	(via
		(at 85.935532 114.505)
		(size 0.45)
		(drill 0.1)
		(layers "F.Cu" "B.Cu")
		(net 1)
	)
	(via
		(at 97 146.25)
		(size 0.45)
		(drill 0.1)
		(layers "F.Cu" "B.Cu")
		(free yes)
		(net 1)
	)
	(via
		(at 108.230532 70.65)
		(size 0.45)
		(drill 0.1)
		(layers "F.Cu" "B.Cu")
		(net 1)
	)
	(via
		(at 67.1 84.7)
		(size 0.45)
		(drill 0.1)
		(layers "F.Cu" "B.Cu")
		(net 1)
	)
	(via
		(at 73.235532 95.455)
		(size 0.45)
		(drill 0.1)
		(layers "F.Cu" "B.Cu")
		(net 1)
	)
	(via
		(at 154.675 105.01)
		(size 0.45)
		(drill 0.1)
		(layers "F.Cu" "B.Cu")
		(net 1)
	)
	(via
		(at 166.87 70.5)
		(size 0.45)
		(drill 0.1)
		(layers "F.Cu" "B.Cu")
		(remove_unused_layers yes)
		(keep_end_layers yes)
		(free yes)
		(zone_layer_connections "In1.Cu" "In3.Cu" "In6.Cu" "In8.Cu")
		(net 1)
	)
	(via
		(at 91.5 146.64)
		(size 0.45)
		(drill 0.1)
		(layers "F.Cu" "B.Cu")
		(net 1)
	)
	(via
		(at 113.530532 79.65)
		(size 0.45)
		(drill 0.1)
		(layers "F.Cu" "B.Cu")
		(net 1)
	)
	(via
		(at 74.505532 115.775)
		(size 0.45)
		(drill 0.1)
		(layers "F.Cu" "B.Cu")
		(net 1)
	)
	(via
		(at 233.77 92)
		(size 0.45)
		(drill 0.1)
		(layers "F.Cu" "B.Cu")
		(net 1)
	)
	(via
		(at 70.695532 111.965)
		(size 0.45)
		(drill 0.1)
		(layers "F.Cu" "B.Cu")
		(net 1)
	)
	(via
		(at 170.15 111.4)
		(size 0.45)
		(drill 0.1)
		(layers "F.Cu" "B.Cu")
		(remove_unused_layers yes)
		(keep_end_layers yes)
		(free yes)
		(zone_layer_connections "In1.Cu" "In3.Cu" "In6.Cu" "In8.Cu")
		(net 1)
	)
	(via
		(at 185.25 54.6)
		(size 0.45)
		(drill 0.1)
		(layers "F.Cu" "B.Cu")
		(net 1)
	)
	(via
		(at 231.5 86.55)
		(size 0.45)
		(drill 0.1)
		(layers "F.Cu" "B.Cu")
		(net 1)
	)
	(via
		(at 117.530532 70.65)
		(size 0.45)
		(drill 0.1)
		(layers "F.Cu" "B.Cu")
		(net 1)
	)
	(via
		(at 144.030532 73.65)
		(size 0.45)
		(drill 0.1)
		(layers "F.Cu" "B.Cu")
		(net 1)
	)
	(via
		(at 175.25 89.9)
		(size 0.45)
		(drill 0.1)
		(layers "F.Cu" "B.Cu")
		(remove_unused_layers yes)
		(keep_end_layers yes)
		(free yes)
		(zone_layer_connections "In1.Cu" "In3.Cu" "In6.Cu" "In8.Cu")
		(net 1)
	)
	(via
		(at 102.230532 81.15)
		(size 0.45)
		(drill 0.1)
		(layers "F.Cu" "B.Cu")
		(free yes)
		(net 1)
	)
	(via
		(at 83.395532 118.315)
		(size 0.45)
		(drill 0.1)
		(layers "F.Cu" "B.Cu")
		(net 1)
	)
	(via
		(at 97 139.75)
		(size 0.45)
		(drill 0.1)
		(layers "F.Cu" "B.Cu")
		(free yes)
		(net 1)
	)
	(via
		(at 219.946 152.2)
		(size 0.45)
		(drill 0.1)
		(layers "F.Cu" "B.Cu")
		(net 1)
	)
	(via
		(at 172.5 123.95)
		(size 0.45)
		(drill 0.1)
		(layers "F.Cu" "B.Cu")
		(remove_unused_layers yes)
		(keep_end_layers yes)
		(zone_layer_connections "In1.Cu" "In3.Cu" "In6.Cu" "In8.Cu")
		(net 1)
	)
	(via
		(at 106.230532 78.15)
		(size 0.45)
		(drill 0.1)
		(layers "F.Cu" "B.Cu")
		(net 1)
	)
	(via
		(at 217.3 83.2)
		(size 0.45)
		(drill 0.1)
		(layers "F.Cu" "B.Cu")
		(net 1)
	)
	(via
		(at 109.530532 70.65)
		(size 0.45)
		(drill 0.1)
		(layers "F.Cu" "B.Cu")
		(net 1)
	)
	(via
		(at 89.25 63.5)
		(size 0.45)
		(drill 0.1)
		(layers "F.Cu" "B.Cu")
		(net 1)
	)
	(via
		(at 199.75 62.9)
		(size 0.45)
		(drill 0.1)
		(layers "F.Cu" "B.Cu")
		(net 1)
	)
	(via
		(at 235.5 128.2)
		(size 0.45)
		(drill 0.1)
		(layers "F.Cu" "B.Cu")
		(net 1)
	)
	(via
		(at 120.230532 76.65)
		(size 0.45)
		(drill 0.1)
		(layers "F.Cu" "B.Cu")
		(net 1)
	)
	(via
		(at 172.37 143.93)
		(size 0.45)
		(drill 0.1)
		(layers "F.Cu" "B.Cu")
		(remove_unused_layers yes)
		(keep_end_layers yes)
		(free yes)
		(zone_layer_connections "In1.Cu" "In3.Cu" "In6.Cu" "In8.Cu")
		(net 1)
	)
	(via
		(at 106.230532 72.15)
		(size 0.45)
		(drill 0.1)
		(layers "F.Cu" "B.Cu")
		(net 1)
	)
	(via
		(at 191.8 125.45)
		(size 0.45)
		(drill 0.1)
		(layers "F.Cu" "B.Cu")
		(remove_unused_layers yes)
		(keep_end_layers yes)
		(zone_layer_connections "In1.Cu" "In3.Cu" "In6.Cu" "In8.Cu")
		(net 1)
	)
	(via
		(at 221.212 57.78)
		(size 0.45)
		(drill 0.1)
		(layers "F.Cu" "B.Cu")
		(net 1)
	)
	(via
		(at 205.706 150.6)
		(size 0.45)
		(drill 0.1)
		(layers "F.Cu" "B.Cu")
		(net 1)
	)
	(via
		(at 63.4 104.5)
		(size 0.45)
		(drill 0.1)
		(layers "F.Cu" "B.Cu")
		(net 1)
	)
	(via
		(at 165.36 92.695856)
		(size 0.45)
		(drill 0.1)
		(layers "F.Cu" "B.Cu")
		(remove_unused_layers yes)
		(keep_end_layers yes)
		(free yes)
		(zone_layer_connections "In1.Cu" "In3.Cu" "In6.Cu" "In8.Cu")
		(net 1)
	)
	(via
		(at 92.5 108.1)
		(size 0.45)
		(drill 0.1)
		(layers "F.Cu" "B.Cu")
		(net 1)
	)
	(via
		(at 71.965532 85.295)
		(size 0.45)
		(drill 0.1)
		(layers "F.Cu" "B.Cu")
		(net 1)
	)
	(via
		(at 181.5 110.55)
		(size 0.45)
		(drill 0.1)
		(layers "F.Cu" "B.Cu")
		(remove_unused_layers yes)
		(keep_end_layers yes)
		(free yes)
		(zone_layer_connections "In1.Cu" "In3.Cu" "In6.Cu" "In8.Cu")
		(net 1)
	)
	(via
		(at 202.6 88.35)
		(size 0.45)
		(drill 0.1)
		(layers "F.Cu" "B.Cu")
		(net 1)
	)
	(via
		(at 104.230532 76.65)
		(size 0.45)
		(drill 0.1)
		(layers "F.Cu" "B.Cu")
		(free yes)
		(net 1)
	)
	(via
		(at 113.8 81.9)
		(size 0.45)
		(drill 0.1)
		(layers "F.Cu" "B.Cu")
		(net 1)
	)
	(via
		(at 236.2 94)
		(size 0.45)
		(drill 0.1)
		(layers "F.Cu" "B.Cu")
		(net 1)
	)
	(via
		(at 174.91 89.545856)
		(size 0.45)
		(drill 0.1)
		(layers "F.Cu" "B.Cu")
		(remove_unused_layers yes)
		(keep_end_layers yes)
		(free yes)
		(zone_layer_connections "In1.Cu" "In3.Cu" "In6.Cu" "In8.Cu")
		(net 1)
	)
	(via
		(at 125.3 58.71)
		(size 0.45)
		(drill 0.1)
		(layers "F.Cu" "B.Cu")
		(net 1)
	)
	(via
		(at 69.425532 87.835)
		(size 0.45)
		(drill 0.1)
		(layers "F.Cu" "B.Cu")
		(net 1)
	)
	(via
		(at 235.47 125.8)
		(size 0.45)
		(drill 0.1)
		(layers "F.Cu" "B.Cu")
		(net 1)
	)
	(via
		(at 69.425532 104.345)
		(size 0.45)
		(drill 0.1)
		(layers "F.Cu" "B.Cu")
		(net 1)
	)
	(via
		(at 70.695532 85.295)
		(size 0.45)
		(drill 0.1)
		(layers "F.Cu" "B.Cu")
		(net 1)
	)
	(via
		(at 167.73 80.31)
		(size 0.45)
		(drill 0.1)
		(layers "F.Cu" "B.Cu")
		(remove_unused_layers yes)
		(keep_end_layers yes)
		(free yes)
		(zone_layer_connections "In1.Cu" "In3.Cu" "In6.Cu" "In8.Cu")
		(net 1)
	)
	(via
		(at 92.25 99.95)
		(size 0.45)
		(drill 0.1)
		(layers "F.Cu" "B.Cu")
		(net 1)
	)
	(via
		(at 216.6 83.2)
		(size 0.45)
		(drill 0.1)
		(layers "F.Cu" "B.Cu")
		(net 1)
	)
	(via
		(at 224 91.3)
		(size 0.45)
		(drill 0.1)
		(layers "F.Cu" "B.Cu")
		(net 1)
	)
	(via
		(at 62.8 107.5)
		(size 0.45)
		(drill 0.1)
		(layers "F.Cu" "B.Cu")
		(net 1)
	)
	(via
		(at 171.9 80.45)
		(size 0.45)
		(drill 0.1)
		(layers "F.Cu" "B.Cu")
		(remove_unused_layers yes)
		(keep_end_layers yes)
		(free yes)
		(zone_layer_connections "In1.Cu" "In3.Cu" "In6.Cu" "In8.Cu")
		(net 1)
	)
	(via
		(at 173.21 92.645856)
		(size 0.45)
		(drill 0.1)
		(layers "F.Cu" "B.Cu")
		(remove_unused_layers yes)
		(keep_end_layers yes)
		(free yes)
		(zone_layer_connections "In1.Cu" "In3.Cu" "In6.Cu" "In8.Cu")
		(net 1)
	)
	(via
		(at 191 128.9)
		(size 0.45)
		(drill 0.1)
		(layers "F.Cu" "B.Cu")
		(remove_unused_layers yes)
		(keep_end_layers yes)
		(zone_layer_connections "In1.Cu" "In3.Cu" "In6.Cu" "In8.Cu")
		(net 1)
	)
	(via
		(at 98.5 139.75)
		(size 0.45)
		(drill 0.1)
		(layers "F.Cu" "B.Cu")
		(free yes)
		(net 1)
	)
	(via
		(at 122.230532 81.15)
		(size 0.45)
		(drill 0.1)
		(layers "F.Cu" "B.Cu")
		(net 1)
	)
	(via
		(at 94.05 95.75)
		(size 0.45)
		(drill 0.1)
		(layers "F.Cu" "B.Cu")
		(net 1)
	)
	(via
		(at 73.235532 87.835)
		(size 0.45)
		(drill 0.1)
		(layers "F.Cu" "B.Cu")
		(net 1)
	)
	(via
		(at 60.6 85.9)
		(size 0.45)
		(drill 0.1)
		(layers "F.Cu" "B.Cu")
		(net 1)
	)
	(via
		(at 127.8 141.8)
		(size 0.45)
		(drill 0.1)
		(layers "F.Cu" "B.Cu")
		(net 1)
	)
	(via
		(at 75.775532 110.695)
		(size 0.45)
		(drill 0.1)
		(layers "F.Cu" "B.Cu")
		(net 1)
	)
	(via
		(at 135.030532 82.65)
		(size 0.45)
		(drill 0.1)
		(layers "F.Cu" "B.Cu")
		(net 1)
	)
	(via
		(at 97.75 146.25)
		(size 0.45)
		(drill 0.1)
		(layers "F.Cu" "B.Cu")
		(free yes)
		(net 1)
	)
	(via
		(at 170.45 127.8)
		(size 0.45)
		(drill 0.1)
		(layers "F.Cu" "B.Cu")
		(remove_unused_layers yes)
		(keep_end_layers yes)
		(free yes)
		(zone_layer_connections "In1.Cu" "In3.Cu" "In6.Cu" "In8.Cu")
		(net 1)
	)
	(via
		(at 173.7 80.55)
		(size 0.45)
		(drill 0.1)
		(layers "F.Cu" "B.Cu")
		(remove_unused_layers yes)
		(keep_end_layers yes)
		(free yes)
		(zone_layer_connections "In1.Cu" "In3.Cu" "In6.Cu" "In8.Cu")
		(net 1)
	)
	(via
		(at 66.5 153)
		(size 0.45)
		(drill 0.1)
		(layers "F.Cu" "B.Cu")
		(free yes)
		(net 1)
	)
	(via
		(at 100.230532 85.65)
		(size 0.45)
		(drill 0.1)
		(layers "F.Cu" "B.Cu")
		(free yes)
		(net 1)
	)
	(via
		(at 170.45 81.9)
		(size 0.45)
		(drill 0.1)
		(layers "F.Cu" "B.Cu")
		(remove_unused_layers yes)
		(keep_end_layers yes)
		(free yes)
		(zone_layer_connections "In1.Cu" "In3.Cu" "In6.Cu" "In8.Cu")
		(net 1)
	)
	(via
		(at 71 147)
		(size 0.45)
		(drill 0.1)
		(layers "F.Cu" "B.Cu")
		(free yes)
		(net 1)
	)
	(via
		(at 112.5 120.25)
		(size 0.45)
		(drill 0.1)
		(layers "F.Cu" "B.Cu")
		(net 1)
	)
	(via
		(at 91.930532 84.15)
		(size 0.45)
		(drill 0.1)
		(layers "F.Cu" "B.Cu")
		(net 1)
	)
	(via
		(at 100.25 63.5)
		(size 0.45)
		(drill 0.1)
		(layers "F.Cu" "B.Cu")
		(net 1)
	)
	(via
		(at 97.530532 79.65)
		(size 0.45)
		(drill 0.1)
		(layers "F.Cu" "B.Cu")
		(net 1)
	)
	(via
		(at 172.84 89.9)
		(size 0.45)
		(drill 0.1)
		(layers "F.Cu" "B.Cu")
		(remove_unused_layers yes)
		(keep_end_layers yes)
		(free yes)
		(zone_layer_connections "In1.Cu" "In3.Cu" "In6.Cu" "In8.Cu")
		(net 1)
	)
	(via
		(at 112.6 131.3)
		(size 0.45)
		(drill 0.1)
		(layers "F.Cu" "B.Cu")
		(net 1)
	)
	(via
		(at 202 122.5)
		(size 0.45)
		(drill 0.1)
		(layers "F.Cu" "B.Cu")
		(net 1)
	)
	(via
		(at 180.94 127.55)
		(size 0.45)
		(drill 0.1)
		(layers "F.Cu" "B.Cu")
		(remove_unused_layers yes)
		(keep_end_layers yes)
		(free yes)
		(zone_layer_connections "In1.Cu" "In3.Cu" "In6.Cu" "In8.Cu")
		(net 1)
	)
	(via
		(at 203.1 117.4)
		(size 0.45)
		(drill 0.1)
		(layers "F.Cu" "B.Cu")
		(net 1)
	)
	(via
		(at 206.75 60.25)
		(size 0.45)
		(drill 0.1)
		(layers "F.Cu" "B.Cu")
		(net 1)
	)
	(via
		(at 98.5 147)
		(size 0.45)
		(drill 0.1)
		(layers "F.Cu" "B.Cu")
		(free yes)
		(net 1)
	)
	(via
		(at 192.1 66.1)
		(size 0.45)
		(drill 0.1)
		(layers "F.Cu" "B.Cu")
		(net 1)
	)
	(via
		(at 159.2 144.2)
		(size 0.45)
		(drill 0.1)
		(layers "F.Cu" "B.Cu")
		(net 1)
	)
	(via
		(at 71.965532 92.915)
		(size 0.45)
		(drill 0.1)
		(layers "F.Cu" "B.Cu")
		(net 1)
	)
	(via
		(at 94.3 90)
		(size 0.45)
		(drill 0.1)
		(layers "F.Cu" "B.Cu")
		(net 1)
	)
	(via
		(at 93.3 94.2)
		(size 0.45)
		(drill 0.1)
		(layers "F.Cu" "B.Cu")
		(net 1)
	)
	(via
		(at 179.6 86.425)
		(size 0.45)
		(drill 0.1)
		(layers "F.Cu" "B.Cu")
		(remove_unused_layers yes)
		(keep_end_layers yes)
		(zone_layer_connections "In1.Cu" "In3.Cu" "In6.Cu" "In8.Cu")
		(net 1)
	)
	(via
		(at 222.2 114.55)
		(size 0.45)
		(drill 0.1)
		(layers "F.Cu" "B.Cu")
		(net 1)
	)
	(via
		(at 93.1 100.15)
		(size 0.45)
		(drill 0.1)
		(layers "F.Cu" "B.Cu")
		(net 1)
	)
	(via
		(at 65.7 103.4)
		(size 0.45)
		(drill 0.1)
		(layers "F.Cu" "B.Cu")
		(net 1)
	)
	(via
		(at 210.925 97.125)
		(size 0.45)
		(drill 0.1)
		(layers "F.Cu" "B.Cu")
		(net 1)
	)
	(via
		(at 118.230532 84.15)
		(size 0.45)
		(drill 0.1)
		(layers "F.Cu" "B.Cu")
		(net 1)
	)
	(via
		(at 226.1 80.25)
		(size 0.45)
		(drill 0.1)
		(layers "F.Cu" "B.Cu")
		(net 1)
	)
	(via
		(at 71.965532 119.585)
		(size 0.45)
		(drill 0.1)
		(layers "F.Cu" "B.Cu")
		(net 1)
	)
	(via
		(at 79.585532 113.235)
		(size 0.45)
		(drill 0.1)
		(layers "F.Cu" "B.Cu")
		(net 1)
	)
	(via
		(at 69.425532 103.075)
		(size 0.45)
		(drill 0.1)
		(layers "F.Cu" "B.Cu")
		(net 1)
	)
	(via
		(at 62 127)
		(size 0.45)
		(drill 0.1)
		(layers "F.Cu" "B.Cu")
		(free yes)
		(net 1)
	)
	(via
		(at 138.55 133.95)
		(size 0.45)
		(drill 0.1)
		(layers "F.Cu" "B.Cu")
		(net 1)
	)
	(via
		(at 83.395532 99.265)
		(size 0.45)
		(drill 0.1)
		(layers "F.Cu" "B.Cu")
		(net 1)
	)
	(via
		(at 85.935532 99.265)
		(size 0.45)
		(drill 0.1)
		(layers "F.Cu" "B.Cu")
		(net 1)
	)
	(via
		(at 95.25 146.25)
		(size 0.45)
		(drill 0.1)
		(layers "F.Cu" "B.Cu")
		(free yes)
		(net 1)
	)
	(via
		(at 92.7 108.6)
		(size 0.45)
		(drill 0.1)
		(layers "F.Cu" "B.Cu")
		(net 1)
	)
	(via
		(at 60.6 135)
		(size 0.45)
		(drill 0.1)
		(layers "F.Cu" "B.Cu")
		(free yes)
		(net 1)
	)
	(via
		(at 206.52 61.512999)
		(size 0.45)
		(drill 0.1)
		(layers "F.Cu" "B.Cu")
		(net 1)
	)
	(via
		(at 114.5 139.75)
		(size 0.45)
		(drill 0.1)
		(layers "F.Cu" "B.Cu")
		(net 1)
	)
	(via
		(at 83.395532 84.025)
		(size 0.45)
		(drill 0.1)
		(layers "F.Cu" "B.Cu")
		(net 1)
	)
	(via
		(at 119.530532 81.15)
		(size 0.45)
		(drill 0.1)
		(layers "F.Cu" "B.Cu")
		(net 1)
	)
	(via
		(at 111.530532 75.15)
		(size 0.45)
		(drill 0.1)
		(layers "F.Cu" "B.Cu")
		(net 1)
	)
	(via
		(at 75.775532 87.835)
		(size 0.45)
		(drill 0.1)
		(layers "F.Cu" "B.Cu")
		(net 1)
	)
	(via
		(at 186.7 121.6)
		(size 0.45)
		(drill 0.1)
		(layers "F.Cu" "B.Cu")
		(net 1)
	)
	(via
		(at 115.530532 81.15)
		(size 0.45)
		(drill 0.1)
		(layers "F.Cu" "B.Cu")
		(net 1)
	)
	(via
		(at 177.2 93)
		(size 0.45)
		(drill 0.1)
		(layers "F.Cu" "B.Cu")
		(remove_unused_layers yes)
		(keep_end_layers yes)
		(free yes)
		(zone_layer_connections "In1.Cu" "In3.Cu" "In6.Cu" "In8.Cu")
		(net 1)
	)
	(via
		(at 164.15 81.16)
		(size 0.45)
		(drill 0.1)
		(layers "F.Cu" "B.Cu")
		(remove_unused_layers yes)
		(keep_end_layers yes)
		(free yes)
		(zone_layer_connections "In1.Cu" "In3.Cu" "In6.Cu" "In8.Cu")
		(net 1)
	)
	(via
		(at 97 141.75)
		(size 0.45)
		(drill 0.1)
		(layers "F.Cu" "B.Cu")
		(free yes)
		(net 1)
	)
	(via
		(at 106.26 75.14)
		(size 0.45)
		(drill 0.1)
		(layers "F.Cu" "B.Cu")
		(net 1)
	)
	(via
		(at 165.93 81.15)
		(size 0.45)
		(drill 0.1)
		(layers "F.Cu" "B.Cu")
		(remove_unused_layers yes)
		(keep_end_layers yes)
		(free yes)
		(zone_layer_connections "In1.Cu" "In3.Cu" "In6.Cu" "In8.Cu")
		(net 1)
	)
	(via
		(at 97.75 141.75)
		(size 0.45)
		(drill 0.1)
		(layers "F.Cu" "B.Cu")
		(free yes)
		(net 1)
	)
	(via
		(at 111.380001 55.640001)
		(size 0.45)
		(drill 0.1)
		(layers "F.Cu" "B.Cu")
		(net 1)
	)
	(via
		(at 103.530532 78.15)
		(size 0.45)
		(drill 0.1)
		(layers "F.Cu" "B.Cu")
		(net 1)
	)
	(via
		(at 143.78 66.33)
		(size 0.45)
		(drill 0.1)
		(layers "F.Cu" "B.Cu")
		(net 1)
	)
	(via
		(at 171.26 143.94)
		(size 0.45)
		(drill 0.1)
		(layers "F.Cu" "B.Cu")
		(remove_unused_layers yes)
		(keep_end_layers yes)
		(free yes)
		(zone_layer_connections "In1.Cu" "In3.Cu" "In6.Cu" "In8.Cu")
		(net 1)
	)
	(via
		(at 84.665532 85.295)
		(size 0.45)
		(drill 0.1)
		(layers "F.Cu" "B.Cu")
		(net 1)
	)
	(via
		(at 78.315532 118.315)
		(size 0.45)
		(drill 0.1)
		(layers "F.Cu" "B.Cu")
		(net 1)
	)
	(via
		(at 94 97.1)
		(size 0.45)
		(drill 0.1)
		(layers "F.Cu" "B.Cu")
		(net 1)
	)
	(via
		(at 77.045532 80.215)
		(size 0.45)
		(drill 0.1)
		(layers "F.Cu" "B.Cu")
		(net 1)
	)
	(via
		(at 70.695532 127.205)
		(size 0.45)
		(drill 0.1)
		(layers "F.Cu" "B.Cu")
		(net 1)
	)
	(via
		(at 109.510001 55.640001)
		(size 0.45)
		(drill 0.1)
		(layers "F.Cu" "B.Cu")
		(net 1)
	)
	(via
		(at 104.230532 85.65)
		(size 0.45)
		(drill 0.1)
		(layers "F.Cu" "B.Cu")
		(free yes)
		(net 1)
	)
	(via
		(at 117.530532 79.65)
		(size 0.45)
		(drill 0.1)
		(layers "F.Cu" "B.Cu")
		(net 1)
	)
	(via
		(at 172.1 91.4)
		(size 0.45)
		(drill 0.1)
		(layers "F.Cu" "B.Cu")
		(remove_unused_layers yes)
		(keep_end_layers yes)
		(free yes)
		(zone_layer_connections "In1.Cu" "In3.Cu" "In6.Cu" "In8.Cu")
		(net 1)
	)
	(via
		(at 79.585532 124.665)
		(size 0.45)
		(drill 0.1)
		(layers "F.Cu" "B.Cu")
		(net 1)
	)
	(via
		(at 108.9 121.7)
		(size 0.45)
		(drill 0.1)
		(layers "F.Cu" "B.Cu")
		(net 1)
	)
	(via
		(at 70.695532 96.725)
		(size 0.45)
		(drill 0.1)
		(layers "F.Cu" "B.Cu")
		(net 1)
	)
	(via
		(at 208.6 102.55)
		(size 0.45)
		(drill 0.1)
		(layers "F.Cu" "B.Cu")
		(net 1)
	)
	(via
		(at 212.3 78)
		(size 0.45)
		(drill 0.1)
		(layers "F.Cu" "B.Cu")
		(net 1)
	)
	(via
		(at 177.35 70.95)
		(size 0.45)
		(drill 0.1)
		(layers "F.Cu" "B.Cu")
		(remove_unused_layers yes)
		(keep_end_layers yes)
		(free yes)
		(zone_layer_connections "In1.Cu" "In3.Cu" "In6.Cu" "In8.Cu")
		(net 1)
	)
	(via
		(at 118.45 88.1)
		(size 0.45)
		(drill 0.1)
		(layers "F.Cu" "B.Cu")
		(net 1)
	)
	(via
		(at 114.5 94.25)
		(size 0.45)
		(drill 0.1)
		(layers "F.Cu" "B.Cu")
		(net 1)
	)
	(via
		(at 179.9 144.02)
		(size 0.45)
		(drill 0.1)
		(layers "F.Cu" "B.Cu")
		(remove_unused_layers yes)
		(keep_end_layers yes)
		(free yes)
		(zone_layer_connections "In1.Cu" "In3.Cu" "In6.Cu" "In8.Cu")
		(net 1)
	)
	(via
		(at 112.5 101.761)
		(size 0.45)
		(drill 0.1)
		(layers "F.Cu" "B.Cu")
		(net 1)
	)
	(via
		(at 167.4 100.65)
		(size 0.45)
		(drill 0.1)
		(layers "F.Cu" "B.Cu")
		(remove_unused_layers yes)
		(keep_end_layers yes)
		(free yes)
		(zone_layer_connections "In1.Cu" "In3.Cu" "In6.Cu" "In8.Cu")
		(net 1)
	)
	(via
		(at 219.8 60)
		(size 0.45)
		(drill 0.1)
		(layers "F.Cu" "B.Cu")
		(net 1)
	)
	(via
		(at 173.53 70.02)
		(size 0.45)
		(drill 0.1)
		(layers "F.Cu" "B.Cu")
		(remove_unused_layers yes)
		(keep_end_layers yes)
		(free yes)
		(zone_layer_connections "In1.Cu" "In3.Cu" "In6.Cu" "In8.Cu")
		(net 1)
	)
	(via
		(at 84.665532 105.615)
		(size 0.45)
		(drill 0.1)
		(layers "F.Cu" "B.Cu")
		(net 1)
	)
	(via
		(at 122.7 126.3)
		(size 0.45)
		(drill 0.1)
		(layers "F.Cu" "B.Cu")
		(net 1)
	)
	(via
		(at 192.026 143.4)
		(size 0.45)
		(drill 0.1)
		(layers "F.Cu" "B.Cu")
		(free yes)
		(net 1)
	)
	(via
		(at 93.9 91.55)
		(size 0.45)
		(drill 0.1)
		(layers "F.Cu" "B.Cu")
		(net 1)
	)
	(via
		(at 170.58 111.84)
		(size 0.45)
		(drill 0.1)
		(layers "F.Cu" "B.Cu")
		(remove_unused_layers yes)
		(keep_end_layers yes)
		(free yes)
		(zone_layer_connections "In1.Cu" "In3.Cu" "In6.Cu" "In8.Cu")
		(net 1)
	)
	(via
		(at 85.935532 84.025)
		(size 0.45)
		(drill 0.1)
		(layers "F.Cu" "B.Cu")
		(net 1)
	)
	(via
		(at 110.230532 78.15)
		(size 0.45)
		(drill 0.1)
		(layers "F.Cu" "B.Cu")
		(net 1)
	)
	(via
		(at 191.576 143.75)
		(size 0.45)
		(drill 0.1)
		(layers "F.Cu" "B.Cu")
		(free yes)
		(net 1)
	)
	(via
		(at 91.930532 78.15)
		(size 0.45)
		(drill 0.1)
		(layers "F.Cu" "B.Cu")
		(net 1)
	)
	(via
		(at 138.830532 75.15)
		(size 0.45)
		(drill 0.1)
		(layers "F.Cu" "B.Cu")
		(net 1)
	)
	(via
		(at 111.22 59.090999)
		(size 0.45)
		(drill 0.1)
		(layers "F.Cu" "B.Cu")
		(net 1)
	)
	(via
		(at 212.6 118.3)
		(size 0.45)
		(drill 0.1)
		(layers "F.Cu" "B.Cu")
		(net 1)
	)
	(via
		(at 201.7 134.9)
		(size 0.45)
		(drill 0.1)
		(layers "F.Cu" "B.Cu")
		(net 1)
	)
	(via
		(at 144.030532 82.65)
		(size 0.45)
		(drill 0.1)
		(layers "F.Cu" "B.Cu")
		(net 1)
	)
	(via
		(at 83.395532 128.475)
		(size 0.45)
		(drill 0.1)
		(layers "F.Cu" "B.Cu")
		(net 1)
	)
	(via
		(at 219.9 102.45)
		(size 0.45)
		(drill 0.1)
		(layers "F.Cu" "B.Cu")
		(net 1)
	)
	(via
		(at 144.45 124.85)
		(size 0.45)
		(drill 0.1)
		(layers "F.Cu" "B.Cu")
		(remove_unused_layers yes)
		(keep_end_layers yes)
		(zone_layer_connections "In1.Cu" "In3.Cu" "In6.Cu" "In8.Cu")
		(net 1)
	)
	(via
		(at 112.5 104.761)
		(size 0.45)
		(drill 0.1)
		(layers "F.Cu" "B.Cu")
		(net 1)
	)
	(via
		(at 234.02 99.15)
		(size 0.45)
		(drill 0.1)
		(layers "F.Cu" "B.Cu")
		(net 1)
	)
	(via
		(at 209.976 141)
		(size 0.45)
		(drill 0.1)
		(layers "F.Cu" "B.Cu")
		(net 1)
	)
	(via
		(at 219.15 88.4)
		(size 0.45)
		(drill 0.1)
		(layers "F.Cu" "B.Cu")
		(net 1)
	)
	(via
		(at 112.5 132.75)
		(size 0.45)
		(drill 0.1)
		(layers "F.Cu" "B.Cu")
		(net 1)
	)
	(via
		(at 208.5 122.5)
		(size 0.45)
		(drill 0.1)
		(layers "F.Cu" "B.Cu")
		(net 1)
	)
	(via
		(at 71 153)
		(size 0.45)
		(drill 0.1)
		(layers "F.Cu" "B.Cu")
		(free yes)
		(net 1)
	)
	(via
		(at 85.935532 113.235)
		(size 0.45)
		(drill 0.1)
		(layers "F.Cu" "B.Cu")
		(net 1)
	)
	(via
		(at 84.665532 96.725)
		(size 0.45)
		(drill 0.1)
		(layers "F.Cu" "B.Cu")
		(net 1)
	)
	(via
		(at 109.530532 85.65)
		(size 0.45)
		(drill 0.1)
		(layers "F.Cu" "B.Cu")
		(net 1)
	)
	(via
		(at 207.326 148.3)
		(size 0.45)
		(drill 0.1)
		(layers "F.Cu" "B.Cu")
		(net 1)
	)
	(via
		(at 131.8 132.6)
		(size 0.45)
		(drill 0.1)
		(layers "F.Cu" "B.Cu")
		(net 1)
	)
	(via
		(at 109.530532 73.65)
		(size 0.45)
		(drill 0.1)
		(layers "F.Cu" "B.Cu")
		(net 1)
	)
	(via
		(at 121.530532 76.65)
		(size 0.45)
		(drill 0.1)
		(layers "F.Cu" "B.Cu")
		(net 1)
	)
	(via
		(at 112.230532 85.65)
		(size 0.45)
		(drill 0.1)
		(layers "F.Cu" "B.Cu")
		(free yes)
		(net 1)
	)
	(via
		(at 94.175 88.55)
		(size 0.45)
		(drill 0.1)
		(layers "F.Cu" "B.Cu")
		(net 1)
	)
	(segment
		(start 64.59 108.96)
		(end 65.6 108.96)
		(width 0.2)
		(layer "B.Cu")
		(net 1)
	)
	(segment
		(start 179.75 92)
		(end 179.2 91.45)
		(width 0.2)
		(layer "B.Cu")
		(net 1)
	)
	(segment
		(start 75.52 65.5)
		(end 74.9 65.5)
		(width 0.1)
		(layer "B.Cu")
		(net 1)
	)
	(segment
		(start 205.3 130.02)
		(end 205.3 129.1)
		(width 0.2)
		(layer "B.Cu")
		(net 1)
	)
	(segment
		(start 178.15 91.003)
		(end 178.15 90.053)
		(width 0.2)
		(layer "B.Cu")
		(net 1)
	)
	(segment
		(start 179.2 78.6)
		(end 179.2 79.6)
		(width 0.2)
		(layer "B.Cu")
		(net 1)
	)
	(segment
		(start 224.53 80.48)
		(end 224.7 80.65)
		(width 0.2)
		(layer "B.Cu")
		(net 1)
	)
	(segment
		(start 236.675 108.825)
		(end 236.9 108.6)
		(width 0.1)
		(layer "B.Cu")
		(net 1)
	)
	(segment
		(start 206.181001 144.012)
		(end 204.488 144.012)
		(width 0.1)
		(layer "B.Cu")
		(net 1)
	)
	(segment
		(start 100.5 58.82)
		(end 100.5 57.98)
		(width 0.2)
		(layer "B.Cu")
		(net 1)
	)
	(segment
		(start 227.700001 83)
		(end 228.300001 82.4)
		(width 0.5)
		(layer "B.Cu")
		(net 1)
	)
	(segment
		(start 64.59 101.461)
		(end 65.561 101.461)
		(width 0.2)
		(layer "B.Cu")
		(net 1)
	)
	(segment
		(start 124.230532 70.65)
		(end 124.230532 69.580532)
		(width 0.3)
		(layer "B.Cu")
		(net 1)
	)
	(segment
		(start 221.35 83.6)
		(end 221.4 83.65)
		(width 0.1)
		(layer "B.Cu")
		(net 1)
	)
	(segment
		(start 83.9 66.6)
		(end 84.100001 66.800001)
		(width 0.5)
		(layer "B.Cu")
		(net 1)
	)
	(segment
		(start 143.73 66.33)
		(end 143.6 66.2)
		(width 0.2)
		(layer "B.Cu")
		(net 1)
	)
	(segment
		(start 220.325 78.015)
		(end 220 78.34)
		(width 0.3)
		(layer "B.Cu")
		(net 1)
	)
	(segment
		(start 160.25 64.75)
		(end 160.4 64.75)
		(width 0.3)
		(layer "B.Cu")
		(net 1)
	)
	(segment
		(start 178.85 91.8)
		(end 179.2 91.45)
		(width 0.2)
		(layer "B.Cu")
		(net 1)
	)
	(segment
		(start 132.85 151.098)
		(end 133.698 151.098)
		(width 0.1)
		(layer "B.Cu")
		(net 1)
	)
	(segment
		(start 112.752 113.748)
		(end 112.5 114)
		(width 0.2)
		(layer "B.Cu")
		(net 1)
	)
	(segment
		(start 98.23 54.5)
		(end 99.1 54.5)
		(width 0.1)
		(layer "B.Cu")
		(net 1)
	)
	(segment
		(start 178.803 85.803)
		(end 179 86)
		(width 0.2)
		(layer "B.Cu")
		(net 1)
	)
	(segment
		(start 125.3 121.44)
		(end 126.16 121.44)
		(width 0.2)
		(layer "B.Cu")
		(net 1)
	)
	(segment
		(start 229.4 120.500001)
		(end 229.4 121.6)
		(width 0.5)
		(layer "B.Cu")
		(net 1)
	)
	(segment
		(start 179.2 91.45)
		(end 179.15 91.45)
		(width 0.2)
		(layer "B.Cu")
		(net 1)
	)
	(segment
		(start 224.33 94.85)
		(end 224.33 94.13)
		(width 0.1)
		(layer "B.Cu")
		(net 1)
	)
	(segment
		(start 113.711 134.26)
		(end 112.51 134.26)
		(width 0.2)
		(layer "B.Cu")
		(net 1)
	)
	(segment
		(start 99.1 125.400001)
		(end 99.1 126.4)
		(width 0.3)
		(layer "B.Cu")
		(net 1)
	)
	(segment
		(start 165.77 58.64)
		(end 165.77 58.99)
		(width 0.1)
		(layer "B.Cu")
		(net 1)
	)
	(segment
		(start 229.57 103.6)
		(end 229.07 104.1)
		(width 0.3)
		(layer "B.Cu")
		(net 1)
	)
	(segment
		(start 112.509 137.259)
		(end 112.5 137.25)
		(width 0.2)
		(layer "B.Cu")
		(net 1)
	)
	(segment
		(start 160.66 64.49)
		(end 161.02 64.49)
		(width 0.3)
		(layer "B.Cu")
		(net 1)
	)
	(segment
		(start 196.7 127.1)
		(end 196.75 127.05)
		(width 0.2)
		(layer "B.Cu")
		(net 1)
	)
	(segment
		(start 100.469 57.949)
		(end 100.5 57.98)
		(width 0.2)
		(layer "B.Cu")
		(net 1)
	)
	(segment
		(start 229.46 133.96)
		(end 229.48 133.94)
		(width 0.2)
		(layer "B.Cu")
		(net 1)
	)
	(segment
		(start 137.68 71.899468)
		(end 137.930532 72.15)
		(width 0.3)
		(layer "B.Cu")
		(net 1)
	)
	(segment
		(start 126.8345 150.1025)
		(end 126.593 150.344)
		(width 0.2)
		(layer "B.Cu")
		(net 1)
	)
	(segment
		(start 213.9 87.7)
		(end 214.38 87.7)
		(width 0.1)
		(layer "B.Cu")
		(net 1)
	)
	(segment
		(start 89.360532 75.28)
		(end 89.230532 75.15)
		(width 0.2)
		(layer "B.Cu")
		(net 1)
	)
	(segment
		(start 217.315 79.315)
		(end 217.3 79.3)
		(width 0.3)
		(layer "B.Cu")
		(net 1)
	)
	(segment
		(start 226.7 54.75)
		(end 227.7 54.75)
		(width 0.1)
		(layer "B.Cu")
		(net 1)
	)
	(segment
		(start 162.84 60.91)
		(end 162.75 61)
		(width 0.1)
		(layer "B.Cu")
		(net 1)
	)
	(segment
		(start 236.174 108.825)
		(end 236.675 108.825)
		(width 0.1)
		(layer "B.Cu")
		(net 1)
	)
	(segment
		(start 224.04 123.4)
		(end 224.5 122.94)
		(width 0.1)
		(layer "B.Cu")
		(net 1)
	)
	(segment
		(start 162.84 60.29)
		(end 161.822 60.29)
		(width 0.1)
		(layer "B.Cu")
		(net 1)
	)
	(segment
		(start 175.534998 60.576004)
		(end 175.568 60.543002)
		(width 0.1)
		(layer "B.Cu")
		(net 1)
	)
	(segment
		(start 179.272 86.753)
		(end 179.6 86.425)
		(width 0.2)
		(layer "B.Cu")
		(net 1)
	)
	(segment
		(start 63.6 107.46)
		(end 64.59 107.46)
		(width 0.25)
		(layer "B.Cu")
		(net 1)
	)
	(segment
		(start 160.58 69.59)
		(end 160.78 69.79)
		(width 0.3)
		(layer "B.Cu")
		(net 1)
	)
	(segment
		(start 141.93 55.13)
		(end 142 55.2)
		(width 0.3)
		(layer "B.Cu")
		(net 1)
	)
	(segment
		(start 126.16 121.44)
		(end 126.2 121.4)
		(width 0.2)
		(layer "B.Cu")
		(net 1)
	)
	(segment
		(start 112.51 132.76)
		(end 112.5 132.75)
		(width 0.2)
		(layer "B.Cu")
		(net 1)
	)
	(segment
		(start 120.2 143.1)
		(end 120.4 143.1)
		(width 0.3)
		(layer "B.Cu")
		(net 1)
	)
	(segment
		(start 198.905 96.4)
		(end 198.939 96.366)
		(width 0.1)
		(layer "B.Cu")
		(net 1)
	)
	(segment
		(start 207.8 80.8)
		(end 207.8 82.2)
		(width 0.1)
		(layer "B.Cu")
		(net 1)
	)
	(segment
		(start 179.55 89.65)
		(end 179.76 89.44)
		(width 0.2)
		(layer "B.Cu")
		(net 1)
	)
	(segment
		(start 112.51 121.76)
		(end 112.5 121.75)
		(width 0.2)
		(layer "B.Cu")
		(net 1)
	)
	(segment
		(start 84.100001 66.800001)
		(end 84.100001 67.2)
		(width 0.5)
		(layer "B.Cu")
		(net 1)
	)
	(segment
		(start 101.2 132.3)
		(end 100.9 132.6)
		(width 0.3)
		(layer "B.Cu")
		(net 1)
	)
	(segment
		(start 225.521 76.221)
		(end 225.5 76.2)
		(width 0.1)
		(layer "B.Cu")
		(net 1)
	)
	(segment
		(start 83.9 66.6)
		(end 83.9 66.2)
		(width 0.5)
		(layer "B.Cu")
		(net 1)
	)
	(segment
		(start 113.685 112.748)
		(end 112.748 112.748)
		(width 0.2)
		(layer "B.Cu")
		(net 1)
	)
	(segment
		(start 213.28 87.7)
		(end 213.9 87.7)
		(width 0.1)
		(layer "B.Cu")
		(net 1)
	)
	(segment
		(start 60.65 83.77)
		(end 60.65 82.66)
		(width 0.1)
		(layer "B.Cu")
		(net 1)
	)
	(segment
		(start 207.2 119)
		(end 206.9 118.7)
		(width 0.1)
		(layer "B.Cu")
		(net 1)
	)
	(segment
		(start 143.725 59.125)
		(end 143.725 60.658)
		(width 0.2)
		(layer "B.Cu")
		(net 1)
	)
	(segment
		(start 229.82 86.9)
		(end 229.82 87.87)
		(width 0.2)
		(layer "B.Cu")
		(net 1)
	)
	(segment
		(start 221.35 82.78)
		(end 221.35 83.6)
		(width 0.1)
		(layer "B.Cu")
		(net 1)
	)
	(segment
		(start 207.8 82.2)
		(end 207.8 83)
		(width 0.1)
		(layer "B.Cu")
		(net 1)
	)
	(segment
		(start 145.87 60.07)
		(end 145.63 60.07)
		(width 0.2)
		(layer "B.Cu")
		(net 1)
	)
	(segment
		(start 112.748 112.748)
		(end 112.5 112.5)
		(width 0.2)
		(layer "B.Cu")
		(net 1)
	)
	(segment
		(start 117.41 70.6)
		(end 117.41 69.480532)
		(width 0.3)
		(layer "B.Cu")
		(net 1)
	)
	(segment
		(start 220.325 76.44)
		(end 220.325 75.725)
		(width 0.3)
		(layer "B.Cu")
		(net 1)
	)
	(segment
		(start 112.502 113.248)
		(end 112.5 113.25)
		(width 0.2)
		(layer "B.Cu")
		(net 1)
	)
	(segment
		(start 201.3 130.02)
		(end 201.3 129.2)
		(width 0.2)
		(layer "B.Cu")
		(net 1)
	)
	(segment
		(start 108.250532 70.63)
		(end 108.230532 70.65)
		(width 0.3)
		(layer "B.Cu")
		(net 1)
	)
	(segment
		(start 60.8 83.92)
		(end 60.65 83.77)
		(width 0.1)
		(layer "B.Cu")
		(net 1)
	)
	(segment
		(start 60.65 81.45)
		(end 60.6 81.4)
		(width 0.1)
		(layer "B.Cu")
		(net 1)
	)
	(segment
		(start 178.85 93.1)
		(end 178.85 91.8)
		(width 0.2)
		(layer "B.Cu")
		(net 1)
	)
	(segment
		(start 206.656 59.491808)
		(end 206.642806 59.505002)
		(width 0.3)
		(layer "B.Cu")
		(net 1)
	)
	(segment
		(start 126.8345 149.027)
		(end 126.8345 150.1025)
		(width 0.2)
		(layer "B.Cu")
		(net 1)
	)
	(segment
		(start 143.6 66.2)
		(end 143.6 65.68)
		(width 0.2)
		(layer "B.Cu")
		(net 1)
	)
	(segment
		(start 126.8345 144.076)
		(end 126.8345 143.019)
		(width 0.2)
		(layer "B.Cu")
		(net 1)
	)
	(segment
		(start 230.25 108.65)
		(end 230.2 108.6)
		(width 0.3)
		(layer "B.Cu")
		(net 1)
	)
	(segment
		(start 102.48 62.48)
		(end 101.77 62.48)
		(width 0.2)
		(layer "B.Cu")
		(net 1)
	)
	(segment
		(start 198.93 64.82)
		(end 197.82 64.82)
		(width 0.2)
		(layer "B.Cu")
		(net 1)
	)
	(segment
		(start 214.38 87.7)
		(end 214.4 87.68)
		(width 0.1)
		(layer "B.Cu")
		(net 1)
	)
	(segment
		(start 145.63 60.07)
		(end 145.3 60.4)
		(width 0.2)
		(layer "B.Cu")
		(net 1)
	)
	(segment
		(start 122.609 124.509)
		(end 122.7 124.6)
		(width 0.15)
		(layer "B.Cu")
		(net 1)
	)
	(segment
		(start 129.8325 148.301)
		(end 128.0825 146.551)
		(width 0.2)
		(layer "B.Cu")
		(net 1)
	)
	(segment
		(start 145.6 65.68)
		(end 146.32 65.68)
		(width 0.2)
		(layer "B.Cu")
		(net 1)
	)
	(segment
		(start 113.711 121.76)
		(end 112.51 121.76)
		(width 0.2)
		(layer "B.Cu")
		(net 1)
	)
	(segment
		(start 199.126 146.3)
		(end 198.906 146.3)
		(width 0.2)
		(layer "B.Cu")
		(net 1)
	)
	(segment
		(start 178.84 81.96)
		(end 179.2 81.6)
		(width 0.2)
		(layer "B.Cu")
		(net 1)
	)
	(segment
		(start 236.209002 93.424001)
		(end 236.209002 93.990998)
		(width 0.2)
		(layer "B.Cu")
		(net 1)
	)
	(segment
		(start 149.93 55.13)
		(end 150 55.2)
		(width 0.3)
		(layer "B.Cu")
		(net 1)
	)
	(segment
		(start 147.84 147.46)
		(end 147.9 147.4)
		(width 0.2)
		(layer "B.Cu")
		(net 1)
	)
	(segment
		(start 230.396 121.996)
		(end 230 121.6)
		(width 0.2)
		(layer "B.Cu")
		(net 1)
	)
	(segment
		(start 238.575 83.545)
		(end 238.58 83.55)
		(width 0.2)
		(layer "B.Cu")
		(net 1)
	)
	(segment
		(start 120.26 70.59)
		(end 121.37 70.59)
		(width 0.3)
		(layer "B.Cu")
		(net 1)
	)
	(segment
		(start 229.95 89.98)
		(end 229.95 89.22)
		(width 0.15)
		(layer "B.Cu")
		(net 1)
	)
	(segment
		(start 220.325 75.725)
		(end 220.3 75.7)
		(width 0.3)
		(layer "B.Cu")
		(net 1)
	)
	(segment
		(start 64.59 110.46)
		(end 65.56 110.46)
		(width 0.2)
		(layer "B.Cu")
		(net 1)
	)
	(segment
		(start 109.44 70.63)
		(end 109.44 70.02)
		(width 0.3)
		(layer "B.Cu")
		(net 1)
	)
	(segment
		(start 123.1 143.1)
		(end 123.4 143.1)
		(width 0.3)
		(layer "B.Cu")
		(net 1)
	)
	(segment
		(start 115.465 119.16)
		(end 115.475 119.15)
		(width 0.2)
		(layer "B.Cu")
		(net 1)
	)
	(segment
		(start 228.606532 130.063468)
		(end 229.07 129.6)
		(width 0.2)
		(layer "B.Cu")
		(net 1)
	)
	(segment
		(start 218.1 79.315)
		(end 219.025 79.315)
		(width 0.3)
		(layer "B.Cu")
		(net 1)
	)
	(segment
		(start 149.93 55.105)
		(end 149.93 55.13)
		(width 0.3)
		(layer "B.Cu")
		(net 1)
	)
	(segment
		(start 220.679 112.019)
		(end 220.679 112.569)
		(width 0.1)
		(layer "B.Cu")
		(net 1)
	)
	(segment
		(start 228.67 116.6)
		(end 229.37 116.6)
		(width 0.1)
		(layer "B.Cu")
		(net 1)
	)
	(segment
		(start 125.3 97)
		(end 126.2 97)
		(width 0.2)
		(layer "B.Cu")
		(net 1)
	)
	(segment
		(start 236.28 97.38)
		(end 236.3 97.4)
		(width 0.2)
		(layer "B.Cu")
		(net 1)
	)
	(segment
		(start 95 55.02)
		(end 95 54.4)
		(width 0.1)
		(layer "B.Cu")
		(net 1)
	)
	(segment
		(start 122.9 144.28)
		(end 122.905 144.285)
		(width 0.3)
		(layer "B.Cu")
		(net 1)
	)
	(segment
		(start 174.55 62.883002)
		(end 175.534998 62.883002)
		(width 0.1)
		(layer "B.Cu")
		(net 1)
	)
	(segment
		(start 226.68 56.26)
		(end 227.69 56.26)
		(width 0.1)
		(layer "B.Cu")
		(net 1)
	)
	(segment
		(start 130.5575 148.301)
		(end 131.499 148.301)
		(width 0.2)
		(layer "B.Cu")
		(net 1)
	)
	(segment
		(start 220.3 75.7)
		(end 220.3 75.4)
		(width 0.2)
		(layer "B.Cu")
		(net 1)
	)
	(segment
		(start 229.46 133.94)
		(end 229.44 133.94)
		(width 0.5)
		(layer "B.Cu")
		(net 1)
	)
	(segment
		(start 135.8 66.4)
		(end 135.6 66.6)
		(width 0.2)
		(layer "B.Cu")
		(net 1)
	)
	(segment
		(start 122.905 143.305)
		(end 122.7 143.1)
		(width 0.3)
		(layer "B.Cu")
		(net 1)
	)
	(segment
		(start 207.35 131.35)
		(end 207.35 129.35)
		(width 0.2)
		(layer "B.Cu")
		(net 1)
	)
	(segment
		(start 211.02 73.51)
		(end 211.79 73.51)
		(width 0.3)
		(layer "B.Cu")
		(net 1)
	)
	(segment
		(start 120.26 70.52)
		(end 121.34 69.44)
		(width 0.3)
		(layer "B.Cu")
		(net 1)
	)
	(segment
		(start 235.75 70.502)
		(end 235.102 70.502)
		(width 0.2)
		(layer "B.Cu")
		(net 1)
	)
	(segment
		(start 114.459 119.16)
		(end 115.465 119.16)
		(width 0.2)
		(layer "B.Cu")
		(net 1)
	)
	(segment
		(start 127.0435 142.81)
		(end 127.0435 141.8)
		(width 0.2)
		(layer "B.Cu")
		(net 1)
	)
	(segment
		(start 217.539 111.461)
		(end 217.6 111.4)
		(width 0.1)
		(layer "B.Cu")
		(net 1)
	)
	(segment
		(start 85.935532 78.964468)
		(end 85.3 79.6)
		(width 0.3)
		(layer "B.Cu")
		(net 1)
	)
	(segment
		(start 114.459 139.791)
		(end 114.5 139.75)
		(width 0.2)
		(layer "B.Cu")
		(net 1)
	)
	(segment
		(start 207.8 82.2)
		(end 207.8 82.3)
		(width 0.1)
		(layer "B.Cu")
		(net 1)
	)
	(segment
		(start 228.97 100.9)
		(end 229.371 100.9)
		(width 0.2)
		(layer "B.Cu")
		(net 1)
	)
	(segment
		(start 160.58 67.49)
		(end 160.33 67.24)
		(width 0.3)
		(layer "B.Cu")
		(net 1)
	)
	(segment
		(start 198.906 146.3)
		(end 198.476 146.73)
		(width 0.2)
		(layer "B.Cu")
		(net 1)
	)
	(segment
		(start 200.226 145.95)
		(end 200.226 146.75)
		(width 0.2)
		(layer "B.Cu")
		(net 1)
	)
	(segment
		(start 105.095 58.32)
		(end 105.09 58.325)
		(width 0.2)
		(layer "B.Cu")
		(net 1)
	)
	(segment
		(start 134.8 54.5)
		(end 135.45 54.5)
		(width 0.1)
		(layer "B.Cu")
		(net 1)
	)
	(segment
		(start 201.28 123.22)
		(end 202 122.5)
		(width 0.2)
		(layer "B.Cu")
		(net 1)
	)
	(segment
		(start 229.59 126.9)
		(end 229.47 126.9)
		(width 0.2)
		(layer "B.Cu")
		(net 1)
	)
	(segment
		(start 234.85 61.975)
		(end 234.85 62.934468)
		(width 0.2)
		(layer "B.Cu")
		(net 1)
	)
	(segment
		(start 121.530532 70.65)
		(end 121.34 70.459468)
		(width 0.3)
		(layer "B.Cu")
		(net 1)
	)
	(segment
		(start 220.35 82.83)
		(end 220.3 82.78)
		(width 0.2)
		(layer "B.Cu")
		(net 1)
	)
	(segment
		(start 122.7 124.6)
		(end 122.7 126.3)
		(width 0.15)
		(layer "B.Cu")
		(net 1)
	)
	(segment
		(start 220.88 123.391698)
		(end 221.3 122.971698)
		(width 0.1)
		(layer "B.Cu")
		(net 1)
	)
	(segment
		(start 121.209 124.509)
		(end 122.609 124.509)
		(width 0.15)
		(layer "B.Cu")
		(net 1)
	)
	(segment
		(start 236.28 95.6)
		(end 236.28 96.6)
		(width 0.2)
		(layer "B.Cu")
		(net 1)
	)
	(segment
		(start 199.65 66.85)
		(end 199.65 67.78)
		(width 0.2)
		(layer "B.Cu")
		(net 1)
	)
	(segment
		(start 178.85 90)
		(end 178.85 88.85)
		(width 0.2)
		(layer "B.Cu")
		(net 1)
	)
	(segment
		(start 214.48 87.6)
		(end 214.4 87.68)
		(width 0.1)
		(layer "B.Cu")
		(net 1)
	)
	(segment
		(start 224.7 80.65)
		(end 225.15 80.65)
		(width 0.2)
		(layer "B.Cu")
		(net 1)
	)
	(segment
		(start 113.685 97.249)
		(end 112.512 97.249)
		(width 0.15)
		(layer "B.Cu")
		(net 1)
	)
	(segment
		(start 229.82 87.87)
		(end 229.69 88)
		(width 0.2)
		(layer "B.Cu")
		(net 1)
	)
	(segment
		(start 160.86 64.33)
		(end 161.02 64.49)
		(width 0.1)
		(layer "B.Cu")
		(net 1)
	)
	(segment
		(start 214.105 78.505)
		(end 213.8 78.2)
		(width 0.1)
		(layer "B.Cu")
		(net 1)
	)
	(segment
		(start 178.85 90)
		(end 179.2 90)
		(width 0.2)
		(layer "B.Cu")
		(net 1)
	)
	(segment
		(start 179.033 79.433)
		(end 179.2 79.6)
		(width 0.2)
		(layer "B.Cu")
		(net 1)
	)
	(segment
		(start 135.8 65.68)
		(end 135.8 66.4)
		(width 0.2)
		(layer "B.Cu")
		(net 1)
	)
	(segment
		(start 60.8 82.51)
		(end 60.65 82.36)
		(width 0.1)
		(layer "B.Cu")
		(net 1)
	)
	(segment
		(start 124.230532 69.580532)
		(end 124.17 69.52)
		(width 0.3)
		(layer "B.Cu")
		(net 1)
	)
	(segment
		(start 211.85 74.34)
		(end 211.02 73.51)
		(width 0.3)
		(layer "B.Cu")
		(net 1)
	)
	(segment
		(start 127.875 132.725)
		(end 127.875 133.525)
		(width 0.2)
		(layer "B.Cu")
		(net 1)
	)
	(segment
		(start 113.685 113.248)
		(end 112.502 113.248)
		(width 0.2)
		(layer "B.Cu")
		(net 1)
	)
	(segment
		(start 178.885 78.175)
		(end 178.885 78.285)
		(width 0.2)
		(layer "B.Cu")
		(net 1)
	)
	(segment
		(start 211.79 73.51)
		(end 212.12 73.18)
		(width 0.3)
		(layer "B.Cu")
		(net 1)
	)
	(segment
		(start 179.2 75.8)
		(end 179.2 75.2)
		(width 0.2)
		(layer "B.Cu")
		(net 1)
	)
	(segment
		(start 215.5 83.425)
		(end 215.8 83.125)
		(width 0.1)
		(layer "B.Cu")
		(net 1)
	)
	(segment
		(start 146.132 60.332)
		(end 145.87 60.07)
		(width 0.2)
		(layer "B.Cu")
		(net 1)
	)
	(segment
		(start 165.15 58.02)
		(end 165.77 58.64)
		(width 0.1)
		(layer "B.Cu")
		(net 1)
	)
	(segment
		(start 146.530532 147.46)
		(end 147.84 147.46)
		(width 0.2)
		(layer "B.Cu")
		(net 1)
	)
	(segment
		(start 178.197 91.05)
		(end 178.15 91.003)
		(width 0.2)
		(layer "B.Cu")
		(net 1)
	)
	(segment
		(start 74.9 65.5)
		(end 74.8 65.4)
		(width 0.1)
		(layer "B.Cu")
		(net 1)
	)
	(segment
		(start 199.89 68.02)
		(end 200.78 68.02)
		(width 0.2)
		(layer "B.Cu")
		(net 1)
	)
	(segment
		(start 225.002 109.85)
		(end 225.002 109.302)
		(width 0.1)
		(layer "B.Cu")
		(net 1)
	)
	(segment
		(start 145.63 58.98)
		(end 145.63 60.07)
		(width 0.2)
		(layer "B.Cu")
		(net 1)
	)
	(segment
		(start 119.095 143.305)
		(end 119.3 143.1)
		(width 0.3)
		(layer "B.Cu")
		(net 1)
	)
	(segment
		(start 198.9 96.4)
		(end 198.905 96.4)
		(width 0.1)
		(layer "B.Cu")
		(net 1)
	)
	(segment
		(start 131.4 144.8)
		(end 132 145.4)
		(width 0.2)
		(layer "B.Cu")
		(net 1)
	)
	(segment
		(start 113.711 137.259)
		(end 112.509 137.259)
		(width 0.2)
		(layer "B.Cu")
		(net 1)
	)
	(segment
		(start 99.1 54.5)
		(end 99.2 54.4)
		(width 0.1)
		(layer "B.Cu")
		(net 1)
	)
	(segment
		(start 105.83 66.01)
		(end 106.49 66.01)
		(width 0.2)
		(layer "B.Cu")
		(net 1)
	)
	(segment
		(start 199.158 58.39)
		(end 199.158 59.8)
		(width 0.25)
		(layer "B.Cu")
		(net 1)
	)
	(segment
		(start 201.28 124.2)
		(end 201.28 128.2)
		(width 0.2)
		(layer "B.Cu")
		(net 1)
	)
	(segment
		(start 100.9 132.6)
		(end 100.9 132.7)
		(width 0.3)
		(layer "B.Cu")
		(net 1)
	)
	(segment
		(start 112.511 101.75)
		(end 112.5 101.761)
		(width 0.15)
		(layer "B.Cu")
		(net 1)
	)
	(segment
		(start 142.52 65.68)
		(end 142 66.2)
		(width 0.2)
		(layer "B.Cu")
		(net 1)
	)
	(segment
		(start 85.935532 78.945)
		(end 85.935532 78.964468)
		(width 0.3)
		(layer "B.Cu")
		(net 1)
	)
	(segment
		(start 73.049999 142.8)
		(end 73 142.849999)
		(width 0.5)
		(layer "B.Cu")
		(net 1)
	)
	(segment
		(start 113.711 129.76)
		(end 112.66 129.76)
		(width 0.1)
		(layer "B.Cu")
		(net 1)
	)
	(segment
		(start 236.05 77.51)
		(end 236.86 77.51)
		(width 0.2)
		(layer "B.Cu")
		(net 1)
	)
	(segment
		(start 197.658 58.39)
		(end 197.658 59.8)
		(width 0.25)
		(layer "B.Cu")
		(net 1)
	)
	(segment
		(start 211.85 74.35)
		(end 211.85 74.34)
		(width 0.3)
		(layer "B.Cu")
		(net 1)
	)
	(segment
		(start 112.511 107.75)
		(end 112.5 107.761)
		(width 0.15)
		(layer "B.Cu")
		(net 1)
	)
	(segment
		(start 234.1 84.1)
		(end 233.6 83.6)
		(width 0.3)
		(layer "B.Cu")
		(net 1)
	)
	(segment
		(start 236.86 77.51)
		(end 236.87 77.5)
		(width 0.2)
		(layer "B.Cu")
		(net 1)
	)
	(segment
		(start 113.685 106.25)
		(end 112.511 106.25)
		(width 0.15)
		(layer "B.Cu")
		(net 1)
	)
	(segment
		(start 146.32 65.68)
		(end 146.4 65.6)
		(width 0.2)
		(layer "B.Cu")
		(net 1)
	)
	(segment
		(start 120.6 143.1)
		(end 121.4 143.1)
		(width 0.3)
		(layer "B.Cu")
		(net 1)
	)
	(segment
		(start 178.951 76.049)
		(end 179.2 75.8)
		(width 0.2)
		(layer "B.Cu")
		(net 1)
	)
	(segment
		(start 215.52 87.185)
		(end 215.415 87.185)
		(width 0.1)
		(layer "B.Cu")
		(net 1)
	)
	(segment
		(start 214.92 71.13)
		(end 215.35 70.7)
		(width 0.3)
		(layer "B.Cu")
		(net 1)
	)
	(segment
		(start 178.8 91.1)
		(end 178.247 91.1)
		(width 0.2)
		(layer "B.Cu")
		(net 1)
	)
	(segment
		(start 205.72 65.98)
		(end 205.7 66)
		(width 0.1)
		(layer "B.Cu")
		(net 1)
	)
	(segment
		(start 137.8 65.68)
		(end 138.58 65.68)
		(width 0.2)
		(layer "B.Cu")
		(net 1)
	)
	(segment
		(start 230 121.6)
		(end 229.4 121.6)
		(width 0.2)
		(layer "B.Cu")
		(net 1)
	)
	(segment
		(start 112.513 95.748)
		(end 112.5 95.761)
		(width 0.15)
		(layer "B.Cu")
		(net 1)
	)
	(segment
		(start 220.679 112.019)
		(end 220.679 111.621)
		(width 0.1)
		(layer "B.Cu")
		(net 1)
	)
	(segment
		(start 137.63 58.98)
		(end 137.63 59.97)
		(width 0.2)
		(layer "B.Cu")
		(net 1)
	)
	(segment
		(start 179.76 89.44)
		(end 179.76 88.85)
		(width 0.2)
		(layer "B.Cu")
		(net 1)
	)
	(segment
		(start 89.8 75.28)
		(end 89.360532 75.28)
		(width 0.2)
		(layer "B.Cu")
		(net 1)
	)
	(segment
		(start 206.181 145.01)
		(end 205.409 145.01)
		(width 0.1)
		(layer "B.Cu")
		(net 1)
	)
	(segment
		(start 112.8 70.62)
		(end 113.500532 70.62)
		(width 0.3)
		(layer "B.Cu")
		(net 1)
	)
	(segment
		(start 220.679 112.569)
		(end 221.14 113.03)
		(width 0.1)
		(layer "B.Cu")
		(net 1)
	)
	(segment
		(start 106.49 66.01)
		(end 106.5 66)
		(width 0.2)
		(layer "B.Cu")
		(net 1)
	)
	(segment
		(start 206.52 65.98)
		(end 205.72 65.98)
		(width 0.1)
		(layer "B.Cu")
		(net 1)
	)
	(segment
		(start 204.486 145.01)
		(end 204.476 145)
		(width 0.1)
		(layer "B.Cu")
		(net 1)
	)
	(segment
		(start 113.685 103.249)
		(end 112.512 103.249)
		(width 0.15)
		(layer "B.Cu")
		(net 1)
	)
	(segment
		(start 222.69 97.59)
		(end 222.7 97.6)
		(width 0.1)
		(layer "B.Cu")
		(net 1)
	)
	(segment
		(start 147.2 62)
		(end 147.16 62)
		(width 0.2)
		(layer "B.Cu")
		(net 1)
	)
	(segment
		(start 220.82 95.392)
		(end 220.82 94.72)
		(width 0.1)
		(layer "B.Cu")
		(net 1)
	)
	(segment
		(start 196.7 127.9)
		(end 196.7 127.1)
		(width 0.2)
		(layer "B.Cu")
		(net 1)
	)
	(segment
		(start 127.875 133.525)
		(end 127.8 133.6)
		(width 0.2)
		(layer "B.Cu")
		(net 1)
	)
	(segment
		(start 218.3 88.4)
		(end 219.15 88.4)
		(width 0.1)
		(layer "B.Cu")
		(net 1)
	)
	(segment
		(start 98.4 63.418)
		(end 100.168 63.418)
		(width 0.2)
		(layer "B.Cu")
		(net 1)
	)
	(segment
		(start 160.78 69.79)
		(end 161.59 69.79)
		(width 0.3)
		(layer "B.Cu")
		(net 1)
	)
	(segment
		(start 65.561 101.461)
		(end 65.6 101.5)
		(width 0.2)
		(layer "B.Cu")
		(net 1)
	)
	(segment
		(start 72.2 142.8)
		(end 72.950001 142.8)
		(width 0.5)
		(layer "B.Cu")
		(net 1)
	)
	(segment
		(start 206.52 65)
		(end 205.7 65)
		(width 0.1)
		(layer "B.Cu")
		(net 1)
	)
	(segment
		(start 170.697 61.298)
		(end 170.805 61.19)
		(width 0.1)
		(layer "B.Cu")
		(net 1)
	)
	(segment
		(start 120.365 144.285)
		(end 120.365 143.335)
		(width 0.3)
		(layer "B.Cu")
		(net 1)
	)
	(segment
		(start 112.64 128.26)
		(end 112.6 128.3)
		(width 0.1)
		(layer "B.Cu")
		(net 1)
	)
	(segment
		(start 113.711 132.76)
		(end 112.51 132.76)
		(width 0.2)
		(layer "B.Cu")
		(net 1)
	)
	(segment
		(start 126.8345 145.303)
		(end 128.0825 146.551)
		(width 0.2)
		(layer "B.Cu")
		(net 1)
	)
	(segment
		(start 137.63 59.97)
		(end 137.3 60.3)
		(width 0.2)
		(layer "B.Cu")
		(net 1)
	)
	(segment
		(start 238.58 83.55)
		(end 238.58 84.27)
		(width 0.2)
		(layer "B.Cu")
		(net 1)
	)
	(segment
		(start 131.68 132.48)
		(end 131.8 132.6)
		(width 0.2)
		(layer "B.Cu")
		(net 1)
	)
	(segment
		(start 214.45 76.2)
		(end 213.8 76.2)
		(width 0.1)
		(layer "B.Cu")
		(net 1)
	)
	(segment
		(start 121.6 143.1)
		(end 121.6 144.25)
		(width 0.3)
		(layer "B.Cu")
		(net 1)
	)
	(segment
		(start 220.88 123.28)
		(end 220.389 122.789)
		(width 0.1)
		(layer "B.Cu")
		(net 1)
	)
	(segment
		(start 108.9 69.48)
		(end 108.91 69.49)
		(width 0.3)
		(layer "B.Cu")
		(net 1)
	)
	(segment
		(start 215.415 87.185)
		(end 215 87.6)
		(width 0.1)
		(layer "B.Cu")
		(net 1)
	)
	(segment
		(start 219.1 59.98)
		(end 219.78 59.98)
		(width 0.2)
		(layer "B.Cu")
		(net 1)
	)
	(segment
		(start 215.538 74.738)
		(end 215.5 74.7)
		(width 0.1)
		(layer "B.Cu")
		(net 1)
	)
	(segment
		(start 171.44 61.19)
		(end 171.5 61.25)
		(width 0.1)
		(layer "B.Cu")
		(net 1)
	)
	(segment
		(start 215 87.6)
		(end 214.48 87.6)
		(width 0.1)
		(layer "B.Cu")
		(net 1)
	)
	(segment
		(start 236.38 135)
		(end 237.2 135)
		(width 0.2)
		(layer "B.Cu")
		(net 1)
	)
	(segment
		(start 238.575 82.500001)
		(end 238.575 83.545)
		(width 0.2)
		(layer "B.Cu")
		(net 1)
	)
	(segment
		(start 220.88 123.391698)
		(end 220.88 123.28)
		(width 0.1)
		(layer "B.Cu")
		(net 1)
	)
	(segment
		(start 179.183 80.383)
		(end 179.2 80.4)
		(width 0.2)
		(layer "B.Cu")
		(net 1)
	)
	(segment
		(start 99.101 57.949)
		(end 100.469 57.949)
		(width 0.2)
		(layer "B.Cu")
		(net 1)
	)
	(segment
		(start 132 145.4)
		(end 132 145.52)
		(width 0.2)
		(layer "B.Cu")
		(net 1)
	)
	(segment
		(start 236.95 109.85)
		(end 236.174 109.85)
		(width 0.3)
		(layer "B.Cu")
		(net 1)
	)
	(segment
		(start 116.25 69.554468)
		(end 116.25 69.46)
		(width 0.3)
		(layer "B.Cu")
		(net 1)
	)
	(segment
		(start 126.8345 144.076)
		(end 126.8345 145.303)
		(width 0.2)
		(layer "B.Cu")
		(net 1)
	)
	(segment
		(start 177.1 60.2)
		(end 177.05 60.2)
		(width 0.1)
		(layer "B.Cu")
		(net 1)
	)
	(segment
		(start 229.47 126.9)
		(end 228.97 126.4)
		(width 0.2)
		(layer "B.Cu")
		(net 1)
	)
	(segment
		(start 133.3 54.5)
		(end 134.6 54.5)
		(width 0.1)
		(layer "B.Cu")
		(net 1)
	)
	(segment
		(start 73 142.849999)
		(end 73 143.6)
		(width 0.5)
		(layer "B.Cu")
		(net 1)
	)
	(segment
		(start 141.93 55.105)
		(end 141.93 55.13)
		(width 0.3)
		(layer "B.Cu")
		(net 1)
	)
	(segment
		(start 219.025 79.315)
		(end 220 78.34)
		(width 0.3)
		(layer "B.Cu")
		(net 1)
	)
	(segment
		(start 113.685 95.748)
		(end 112.513 95.748)
		(width 0.15)
		(layer "B.Cu")
		(net 1)
	)
	(segment
		(start 213.28 91.8)
		(end 214.3 91.8)
		(width 0.1)
		(layer "B.Cu")
		(net 1)
	)
	(segment
		(start 209.976 141)
		(end 209.196532 141)
		(width 0.1)
		(layer "B.Cu")
		(net 1)
	)
	(segment
		(start 160.86 63.288)
		(end 160.86 64.33)
		(width 0.1)
		(layer "B.Cu")
		(net 1)
	)
	(segment
		(start 204.488 144.012)
		(end 204.476 144)
		(width 0.1)
		(layer "B.Cu")
		(net 1)
	)
	(segment
		(start 229.1 107.200001)
		(end 229.999999 107.200001)
		(width 0.3)
		(layer "B.Cu")
		(net 1)
	)
	(segment
		(start 125.3 139)
		(end 126.2 139)
		(width 0.2)
		(layer "B.Cu")
		(net 1)
	)
	(segment
		(start 236.8 123)
		(end 236.9 123)
		(width 0.1)
		(layer "B.Cu")
		(net 1)
	)
	(segment
		(start 229.46 133.94)
		(end 229.46 133.96)
		(width 0.2)
		(layer "B.Cu")
		(net 1)
	)
	(segment
		(start 138.202 60.505)
		(end 138.202 60.302)
		(width 0.2)
		(layer "B.Cu")
		(net 1)
	)
	(segment
		(start 127.0435 141.8)
		(end 127.8 141.8)
		(width 0.2)
		(layer "B.Cu")
		(net 1)
	)
	(segment
		(start 139.2 62.6)
		(end 138.8 63)
		(width 0.2)
		(layer "B.Cu")
		(net 1)
	)
	(segment
		(start 134.7 54.6)
		(end 134.8 54.5)
		(width 0.1)
		(layer "B.Cu")
		(net 1)
	)
	(segment
		(start 225.521 76.93)
		(end 225.521 76.221)
		(width 0.1)
		(layer "B.Cu")
		(net 1)
	)
	(segment
		(start 120.4 144.25)
		(end 120.365 144.285)
		(width 0.3)
		(layer "B.Cu")
		(net 1)
	)
	(segment
		(start 135.6 61.8)
		(end 135.604 61.796)
		(width 0.2)
		(layer "B.Cu")
		(net 1)
	)
	(segment
		(start 176.4 62.85)
		(end 176.75 62.5)
		(width 0.1)
		(layer "B.Cu")
		(net 1)
	)
	(segment
		(start 126.8345 143.019)
		(end 127.0435 142.81)
		(width 0.2)
		(layer "B.Cu")
		(net 1)
	)
	(segment
		(start 221.182132 97.59)
		(end 222.69 97.59)
		(width 0.1)
		(layer "B.Cu")
		(net 1)
	)
	(segment
		(start 174.55 60.576004)
		(end 175.534998 60.576004)
		(width 0.1)
		(layer "B.Cu")
		(net 1)
	)
	(segment
		(start 133.2 54.6)
		(end 133.3 54.5)
		(width 0.1)
		(layer "B.Cu")
		(net 1)
	)
	(segment
		(start 113.6 114.85)
		(end 113.5 114.75)
		(width 0.2)
		(layer "B.Cu")
		(net 1)
	)
	(segment
		(start 161.59 69.79)
		(end 161.7 69.9)
		(width 0.3)
		(layer "B.Cu")
		(net 1)
	)
	(segment
		(start 164.365 63.98)
		(end 163.62 63.98)
		(width 0.3)
		(layer "B.Cu")
		(net 1)
	)
	(segment
		(start 224.5 122.94)
		(end 224.5 122.6)
		(width 0.1)
		(layer "B.Cu")
		(net 1)
	)
	(segment
		(start 202.158 59.042)
		(end 201.5 59.7)
		(width 0.15)
		(layer "B.Cu")
		(net 1)
	)
	(segment
		(start 238.58 84.27)
		(end 238.55 84.3)
		(width 0.2)
		(layer "B.Cu")
		(net 1)
	)
	(segment
		(start 217.7 87.18)
		(end 217.7 87.8)
		(width 0.1)
		(layer "B.Cu")
		(net 1)
	)
	(segment
		(start 236.28 96.6)
		(end 236.28 97.38)
		(width 0.2)
		(layer "B.Cu")
		(net 1)
	)
	(segment
		(start 102.98 66.01)
		(end 102.98 65.27)
		(width 0.2)
		(layer "B.Cu")
		(net 1)
	)
	(segment
		(start 220.325 76.44)
		(end 220.325 78.015)
		(width 0.3)
		(layer "B.Cu")
		(net 1)
	)
	(segment
		(start 112.6 131.3)
		(end 113.671 131.3)
		(width 0.1)
		(layer "B.Cu")
		(net 1)
	)
	(segment
		(start 200.78 68.02)
		(end 200.8 68)
		(width 0.2)
		(layer "B.Cu")
		(net 1)
	)
	(segment
		(start 220.679 111.621)
		(end 220.9 111.4)
		(width 0.1)
		(layer "B.Cu")
		(net 1)
	)
	(segment
		(start 112.51 134.26)
		(end 112.5 134.25)
		(width 0.2)
		(layer "B.Cu")
		(net 1)
	)
	(segment
		(start 170.805 61.19)
		(end 171.44 61.19)
		(width 0.1)
		(layer "B.Cu")
		(net 1)
	)
	(segment
		(start 208.28 82.3)
		(end 207.8 82.3)
		(width 0.1)
		(layer "B.Cu")
		(net 1)
	)
	(segment
		(start 131.397 144.803)
		(end 131.4 144.8)
		(width 0.2)
		(layer "B.Cu")
		(net 1)
	)
	(segment
		(start 125.3 137.6)
		(end 126.2 137.6)
		(width 0.2)
		(layer "B.Cu")
		(net 1)
	)
	(segment
		(start 214.448 78.505)
		(end 214.105 78.505)
		(width 0.1)
		(layer "B.Cu")
		(net 1)
	)
	(segment
		(start 196.6 132.85)
		(end 196.55 132.9)
		(width 0.1)
		(layer "B.Cu")
		(net 1)
	)
	(segment
		(start 179.2 90)
		(end 179.55 89.65)
		(width 0.2)
		(layer "B.Cu")
		(net 1)
	)
	(segment
		(start 135.604 61.796)
		(end 135.604 60.779)
		(width 0.2)
		(layer "B.Cu")
		(net 1)
	)
	(segment
		(start 122.905 144.285)
		(end 122.905 143.295)
		(width 0.3)
		(layer "B.Cu")
		(net 1)
	)
	(segment
		(start 113.711 120.261)
		(end 112.511 120.261)
		(width 0.2)
		(layer "B.Cu")
		(net 1)
	)
	(segment
		(start 121.6 143.1)
		(end 121.8 143.1)
		(width 0.3)
		(layer "B.Cu")
		(net 1)
	)
	(segment
		(start 201.5 129)
		(end 202 129)
		(width 0.2)
		(layer "B.Cu")
		(net 1)
	)
	(segment
		(start 178.145 79.433)
		(end 179.033 79.433)
		(width 0.2)
		(layer "B.Cu")
		(net 1)
	)
	(segment
		(start 129.8305 144.803)
		(end 128.0825 146.551)
		(width 0.2)
		(layer "B.Cu")
		(net 1)
	)
	(segment
		(start 144.33 55.105)
		(end 144.33 55.13)
		(width 0.3)
		(layer "B.Cu")
		(net 1)
	)
	(segment
		(start 223.579 122.419)
		(end 223.579 122.939)
		(width 0.1)
		(layer "B.Cu")
		(net 1)
	)
	(segment
		(start 218.1 79.315)
		(end 217.315 79.315)
		(width 0.3)
		(layer "B.Cu")
		(net 1)
	)
	(segment
		(start 121.4 143.1)
		(end 121.6 143.1)
		(width 0.3)
		(layer "B.Cu")
		(net 1)
	)
	(segment
		(start 163.62 63.98)
		(end 163.4 64.2)
		(width 0.3)
		(layer "B.Cu")
		(net 1)
	)
	(segment
		(start 161.822 60.29)
		(end 161.81 60.278)
		(width 0.1)
		(layer "B.Cu")
		(net 1)
	)
	(segment
		(start 65.54 111.96)
		(end 65.6 111.9)
		(width 0.2)
		(layer "B.Cu")
		(net 1)
	)
	(segment
		(start 230.454 95.096)
		(end 231.099001 95.096)
		(width 0.2)
		(layer "B.Cu")
		(net 1)
	)
	(segment
		(start 120.26 70.59)
		(end 120.26 70.52)
		(width 0.3)
		(layer "B.Cu")
		(net 1)
	)
	(segment
		(start 225.521 79.815)
		(end 225.665 79.815)
		(width 0.2)
		(layer "B.Cu")
		(net 1)
	)
	(segment
		(start 113.500532 70.62)
		(end 113.530532 70.65)
		(width 0.3)
		(layer "B.Cu")
		(net 1)
	)
	(segment
		(start 114.46 94.149)
		(end 114.46 94.21)
		(width 0.2)
		(layer "B.Cu")
		(net 1)
	)
	(segment
		(start 122.7 143.1)
		(end 122.9 143.1)
		(width 0.3)
		(layer "B.Cu")
		(net 1)
	)
	(segment
		(start 136.26 55.07)
		(end 136.295 55.105)
		(width 0.3)
		(layer "B.Cu")
		(net 1)
	)
	(segment
		(start 135.45 54.5)
		(end 135.725 54.5)
		(width 0.1)
		(layer "B.Cu")
		(net 1)
	)
	(segment
		(start 72.950001 142.8)
		(end 73 142.849999)
		(width 0.5)
		(layer "B.Cu")
		(net 1)
	)
	(segment
		(start 119.095 144.285)
		(end 119.095 143.305)
		(width 0.3)
		(layer "B.Cu")
		(net 1)
	)
	(segment
		(start 234.12 84.1)
		(end 234.1 84.1)
		(width 0.3)
		(layer "B.Cu")
		(net 1)
	)
	(segment
		(start 137.68 71.2)
		(end 137.68 71.899468)
		(width 0.3)
		(layer "B.Cu")
		(net 1)
	)
	(segment
		(start 113.685 109.249)
		(end 112.512 109.249)
		(width 0.15)
		(layer "B.Cu")
		(net 1)
	)
	(segment
		(start 200.658 58.39)
		(end 200.658 59.8)
		(width 0.25)
		(layer "B.Cu")
		(net 1)
	)
	(segment
		(start 96.53 65.998)
		(end 96.248 65.998)
		(width 0.2)
		(layer "B.Cu")
		(net 1)
	)
	(segment
		(start 220.9 111.4)
		(end 221.9 111.4)
		(width 0.1)
		(layer "B.Cu")
		(net 1)
	)
	(segment
		(start 206.656 58.39)
		(end 206.656 59.491808)
		(width 0.25)
		(layer "B.Cu")
		(net 1)
	)
	(segment
		(start 231.043001 133.94)
		(end 231.099001 133.996)
		(width 0.2)
		(layer "B.Cu")
		(net 1)
	)
	(segment
		(start 230.15 95.4)
		(end 230.454 95.096)
		(width 0.2)
		(layer "B.Cu")
		(net 1)
	)
	(segment
		(start 165.634 67.766)
		(end 166.2 67.2)
		(width 0.3)
		(layer "B.Cu")
		(net 1)
	)
	(segment
		(start 236.209002 93.990998)
		(end 236.2 94)
		(width 0.2)
		(layer "B.Cu")
		(net 1)
	)
	(segment
		(start 179.75 93.1)
		(end 179.75 92)
		(width 0.2)
		(layer "B.Cu")
		(net 1)
	)
	(segment
		(start 112.66 129.76)
		(end 112.6 129.7)
		(width 0.1)
		(layer "B.Cu")
		(net 1)
	)
	(segment
		(start 135.69 55.07)
		(end 136.26 55.07)
		(width 0.3)
		(layer "B.Cu")
		(net 1)
	)
	(segment
		(start 136.295 55.105)
		(end 136.33 55.105)
		(width 0.3)
		(layer "B.Cu")
		(net 1)
	)
	(segment
		(start 121.635 144.285)
		(end 121.635 143.335)
		(width 0.3)
		(layer "B.Cu")
		(net 1)
	)
	(segment
		(start 236.8 122)
		(end 236.9 122)
		(width 0.1)
		(layer "B.Cu")
		(net 1)
	)
	(segment
		(start 226.3 83)
		(end 227.700001 83)
		(width 0.5)
		(layer "B.Cu")
		(net 1)
	)
	(segment
		(start 178.885 78.175)
		(end 179.805 78.175)
		(width 0.2)
		(layer "B.Cu")
		(net 1)
	)
	(segment
		(start 113.685 104.749)
		(end 112.512 104.749)
		(width 0.15)
		(layer "B.Cu")
		(net 1)
	)
	(segment
		(start 210.52 60)
		(end 209.8 60)
		(width 0.2)
		(layer "B.Cu")
		(net 1)
	)
	(segment
		(start 112.11 95.251)
		(end 112.1 95.261)
		(width 0.15)
		(layer "B.Cu")
		(net 1)
	)
	(segment
		(start 208.28 80.32)
		(end 207.8 80.8)
		(width 0.1)
		(layer "B.Cu")
		(net 1)
	)
	(segment
		(start 134.6 54.5)
		(end 134.7 54.6)
		(width 0.1)
		(layer "B.Cu")
		(net 1)
	)
	(segment
		(start 179.2 79.6)
		(end 179.2 80.4)
		(width 0.2)
		(layer "B.Cu")
		(net 1)
	)
	(segment
		(start 109.44 70.02)
		(end 108.91 69.49)
		(width 0.3)
		(layer "B.Cu")
		(net 1)
	)
	(segment
		(start 211.800999 66.004)
		(end 212.696 66.004)
		(width 0.3)
		(layer "B.Cu")
		(net 1)
	)
	(segment
		(start 64.59 111.96)
		(end 65.54 111.96)
		(width 0.2)
		(layer "B.Cu")
		(net 1)
	)
	(segment
		(start 100.508 66.008)
		(end 101 66.5)
		(width 0.2)
		(layer "B.Cu")
		(net 1)
	)
	(segment
		(start 229.4 133.9)
		(end 229.4 132.700001)
		(width 0.5)
		(layer "B.Cu")
		(net 1)
	)
	(segment
		(start 221.3 122.971698)
		(end 221.3 122.5)
		(width 0.1)
		(layer "B.Cu")
		(net 1)
	)
	(segment
		(start 121.6 144.25)
		(end 121.635 144.285)
		(width 0.3)
		(layer "B.Cu")
		(net 1)
	)
	(segment
		(start 231.099001 121.996)
		(end 230.396 121.996)
		(width 0.2)
		(layer "B.Cu")
		(net 1)
	)
	(segment
		(start 134.8 65.68)
		(end 134.8 66.6)
		(width 0.2)
		(layer "B.Cu")
		(net 1)
	)
	(segment
		(start 209.206 147)
		(end 209.976 147)
		(width 0.1)
		(layer "B.Cu")
		(net 1)
	)
	(segment
		(start 144.33 55.13)
		(end 144.4 55.2)
		(width 0.3)
		(layer "B.Cu")
		(net 1)
	)
	(segment
		(start 236.28 122)
		(end 236.8 122)
		(width 0.1)
		(layer "B.Cu")
		(net 1)
	)
	(segment
		(start 112.81 70.61)
		(end 112.8 70.62)
		(width 0.3)
		(layer "B.Cu")
		(net 1)
	)
	(segment
		(start 120.365 143.335)
		(end 120.6 143.1)
		(width 0.3)
		(layer "B.Cu")
		(net 1)
	)
	(segment
		(start 178.797 90.053)
		(end 178.85 90)
		(width 0.2)
		(layer "B.Cu")
		(net 1)
	)
	(segment
		(start 161.7 69.9)
		(end 161.7 70.5)
		(width 0.3)
		(layer "B.Cu")
		(net 1)
	)
	(segment
		(start 199.126 143.9)
		(end 198.856 143.9)
		(width 0.2)
		(layer "B.Cu")
		(net 1)
	)
	(segment
		(start 213.8 78.2)
		(end 213.8 76.2)
		(width 0.1)
		(layer "B.Cu")
		(net 1)
	)
	(segment
		(start 126.593 151.193)
		(end 126.6 151.2)
		(width 0.2)
		(layer "B.Cu")
		(net 1)
	)
	(segment
		(start 224.33 94.13)
		(end 224.3 94.1)
		(width 0.1)
		(layer "B.Cu")
		(net 1)
	)
	(segment
		(start 207.2 119.98)
		(end 207.2 119)
		(width 0.1)
		(layer "B.Cu")
		(net 1)
	)
	(segment
		(start 73.8 142.8)
		(end 73.049999 142.8)
		(width 0.5)
		(layer "B.Cu")
		(net 1)
	)
	(segment
		(start 126.593 150.344)
		(end 126.593 151.193)
		(width 0.2)
		(layer "B.Cu")
		(net 1)
	)
	(segment
		(start 146.132 61.297)
		(end 146.132 60.525)
		(width 0.2)
		(layer "B.Cu")
		(net 1)
	)
	(segment
		(start 229.59 103.6)
		(end 229.57 103.6)
		(width 0.3)
		(layer "B.Cu")
		(net 1)
	)
	(segment
		(start 113.711 138.759)
		(end 112.509 138.759)
		(width 0.2)
		(layer "B.Cu")
		(net 1)
	)
	(segment
		(start 206.9 118.7)
		(end 206.9 117.76)
		(width 0.1)
		(layer "B.Cu")
		(net 1)
	)
	(segment
		(start 100.168 63.418)
		(end 100.25 63.5)
		(width 0.2)
		(layer "B.Cu")
		(net 1)
	)
	(segment
		(start 113.685 107.75)
		(end 112.511 107.75)
		(width 0.15)
		(layer "B.Cu")
		(net 1)
	)
	(segment
		(start 178.85 91.05)
		(end 178.197 91.05)
		(width 0.2)
		(layer "B.Cu")
		(net 1)
	)
	(segment
		(start 120.365 151.015)
		(end 120.18 151.2)
		(width 0.2)
		(layer "B.Cu")
		(net 1)
	)
	(segment
		(start 207.18 120)
		(end 207.2 119.98)
		(width 0.1)
		(layer "B.Cu")
		(net 1)
	)
	(segment
		(start 178.186 76.049)
		(end 178.951 76.049)
		(width 0.2)
		(layer "B.Cu")
		(net 1)
	)
	(segment
		(start 235.102 70.502)
		(end 235 70.4)
		(width 0.2)
		(layer "B.Cu")
		(net 1)
	)
	(segment
		(start 131.499 148.301)
		(end 131.5 148.3)
		(width 0.2)
		(layer "B.Cu")
		(net 1)
	)
	(segment
		(start 160.58 68.739)
		(end 160.58 69.59)
		(width 0.3)
		(layer "B.Cu")
		(net 1)
	)
	(segment
		(start 175.568 62.85)
		(end 176.4 62.85)
		(width 0.1)
		(layer "B.Cu")
		(net 1)
	)
	(segment
		(start 160.4 64.75)
		(end 160.66 64.49)
		(width 0.3)
		(layer "B.Cu")
		(net 1)
	)
	(segment
		(start 116.3 70.6)
		(end 117.41 70.6)
		(width 0.3)
		(layer "B.Cu")
		(net 1)
	)
	(segment
		(start 112.512 104.749)
		(end 112.5 104.761)
		(width 0.15)
		(layer "B.Cu")
		(net 1)
	)
	(segment
		(start 143.725 60.658)
		(end 143.604 60.779)
		(width 0.2)
		(layer "B.Cu")
		(net 1)
	)
	(segment
		(start 121.37 70.59)
		(end 121.45 70.67)
		(width 0.3)
		(layer "B.Cu")
		(net 1)
	)
	(segment
		(start 125.3 98.2)
		(end 125.3 98.5)
		(width 0.2)
		(layer "B.Cu")
		(net 1)
	)
	(segment
		(start 219.78 59.98)
		(end 219.8 60)
		(width 0.2)
		(layer "B.Cu")
		(net 1)
	)
	(segment
		(start 116.3 69.604468)
		(end 116.25 69.554468)
		(width 0.3)
		(layer "B.Cu")
		(net 1)
	)
	(segment
		(start 99.8 66.008)
		(end 100.508 66.008)
		(width 0.2)
		(layer "B.Cu")
		(net 1)
	)
	(segment
		(start 138.202 60.302)
		(end 137.87 59.97)
		(width 0.2)
		(layer "B.Cu")
		(net 1)
	)
	(segment
		(start 178.15 85.803)
		(end 178.803 85.803)
		(width 0.2)
		(layer "B.Cu")
		(net 1)
	)
	(segment
		(start 126.3345 144.803)
		(end 128.0825 146.551)
		(width 0.2)
		(layer "B.Cu")
		(net 1)
	)
	(segment
		(start 229.999999 107.200001)
		(end 230 107.2)
		(width 0.3)
		(layer "B.Cu")
		(net 1)
	)
	(segment
		(start 125.3 120)
		(end 126.2 120)
		(width 0.2)
		(layer "B.Cu")
		(net 1)
	)
	(segment
		(start 113.685 98.749)
		(end 112.512 98.749)
		(width 0.15)
		(layer "B.Cu")
		(net 1)
	)
	(segment
		(start 64.59 102.962)
		(end 63.637 102.962)
		(width 0.2)
		(layer "B.Cu")
		(net 1)
	)
	(segment
		(start 215 87.6)
		(end 215 88.68)
		(width 0.1)
		(layer "B.Cu")
		(net 1)
	)
	(segment
		(start 112.511 106.25)
		(end 112.5 106.261)
		(width 0.15)
		(layer "B.Cu")
		(net 1)
	)
	(segment
		(start 217.539 111.989)
		(end 217.539 111.461)
		(width 0.1)
		(layer "B.Cu")
		(net 1)
	)
	(segment
		(start 212.696 66.004)
		(end 212.7 66)
		(width 0.3)
		(layer "B.Cu")
		(net 1)
	)
	(segment
		(start 208.157 59.491808)
		(end 208.223808 59.425)
		(width 0.3)
		(layer "B.Cu")
		(net 1)
	)
	(segment
		(start 202.158 58.39)
		(end 202.158 59.042)
		(width 0.15)
		(layer "B.Cu")
		(net 1)
	)
	(segment
		(start 178.145 80.383)
		(end 179.183 80.383)
		(width 0.2)
		(layer "B.Cu")
		(net 1)
	)
	(segment
		(start 114.459 139.861)
		(end 114.459 139.791)
		(width 0.2)
		(layer "B.Cu")
		(net 1)
	)
	(segment
		(start 130.5575 144.803)
		(end 131.397 144.803)
		(width 0.2)
		(layer "B.Cu")
		(net 1)
	)
	(segment
		(start 122.9 143.1)
		(end 122.9 144.28)
		(width 0.3)
		(layer "B.Cu")
		(net 1)
	)
	(segment
		(start 120.4 143.1)
		(end 120.6 143.1)
		(width 0.3)
		(layer "B.Cu")
		(net 1)
	)
	(segment
		(start 206.9 117.76)
		(end 207.34 117.32)
		(width 0.1)
		(layer "B.Cu")
		(net 1)
	)
	(segment
		(start 139.2 61.277)
		(end 139.2 60.505)
		(width 0.2)
		(layer "B.Cu")
		(net 1)
	)
	(segment
		(start 214.5 71.13)
		(end 214.92 71.13)
		(width 0.3)
		(layer "B.Cu")
		(net 1)
	)
	(segment
		(start 130.5575 144.803)
		(end 129.8305 144.803)
		(width 0.2)
		(layer "B.Cu")
		(net 1)
	)
	(segment
		(start 143.78 66.33)
		(end 143.73 66.33)
		(width 0.2)
		(layer "B.Cu")
		(net 1)
	)
	(segment
		(start 112.512 98.749)
		(end 112.5 98.761)
		(width 0.15)
		(layer "B.Cu")
		(net 1)
	)
	(segment
		(start 236.28 123)
		(end 236.8 123)
		(width 0.1)
		(layer "B.Cu")
		(net 1)
	)
	(segment
		(start 120.365 143.265)
		(end 120.2 143.1)
		(width 0.3)
		(layer "B.Cu")
		(net 1)
	)
	(segment
		(start 83.9 66.2)
		(end 84.1 66)
		(width 0.5)
		(layer "B.Cu")
		(net 1)
	)
	(segment
		(start 121.8 143.1)
		(end 122.7 143.1)
		(width 0.3)
		(layer "B.Cu")
		(net 1)
	)
	(segment
		(start 120.365 151.015)
		(end 120.365 149.71)
		(width 0.3)
		(layer "B.Cu")
		(net 1)
	)
	(segment
		(start 215.5 83.82)
		(end 215.5 83.425)
		(width 0.1)
		(layer "B.Cu")
		(net 1)
	)
	(segment
		(start 178.247 91.1)
		(end 178.15 91.003)
		(width 0.2)
		(layer "B.Cu")
		(net 1)
	)
	(segment
		(start 230.17 90.2)
		(end 229.95 89.98)
		(width 0.15)
		(layer "B.Cu")
		(net 1)
	)
	(segment
		(start 220.389 122.789)
		(end 220.389 122.400698)
		(width 0.1)
		(layer "B.Cu")
		(net 1)
	)
	(segment
		(start 229.57 113.8)
		(end 228.97 113.2)
		(width 0.5)
		(layer "B.Cu")
		(net 1)
	)
	(segment
		(start 179.15 91.45)
		(end 178.8 91.1)
		(width 0.2)
		(layer "B.Cu")
		(net 1)
	)
	(segment
		(start 125.3 113.5)
		(end 126.1 113.5)
		(width 0.2)
		(layer "B.Cu")
		(net 1)
	)
	(segment
		(start 217.539 112.539)
		(end 217.539 111.989)
		(width 0.1)
		(layer "B.Cu")
		(net 1)
	)
	(segment
		(start 113.685 101.75)
		(end 112.511 101.75)
		(width 0.15)
		(layer "B.Cu")
		(net 1)
	)
	(segment
		(start 176.706998 60.543002)
		(end 175.568 60.543002)
		(width 0.1)
		(layer "B.Cu")
		(net 1)
	)
	(segment
		(start 147.16 62)
		(end 147.13 61.97)
		(width 0.2)
		(layer "B.Cu")
		(net 1)
	)
	(segment
		(start 224.33 94.85)
		(end 224.33 95.868)
		(width 0.1)
		(layer "B.Cu")
		(net 1)
	)
	(segment
		(start 207.8 83)
		(end 206.8 84)
		(width 0.1)
		(layer "B.Cu")
		(net 1)
	)
	(segment
		(start 175.534998 62.883002)
		(end 175.568 62.85)
		(width 0.1)
		(layer "B.Cu")
		(net 1)
	)
	(segment
		(start 146.132 60.525)
		(end 146.132 60.332)
		(width 0.2)
		(layer "B.Cu")
		(net 1)
	)
	(segment
		(start 162.84 60.29)
		(end 162.84 60.91)
		(width 0.1)
		(layer "B.Cu")
		(net 1)
	)
	(segment
		(start 205.88 101.8)
		(end 206.6 101.8)
		(width 0.3)
		(layer "B.Cu")
		(net 1)
	)
	(segment
		(start 116.25 69.46)
		(end 117.430532 69.46)
		(width 0.3)
		(layer "B.Cu")
		(net 1)
	)
	(segment
		(start 233.4 81.796)
		(end 232.499001 81.796)
		(width 0.2)
		(layer "B.Cu")
		(net 1)
	)
	(segment
		(start 208.223808 59.425)
		(end 208.225 59.425)
		(width 0.3)
		(layer "B.Cu")
		(net 1)
	)
	(segment
		(start 137.87 59.97)
		(end 137.63 59.97)
		(width 0.2)
		(layer "B.Cu")
		(net 1)
	)
	(segment
		(start 178.186 75.099)
		(end 179.099 75.099)
		(width 0.2)
		(layer "B.Cu")
		(net 1)
	)
	(segment
		(start 222.702 109.85)
		(end 222.702 109.302)
		(width 0.1)
		(layer "B.Cu")
		(net 1)
	)
	(segment
		(start 165.634 67.789)
		(end 165.634 67.766)
		(width 0.3)
		(layer "B.Cu")
		(net 1)
	)
	(segment
		(start 120.18 151.2)
		(end 120.18 152.88)
		(width 0.3)
		(layer "B.Cu")
		(net 1)
	)
	(segment
		(start 131 132.48)
		(end 131.68 132.48)
		(width 0.2)
		(layer "B.Cu")
		(net 1)
	)
	(segment
		(start 117.41 69.480532)
		(end 117.430532 69.46)
		(width 0.3)
		(layer "B.Cu")
		(net 1)
	)
	(segment
		(start 109.44 70.63)
		(end 108.250532 70.63)
		(width 0.3)
		(layer "B.Cu")
		(net 1)
	)
	(segment
		(start 160.58 68.739)
		(end 160.58 67.49)
		(width 0.3)
		(layer "B.Cu")
		(net 1)
	)
	(segment
		(start 213.9 89.18)
		(end 213.9 87.7)
		(width 0.1)
		(layer "B.Cu")
		(net 1)
	)
	(segment
		(start 107.78 69.48)
		(end 108.9 69.48)
		(width 0.3)
		(layer "B.Cu")
		(net 1)
	)
	(segment
		(start 112.512 109.249)
		(end 112.5 109.261)
		(width 0.15)
		(layer "B.Cu")
		(net 1)
	)
	(segment
		(start 178.84 82.5)
		(end 178.84 81.96)
		(width 0.2)
		(layer "B.Cu")
		(net 1)
	)
	(segment
		(start 63.637 102.962)
		(end 63.5 102.825)
		(width 0.2)
		(layer "B.Cu")
		(net 1)
	)
	(segment
		(start 119.3 143.1)
		(end 120.2 143.1)
		(width 0.3)
		(layer "B.Cu")
		(net 1)
	)
	(segment
		(start 121.635 143.265)
		(end 121.8 143.1)
		(width 0.3)
		(layer "B.Cu")
		(net 1)
	)
	(segment
		(start 229.44 133.94)
		(end 229.4 133.9)
		(width 0.5)
		(layer "B.Cu")
		(net 1)
	)
	(segment
		(start 229.48 133.94)
		(end 231.043001 133.94)
		(width 0.2)
		(layer "B.Cu")
		(net 1)
	)
	(segment
		(start 98.752 60.748)
		(end 99.2 60.3)
		(width 0.1)
		(layer "B.Cu")
		(net 1)
	)
	(segment
		(start 229.95 89.22)
		(end 229.97 89.2)
		(width 0.15)
		(layer "B.Cu")
		(net 1)
	)
	(segment
		(start 179 86.753)
		(end 179.272 86.753)
		(width 0.2)
		(layer "B.Cu")
		(net 1)
	)
	(segment
		(start 228.606532 130.063468)
		(end 228.606532 131.21)
		(width 0.2)
		(layer "B.Cu")
		(net 1)
	)
	(segment
		(start 231.100001 108.65)
		(end 230.25 108.65)
		(width 0.3)
		(layer "B.Cu")
		(net 1)
	)
	(segment
		(start 218.624618 97.8)
		(end 218.842132 97.582486)
		(width 0.1)
		(layer "B.Cu")
		(net 1)
	)
	(segment
		(start 114.46 94.21)
		(end 114.5 94.25)
		(width 0.2)
		(layer "B.Cu")
		(net 1)
	)
	(segment
		(start 125.6085 144.803)
		(end 126.3345 144.803)
		(width 0.2)
		(layer "B.Cu")
		(net 1)
	)
	(segment
		(start 65.56 110.46)
		(end 65.6 110.5)
		(width 0.2)
		(layer "B.Cu")
		(net 1)
	)
	(segment
		(start 112.81 69.49)
		(end 112.81 70.61)
		(width 0.3)
		(layer "B.Cu")
		(net 1)
	)
	(segment
		(start 224.53 79.9)
		(end 224.53 80.48)
		(width 0.2)
		(layer "B.Cu")
		(net 1)
	)
	(segment
		(start 122.905 144.285)
		(end 122.905 143.305)
		(width 0.3)
		(layer "B.Cu")
		(net 1)
	)
	(segment
		(start 112.512 103.249)
		(end 112.5 103.261)
		(width 0.15)
		(layer "B.Cu")
		(net 1)
	)
	(segment
		(start 133.698 151.098)
		(end 133.8 151.2)
		(width 0.1)
		(layer "B.Cu")
		(net 1)
	)
	(segment
		(start 178.885 78.285)
		(end 179.2 78.6)
		(width 0.2)
		(layer "B.Cu")
		(net 1)
	)
	(segment
		(start 112.511 120.261)
		(end 112.5 120.25)
		(width 0.2)
		(layer "B.Cu")
		(net 1)
	)
	(segment
		(start 107.78 70.11)
		(end 108.33 70.66)
		(width 0.3)
		(layer "B.Cu")
		(net 1)
	)
	(segment
		(start 120.18 152.88)
		(end 120.2 152.9)
		(width 0.2)
		(layer "B.Cu")
		(net 1)
	)
	(segment
		(start 212.821 62.504)
		(end 211.800999 62.504)
		(width 0.3)
		(layer "B.Cu")
		(net 1)
	)
	(segment
		(start 138.58 65.68)
		(end 138.6 65.7)
		(width 0.2)
		(layer "B.Cu")
		(net 1)
	)
	(segment
		(start 113.711 128.26)
		(end 112.64 128.26)
		(width 0.1)
		(layer "B.Cu")
		(net 1)
	)
	(segment
		(start 208.28 80.3)
		(end 208.28 80.32)
		(width 0.1)
		(layer "B.Cu")
		(net 1)
	)
	(segment
		(start 139.2 61.277)
		(end 139.2 62.6)
		(width 0.2)
		(layer "B.Cu")
		(net 1)
	)
	(segment
		(start 105.88 58.32)
		(end 105.095 58.32)
		(width 0.2)
		(layer "B.Cu")
		(net 1)
	)
	(segment
		(start 121.34 70.459468)
		(end 121.34 69.44)
		(width 0.3)
		(layer "B.Cu")
		(net 1)
	)
	(segment
		(start 98.4 60.748)
		(end 98.752 60.748)
		(width 0.1)
		(layer "B.Cu")
		(net 1)
	)
	(segment
		(start 217.6 97.8)
		(end 218.624618 97.8)
		(width 0.1)
		(layer "B.Cu")
		(net 1)
	)
	(segment
		(start 113.685 113.748)
		(end 112.752 113.748)
		(width 0.2)
		(layer "B.Cu")
		(net 1)
	)
	(segment
		(start 223.579 122.939)
		(end 224.04 123.4)
		(width 0.1)
		(layer "B.Cu")
		(net 1)
	)
	(segment
		(start 201.3 130.02)
		(end 200.3 130.02)
		(width 0.2)
		(layer "B.Cu")
		(net 1)
	)
	(segment
		(start 113.711 135.76)
		(end 112.51 135.76)
		(width 0.2)
		(layer "B.Cu")
		(net 1)
	)
	(segment
		(start 120.365 144.285)
		(end 120.365 143.265)
		(width 0.3)
		(layer "B.Cu")
		(net 1)
	)
	(segment
		(start 112.512 97.249)
		(end 112.5 97.261)
		(width 0.15)
		(layer "B.Cu")
		(net 1)
	)
	(segment
		(start 113.685 95.251)
		(end 112.11 95.251)
		(width 0.15)
		(layer "B.Cu")
		(net 1)
	)
	(segment
		(start 214.3 91.8)
		(end 214.4 91.7)
		(width 0.1)
		(layer "B.Cu")
		(net 1)
	)
	(segment
		(start 220.3 75.4)
		(end 220 75.1)
		(width 0.2)
		(layer "B.Cu")
		(net 1)
	)
	(segment
		(start 234.85 62.934468)
		(end 234.809468 62.975)
		(width 0.2)
		(layer "B.Cu")
		(net 1)
	)
	(segment
		(start 125.3 112)
		(end 126.1 112)
		(width 0.2)
		(layer "B.Cu")
		(net 1)
	)
	(segment
		(start 178.15 86.753)
		(end 179 86.753)
		(width 0.2)
		(layer "B.Cu")
		(net 1)
	)
	(segment
		(start 229.59 113.8)
		(end 229.57 113.8)
		(width 0.5)
		(layer "B.Cu")
		(net 1)
	)
	(segment
		(start 208.157 58.39)
		(end 208.157 59.491808)
		(width 0.25)
		(layer "B.Cu")
		(net 1)
	)
	(segment
		(start 121.635 144.285)
		(end 121.635 143.265)
		(width 0.3)
		(layer "B.Cu")
		(net 1)
	)
	(segment
		(start 179 86)
		(end 179 86.753)
		(width 0.2)
		(layer "B.Cu")
		(net 1)
	)
	(segment
		(start 147.13 61.97)
		(end 147.13 61.297)
		(width 0.2)
		(layer "B.Cu")
		(net 1)
	)
	(segment
		(start 227.69 56.26)
		(end 227.7 56.25)
		(width 0.1)
		(layer "B.Cu")
		(net 1)
	)
	(segment
		(start 217.7 87.8)
		(end 218.3 88.4)
		(width 0.1)
		(layer "B.Cu")
		(net 1)
	)
	(segment
		(start 201.28 124.2)
		(end 201.28 123.22)
		(width 0.2)
		(layer "B.Cu")
		(net 1)
	)
	(segment
		(start 120.4 143.1)
		(end 120.4 144.25)
		(width 0.3)
		(layer "B.Cu")
		(net 1)
	)
	(segment
		(start 101 66.5)
		(end 101 67.5)
		(width 0.2)
		(layer "B.Cu")
		(net 1)
	)
	(segment
		(start 95.9 65.65)
		(end 96.248 65.998)
		(width 0.2)
		(layer "B.Cu")
		(net 1)
	)
	(segment
		(start 125.65 97.85)
		(end 125.3 98.2)
		(width 0.2)
		(layer "B.Cu")
		(net 1)
	)
	(segment
		(start 121.635 143.335)
		(end 121.4 143.1)
		(width 0.3)
		(layer "B.Cu")
		(net 1)
	)
	(segment
		(start 199.65 67.78)
		(end 199.89 68.02)
		(width 0.2)
		(layer "B.Cu")
		(net 1)
	)
	(segment
		(start 179.75 82.5)
		(end 178.84 82.5)
		(width 0.2)
		(layer "B.Cu")
		(net 1)
	)
	(segment
		(start 114.46 114.85)
		(end 113.6 114.85)
		(width 0.2)
		(layer "B.Cu")
		(net 1)
	)
	(segment
		(start 215.538 75.490532)
		(end 215.538 74.738)
		(width 0.1)
		(layer "B.Cu")
		(net 1)
	)
	(segment
		(start 220.75 83.65)
		(end 220.35 83.25)
		(width 0.2)
		(layer "B.Cu")
		(net 1)
	)
	(segment
		(start 235.806 74.6)
		(end 236.57 74.6)
		(width 0.1)
		(layer "B.Cu")
		(net 1)
	)
	(segment
		(start 135.725 54.5)
		(end 136.33 55.105)
		(width 0.1)
		(layer "B.Cu")
		(net 1)
	)
	(segment
		(start 179.099 75.099)
		(end 179.2 75.2)
		(width 0.2)
		(layer "B.Cu")
		(net 1)
	)
	(segment
		(start 112.51 135.76)
		(end 112.5 135.75)
		(width 0.2)
		(layer "B.Cu")
		(net 1)
	)
	(segment
		(start 113.671 131.3)
		(end 113.711 131.26)
		(width 0.1)
		(layer "B.Cu")
		(net 1)
	)
	(segment
		(start 215 88.68)
		(end 215.52 89.2)
		(width 0.1)
		(layer "B.Cu")
		(net 1)
	)
	(segment
		(start 138.202 61.277)
		(end 138.202 60.505)
		(width 0.2)
		(layer "B.Cu")
		(net 1)
	)
	(segment
		(start 169.65 61.298)
		(end 170.697 61.298)
		(width 0.1)
		(layer "B.Cu")
		(net 1)
	)
	(segment
		(start 220.35 83.25)
		(end 220.35 82.83)
		(width 0.2)
		(layer "B.Cu")
		(net 1)
	)
	(segment
		(start 196.6 132.13)
		(end 196.6 132.85)
		(width 0.1)
		(layer "B.Cu")
		(net 1)
	)
	(segment
		(start 122.9 143.1)
		(end 123.1 143.1)
		(width 0.3)
		(layer "B.Cu")
		(net 1)
	)
	(segment
		(start 101.77 62.48)
		(end 101.75 62.5)
		(width 0.2)
		(layer "B.Cu")
		(net 1)
	)
	(segment
		(start 225.002 109.302)
		(end 225 109.3)
		(width 0.1)
		(layer "B.Cu")
		(net 1)
	)
	(segment
		(start 95.9 65.65)
		(end 95.9 65.1)
		(width 0.2)
		(layer "B.Cu")
		(net 1)
	)
	(segment
		(start 113.685 100.249)
		(end 112.512 100.249)
		(width 0.15)
		(layer "B.Cu")
		(net 1)
	)
	(segment
		(start 236.38 133)
		(end 237.2 133)
		(width 0.1)
		(layer "B.Cu")
		(net 1)
	)
	(segment
		(start 205.409 145.01)
		(end 204.486 145.01)
		(width 0.1)
		(layer "B.Cu")
		(net 1)
	)
	(segment
		(start 198.856 143.9)
		(end 198.476 143.52)
		(width 0.2)
		(layer "B.Cu")
		(net 1)
	)
	(segment
		(start 201.3 129.2)
		(end 201.5 129)
		(width 0.2)
		(layer "B.Cu")
		(net 1)
	)
	(segment
		(start 116.3 70.6)
		(end 116.3 69.604468)
		(width 0.3)
		(layer "B.Cu")
		(net 1)
	)
	(segment
		(start 122.905 143.295)
		(end 123.1 143.1)
		(width 0.3)
		(layer "B.Cu")
		(net 1)
	)
	(segment
		(start 163.4 64.2)
		(end 163.4 64.6)
		(width 0.3)
		(layer "B.Cu")
		(net 1)
	)
	(segment
		(start 212.12 73.18)
		(end 212.12 72.011)
		(width 0.3)
		(layer "B.Cu")
		(net 1)
	)
	(segment
		(start 220.82 94.72)
		(end 220.5 94.4)
		(width 0.1)
		(layer "B.Cu")
		(net 1)
	)
	(segment
		(start 102.98 65.27)
		(end 103 65.25)
		(width 0.2)
		(layer "B.Cu")
		(net 1)
	)
	(segment
		(start 107.78 69.48)
		(end 107.78 70.11)
		(width 0.3)
		(layer "B.Cu")
		(net 1)
	)
	(segment
		(start 177.05 60.2)
		(end 176.706998 60.543002)
		(width 0.1)
		(layer "B.Cu")
		(net 1)
	)
	(segment
		(start 142.6 65.68)
		(end 142.52 65.68)
		(width 0.2)
		(layer "B.Cu")
		(net 1)
	)
	(segment
		(start 112.29 70.62)
		(end 112.8 70.62)
		(width 0.3)
		(layer "B.Cu")
		(net 1)
	)
	(segment
		(start 60.65 82.36)
		(end 60.65 81.45)
		(width 0.1)
		(layer "B.Cu")
		(net 1)
	)
	(segment
		(start 126.15 97.85)
		(end 125.65 97.85)
		(width 0.2)
		(layer "B.Cu")
		(net 1)
	)
	(segment
		(start 147.13 60.525)
		(end 147.13 61.297)
		(width 0.2)
		(layer "B.Cu")
		(net 1)
	)
	(segment
		(start 112.509 138.759)
		(end 112.5 138.75)
		(width 0.2)
		(layer "B.Cu")
		(net 1)
	)
	(segment
		(start 212.875 62.45)
		(end 212.821 62.504)
		(width 0.3)
		(layer "B.Cu")
		(net 1)
	)
	(segment
		(start 218.03 113.03)
		(end 217.539 112.539)
		(width 0.1)
		(layer "B.Cu")
		(net 1)
	)
	(segment
		(start 130.5575 148.301)
		(end 129.8325 148.301)
		(width 0.2)
		(layer "B.Cu")
		(net 1)
	)
	(segment
		(start 222.702 109.302)
		(end 222.7 109.3)
		(width 0.1)
		(layer "B.Cu")
		(net 1)
	)
	(segment
		(start 112.512 100.249)
		(end 112.5 100.261)
		(width 0.15)
		(layer "B.Cu")
		(net 1)
	)
	(segment
		(start 89.9 78.42)
		(end 89.500532 78.42)
		(width 0.2)
		(layer "B.Cu")
		(net 1)
	)
	(segment
		(start 178.15 90.053)
		(end 178.797 90.053)
		(width 0.2)
		(layer "B.Cu")
		(net 1)
	)
	(segment
		(start 60.65 82.66)
		(end 60.8 82.51)
		(width 0.1)
		(layer "B.Cu")
		(net 1)
	)
	(segment
		(start 89.500532 78.42)
		(end 89.230532 78.15)
		(width 0.2)
		(layer "B.Cu")
		(net 1)
	)
	(segment
		(start 197.82 64.82)
		(end 197.4 64.4)
		(width 0.2)
		(layer "B.Cu")
		(net 1)
	)
	(segment
		(start 225.665 79.815)
		(end 226.1 80.25)
		(width 0.2)
		(layer "B.Cu")
		(net 1)
	)
	(segment
		(start 229.07 129.6)
		(end 229.37 129.6)
		(width 0.2)
		(layer "B.Cu")
		(net 1)
	)
	(segment
		(start 213.28 89.8)
		(end 213.9 89.18)
		(width 0.1)
		(layer "B.Cu")
		(net 1)
	)
	(segment
		(start 168 65.1)
		(end 168 63.3)
		(width 0.3)
		(layer "F.Cu")
		(net 2)
	)
	(segment
		(start 147 121.2)
		(end 147.32 120.88)
		(width 0.2)
		(layer "F.Cu")
		(net 2)
	)
	(segment
		(start 189.976 140.1)
		(end 189.976 138.15)
		(width 0.1)
		(layer "F.Cu")
		(net 2)
	)
	(segment
		(start 153.8 97.2)
		(end 154 97)
		(width 0.2)
		(layer "F.Cu")
		(net 2)
	)
	(segment
		(start 210.599132 92.592)
		(end 211.992 92.592)
		(width 0.2)
		(layer "F.Cu")
		(net 2)
	)
	(segment
		(start 187.499 123.499)
		(end 186.919001 123.499)
		(width 0.2)
		(layer "F.Cu")
		(net 2)
	)
	(segment
		(start 61.5 97.9)
		(end 61.5 95.425)
		(width 0.75)
		(layer "F.Cu")
		(net 2)
	)
	(segment
		(start 203.95 79.48)
		(end 204.52 79.48)
		(width 0.2)
		(layer "F.Cu")
		(net 2)
	)
	(segment
		(start 87.83 145.65)
		(end 87.83 146.550498)
		(width 0.2)
		(layer "F.Cu")
		(net 2)
	)
	(segment
		(start 201.753 131.488)
		(end 201.753 132.547)
		(width 0.2)
		(layer "F.Cu")
		(net 2)
	)
	(segment
		(start 216.8 119.62)
		(end 217.48 119.62)
		(width 0.2)
		(layer "F.Cu")
		(net 2)
	)
	(segment
		(start 199.565 127.3)
		(end 197.68 127.3)
		(width 0.2)
		(layer "F.Cu")
		(net 2)
	)
	(segment
		(start 60.824 111.44)
		(end 64.8 107.464)
		(width 0.75)
		(layer "F.Cu")
		(net 2)
	)
	(segment
		(start 64.2 89.2)
		(end 63.8 88.8)
		(width 0.5)
		(layer "F.Cu")
		(net 2)
	)
	(segment
		(start 62.2 102.1)
		(end 61.5 101.4)
		(width 0.75)
		(layer "F.Cu")
		(net 2)
	)
	(segment
		(start 217.6 84.78)
		(end 218.38 84.78)
		(width 0.2)
		(layer "F.Cu")
		(net 2)
	)
	(segment
		(start 218.38 84.78)
		(end 218.4 84.8)
		(width 0.2)
		(layer "F.Cu")
		(net 2)
	)
	(segment
		(start 61.05 86.43)
		(end 61.57 85.91)
		(width 0.2)
		(layer "F.Cu")
		(net 2)
	)
	(segment
		(start 203.1 118.38)
		(end 203.1 118.4)
		(width 0.1)
		(layer "F.Cu")
		(net 2)
	)
	(segment
		(start 61.5 101.4)
		(end 61.5 98.7)
		(width 0.75)
		(layer "F.Cu")
		(net 2)
	)
	(segment
		(start 100.8 123.3)
		(end 100.6 123.1)
		(width 0.5)
		(layer "F.Cu")
		(net 2)
	)
	(segment
		(start 87.83 146.550498)
		(end 88.171001 146.891499)
		(width 0.2)
		(layer "F.Cu")
		(net 2)
	)
	(segment
		(start 147.32 120.88)
		(end 147.32 117.2)
		(width 0.2)
		(layer "F.Cu")
		(net 2)
	)
	(segment
		(start 172.79 63.01)
		(end 172.6 63.2)
		(width 0.1)
		(layer "F.Cu")
		(net 2)
	)
	(segment
		(start 203.1 118.7)
		(end 203.1 118.4)
		(width 0.2)
		(layer "F.Cu")
		(net 2)
	)
	(segment
		(start 189.986 149.7)
		(end 188.426 149.7)
		(width 0.1)
		(layer "F.Cu")
		(net 2)
	)
	(segment
		(start 216.72 93.32)
		(end 216.4 93)
		(width 0.2)
		(layer "F.Cu")
		(net 2)
	)
	(segment
		(start 212 92.1)
		(end 212 92.6)
		(width 0.2)
		(layer "F.Cu")
		(net 2)
	)
	(segment
		(start 61.5 98.7)
		(end 61.5 97.9)
		(width 0.75)
		(layer "F.Cu")
		(net 2)
	)
	(segment
		(start 205.353 131.488)
		(end 205.353 132.197)
		(width 0.2)
		(layer "F.Cu")
		(net 2)
	)
	(segment
		(start 62.6 83.6)
		(end 63.8 83.6)
		(width 0.2)
		(layer "F.Cu")
		(net 2)
	)
	(segment
		(start 168.81 63.01)
		(end 168.81 62.01)
		(width 0.3)
		(layer "F.Cu")
		(net 2)
	)
	(segment
		(start 152.724 109.736)
		(end 152.96 109.5)
		(width 0.2)
		(layer "F.Cu")
		(net 2)
	)
	(segment
		(start 172.6 63.2)
		(end 169 63.2)
		(width 0.1)
		(layer "F.Cu")
		(net 2)
	)
	(segment
		(start 173.24 63.01)
		(end 172.79 63.01)
		(width 0.1)
		(layer "F.Cu")
		(net 2)
	)
	(segment
		(start 100.8 126.6)
		(end 101.4 127.2)
		(width 0.5)
		(layer "F.Cu")
		(net 2)
	)
	(segment
		(start 88.171001 146.891499)
		(end 89.55 146.891499)
		(width 0.2)
		(layer "F.Cu")
		(net 2)
	)
	(segment
		(start 63.8 102.1)
		(end 62.2 102.1)
		(width 0.75)
		(layer "F.Cu")
		(net 2)
	)
	(segment
		(start 212.4 135.68)
		(end 211.443 135.68)
		(width 0.2)
		(layer "F.Cu")
		(net 2)
	)
	(segment
		(start 212.565632 91.972856)
		(end 212.127144 91.972856)
		(width 0.2)
		(layer "F.Cu")
		(net 2)
	)
	(segment
		(start 62.7 94.225)
		(end 63.375 94.225)
		(width 0.75)
		(layer "F.Cu")
		(net 2)
	)
	(segment
		(start 198.5 121.9)
		(end 198.6 121.8)
		(width 0.2)
		(layer "F.Cu")
		(net 2)
	)
	(segment
		(start 197.726 145.5)
		(end 199.226 145.5)
		(width 0.2)
		(layer "F.Cu")
		(net 2)
	)
	(segment
		(start 216.72 94.2)
		(end 216.72 93.32)
		(width 0.2)
		(layer "F.Cu")
		(net 2)
	)
	(segment
		(start 152.325001 107.154999)
		(end 151.98 107.5)
		(width 0.2)
		(layer "F.Cu")
		(net 2)
	)
	(segment
		(start 204.8 79.2)
		(end 204.9 79.2)
		(width 0.2)
		(layer "F.Cu")
		(net 2)
	)
	(segment
		(start 151.675 106.21)
		(end 151.19 106.21)
		(width 0.2)
		(layer "F.Cu")
		(net 2)
	)
	(segment
		(start 136.5 103.35)
		(end 138.45 103.35)
		(width 0.2)
		(layer "F.Cu")
		(net 2)
	)
	(segment
		(start 139.431999 106.5)
		(end 139.431999 105.8)
		(width 0.2)
		(layer "F.Cu")
		(net 2)
	)
	(segment
		(start 64.105 97.45)
		(end 64 97.555)
		(width 0.2)
		(layer "F.Cu")
		(net 2)
	)
	(segment
		(start 199.565 125.3)
		(end 198.5 125.3)
		(width 0.2)
		(layer "F.Cu")
		(net 2)
	)
	(segment
		(start 135.52 106.93)
		(end 134.73 106.93)
		(width 0.2)
		(layer "F.Cu")
		(net 2)
	)
	(segment
		(start 197.695 121.9)
		(end 198.5 121.9)
		(width 0.2)
		(layer "F.Cu")
		(net 2)
	)
	(segment
		(start 170.6 132.3)
		(end 170.6 131.4)
		(width 0.1)
		(layer "F.Cu")
		(net 2)
	)
	(segment
		(start 203.755 119.911)
		(end 203.755 119.355)
		(width 0.2)
		(layer "F.Cu")
		(net 2)
	)
	(segment
		(start 151.05 106.6)
		(end 151.95 107.5)
		(width 0.2)
		(layer "F.Cu")
		(net 2)
	)
	(segment
		(start 138.931999 106.5)
		(end 138.931999 105.868001)
		(width 0.2)
		(layer "F.Cu")
		(net 2)
	)
	(segment
		(start 169 63.2)
		(end 168.81 63.01)
		(width 0.1)
		(layer "F.Cu")
		(net 2)
	)
	(segment
		(start 153.019999 96.019999)
		(end 153.7 96.7)
		(width 0.2)
		(layer "F.Cu")
		(net 2)
	)
	(segment
		(start 215.864632 86.560368)
		(end 216.6 85.825)
		(width 0.2)
		(layer "F.Cu")
		(net 2)
	)
	(segment
		(start 216.2 93.2)
		(end 216.4 93)
		(width 0.2)
		(layer "F.Cu")
		(net 2)
	)
	(segment
		(start 157.8 115.4)
		(end 157.2 114.8)
		(width 0.2)
		(layer "F.Cu")
		(net 2)
	)
	(segment
		(start 153.019999 96)
		(end 153.019999 96.019999)
		(width 0.2)
		(layer "F.Cu")
		(net 2)
	)
	(segment
		(start 170.44 131.24)
		(end 169.674468 131.24)
		(width 0.1)
		(layer "F.Cu")
		(net 2)
	)
	(segment
		(start 213.805 95.88)
		(end 213.88 95.88)
		(width 0.3)
		(layer "F.Cu")
		(net 2)
	)
	(segment
		(start 153.7 96.7)
		(end 153.9 96.7)
		(width 0.2)
		(layer "F.Cu")
		(net 2)
	)
	(segment
		(start 166.25 57.12)
		(end 166.25 58)
		(width 0.1)
		(layer "F.Cu")
		(net 2)
	)
	(segment
		(start 204.9 79.2)
		(end 204.905 79.205)
		(width 0.2)
		(layer "F.Cu")
		(net 2)
	)
	(segment
		(start 215.864632 86.872856)
		(end 215.864632 86.560368)
		(width 0.2)
		(layer "F.Cu")
		(net 2)
	)
	(segment
		(start 152 121.5)
		(end 150.3 121.5)
		(width 0.2)
		(layer "F.Cu")
		(net 2)
	)
	(segment
		(start 217.48 119.62)
		(end 217.5 119.6)
		(width 0.2)
		(layer "F.Cu")
		(net 2)
	)
	(segment
		(start 211.443 135.68)
		(end 211.286 135.837)
		(width 0.2)
		(layer "F.Cu")
		(net 2)
	)
	(segment
		(start 190.12 82.4)
		(end 190.12 83.18)
		(width 0.1)
		(layer "F.Cu")
		(net 2)
	)
	(segment
		(start 138.45 103.35)
		(end 138.8 103.7)
		(width 0.2)
		(layer "F.Cu")
		(net 2)
	)
	(segment
		(start 197.726 144.7)
		(end 199.176 144.7)
		(width 0.2)
		(layer "F.Cu")
		(net 2)
	)
	(segment
		(start 195.82 73.02)
		(end 195.8 73)
		(width 0.1)
		(layer "F.Cu")
		(net 2)
	)
	(segment
		(start 204.52 79.48)
		(end 204.8 79.2)
		(width 0.2)
		(layer "F.Cu")
		(net 2)
	)
	(segment
		(start 100.8 127.2)
		(end 100.8 126.6)
		(width 0.5)
		(layer "F.Cu")
		(net 2)
	)
	(segment
		(start 63.8 83.6)
		(end 64.25 84.05)
		(width 0.2)
		(layer "F.Cu")
		(net 2)
	)
	(segment
		(start 152.699999 97.175)
		(end 152.699999 96.32)
		(width 0.2)
		(layer "F.Cu")
		(net 2)
	)
	(segment
		(start 210.313 135.837)
		(end 211.286 135.837)
		(width 0.3)
		(layer "F.Cu")
		(net 2)
	)
	(segment
		(start 209.754 131.488)
		(end 209.754 133.084)
		(width 0.2)
		(layer "F.Cu")
		(net 2)
	)
	(segment
		(start 204.905 79.205)
		(end 205.52 79.205)
		(width 0.2)
		(layer "F.Cu")
		(net 2)
	)
	(segment
		(start 61.57 84.63)
		(end 62.6 83.6)
		(width 0.2)
		(layer "F.Cu")
		(net 2)
	)
	(segment
		(start 61.9 98.3)
		(end 61.5 97.9)
		(width 0.2)
		(layer "F.Cu")
		(net 2)
	)
	(segment
		(start 152.325001 106.235)
		(end 152.325001 107.154999)
		(width 0.2)
		(layer "F.Cu")
		(net 2)
	)
	(segment
		(start 170.6 131.4)
		(end 170.44 131.24)
		(width 0.1)
		(layer "F.Cu")
		(net 2)
	)
	(segment
		(start 61.463 88.663)
		(end 61.463 87.741)
		(width 0.5)
		(layer "F.Cu")
		(net 2)
	)
	(segment
		(start 152.724 110.75)
		(end 152.724 109.736)
		(width 0.2)
		(layer "F.Cu")
		(net 2)
	)
	(segment
		(start 151.19 106.21)
		(end 151.05 106.35)
		(width 0.2)
		(layer "F.Cu")
		(net 2)
	)
	(segment
		(start 213.865632 86.872856)
		(end 213.865632 85.634368)
		(width 0.2)
		(layer "F.Cu")
		(net 2)
	)
	(segment
		(start 199.176 144.7)
		(end 199.226 144.75)
		(width 0.2)
		(layer "F.Cu")
		(net 2)
	)
	(segment
		(start 201.22 135.7)
		(end 200.4 135.7)
		(width 0.1)
		(layer "F.Cu")
		(net 2)
	)
	(segment
		(start 100.8 126.6)
		(end 101.4 126.6)
		(width 0.5)
		(layer "F.Cu")
		(net 2)
	)
	(segment
		(start 101.4 127.2)
		(end 101.4 126.6)
		(width 0.5)
		(layer "F.Cu")
		(net 2)
	)
	(segment
		(start 61.57 85.91)
		(end 61.57 84.63)
		(width 0.2)
		(layer "F.Cu")
		(net 2)
	)
	(segment
		(start 190.12 82.4)
		(end 190.12 81.4)
		(width 0.1)
		(layer "F.Cu")
		(net 2)
	)
	(segment
		(start 210.155 119.911)
		(end 210.155 119.065)
		(width 0.2)
		(layer "F.Cu")
		(net 2)
	)
	(segment
		(start 216.6 85.825)
		(end 216.6 84.78)
		(width 0.2)
		(layer "F.Cu")
		(net 2)
	)
	(segment
		(start 134.7 105.15)
		(end 136.5 103.35)
		(width 0.2)
		(layer "F.Cu")
		(net 2)
	)
	(segment
		(start 152.96 109.5)
		(end 153.8 109.5)
		(width 0.2)
		(layer "F.Cu")
		(net 2)
	)
	(segment
		(start 138.931999 105.868001)
		(end 139 105.8)
		(width 0.2)
		(layer "F.Cu")
		(net 2)
	)
	(segment
		(start 201.753 132.547)
		(end 201.7 132.6)
		(width 0.2)
		(layer "F.Cu")
		(net 2)
	)
	(segment
		(start 90.231499 146.891499)
		(end 90.24 146.9)
		(width 0.2)
		(layer "F.Cu")
		(net 2)
	)
	(segment
		(start 153.019999 96)
		(end 153.019999 95.480001)
		(width 0.2)
		(layer "F.Cu")
		(net 2)
	)
	(segment
		(start 61.9 98.3)
		(end 61.5 98.7)
		(width 0.2)
		(layer "F.Cu")
		(net 2)
	)
	(segment
		(start 213.3 135.7)
		(end 212.42 135.7)
		(width 0.2)
		(layer "F.Cu")
		(net 2)
	)
	(segment
		(start 64.2 89.9)
		(end 64.2 89.2)
		(width 0.5)
		(layer "F.Cu")
		(net 2)
	)
	(segment
		(start 152.699999 96.32)
		(end 153.019999 96)
		(width 0.2)
		(layer "F.Cu")
		(net 2)
	)
	(segment
		(start 89.55 146.891499)
		(end 90.231499 146.891499)
		(width 0.2)
		(layer "F.Cu")
		(net 2)
	)
	(segment
		(start 153.019999 95.480001)
		(end 153.1 95.4)
		(width 0.2)
		(layer "F.Cu")
		(net 2)
	)
	(segment
		(start 214.48 133.8)
		(end 215.2 133.8)
		(width 0.1)
		(layer "F.Cu")
		(net 2)
	)
	(segment
		(start 134.73 106.93)
		(end 134.7 106.9)
		(width 0.2)
		(layer "F.Cu")
		(net 2)
	)
	(segment
		(start 211.992 92.592)
		(end 212 92.6)
		(width 0.2)
		(layer "F.Cu")
		(net 2)
	)
	(segment
		(start 139.431999 105.311999)
		(end 139.4 105.28)
		(width 0.2)
		(layer "F.Cu")
		(net 2)
	)
	(segment
		(start 61.9 98.3)
		(end 63.12 98.3)
		(width 0.2)
		(layer "F.Cu")
		(net 2)
	)
	(segment
		(start 209.77 133.1)
		(end 209.77 133.47)
		(width 0.2)
		(layer "F.Cu")
		(net 2)
	)
	(segment
		(start 194 127.3)
		(end 194.62 127.3)
		(width 0.2)
		(layer "F.Cu")
		(net 2)
	)
	(segment
		(start 64.8 107.464)
		(end 64.8 103.1)
		(width 0.75)
		(layer "F.Cu")
		(net 2)
	)
	(segment
		(start 67.4 83.3)
		(end 67.4 82.2)
		(width 0.2)
		(layer "F.Cu")
		(net 2)
	)
	(segment
		(start 139.431999 105.8)
		(end 139.431999 105.311999)
		(width 0.2)
		(layer "F.Cu")
		(net 2)
	)
	(segment
		(start 154 97)
		(end 154 96.8)
		(width 0.2)
		(layer "F.Cu")
		(net 2)
	)
	(segment
		(start 154 96.8)
		(end 153.9 96.7)
		(width 0.2)
		(layer "F.Cu")
		(net 2)
	)
	(segment
		(start 213.8 107.48)
		(end 213.8 108.2)
		(width 0.1)
		(layer "F.Cu")
		(net 2)
	)
	(segment
		(start 213.88 95.88)
		(end 214.4 96.4)
		(width 0.3)
		(layer "F.Cu")
		(net 2)
	)
	(segment
		(start 198.7 121.7)
		(end 198.6 121.8)
		(width 0.2)
		(layer "F.Cu")
		(net 2)
	)
	(segment
		(start 201.7 132.6)
		(end 201.7 133.22)
		(width 0.2)
		(layer "F.Cu")
		(net 2)
	)
	(segment
		(start 65.15 97.45)
		(end 64.105 97.45)
		(width 0.2)
		(layer "F.Cu")
		(net 2)
	)
	(segment
		(start 140.62 135.77)
		(end 140.65 135.8)
		(width 0.3)
		(layer "F.Cu")
		(net 2)
	)
	(segment
		(start 212.127144 91.972856)
		(end 212 92.1)
		(width 0.2)
		(layer "F.Cu")
		(net 2)
	)
	(segment
		(start 63.8 88.8)
		(end 61.6 88.8)
		(width 0.5)
		(layer "F.Cu")
		(net 2)
	)
	(segment
		(start 134.7 106.9)
		(end 134.7 105.15)
		(width 0.2)
		(layer "F.Cu")
		(net 2)
	)
	(segment
		(start 216.6 84.78)
		(end 217.6 84.78)
		(width 0.2)
		(layer "F.Cu")
		(net 2)
	)
	(segment
		(start 151.05 106.35)
		(end 151.05 106.6)
		(width 0.2)
		(layer "F.Cu")
		(net 2)
	)
	(segment
		(start 63.12 98.3)
		(end 63.9 97.52)
		(width 0.2)
		(layer "F.Cu")
		(net 2)
	)
	(segment
		(start 61.6 88.8)
		(end 61.463 88.663)
		(width 0.5)
		(layer "F.Cu")
		(net 2)
	)
	(segment
		(start 64.25 84.05)
		(end 64.25 85.47)
		(width 0.2)
		(layer "F.Cu")
		(net 2)
	)
	(segment
		(start 138.8 103.7)
		(end 138.8 104.68)
		(width 0.2)
		(layer "F.Cu")
		(net 2)
	)
	(segment
		(start 63.375 94.225)
		(end 64.2 93.4)
		(width 0.75)
		(layer "F.Cu")
		(net 2)
	)
	(segment
		(start 196.6 73.02)
		(end 195.82 73.02)
		(width 0.1)
		(layer "F.Cu")
		(net 2)
	)
	(segment
		(start 190.12 83.18)
		(end 190.1 83.2)
		(width 0.1)
		(layer "F.Cu")
		(net 2)
	)
	(segment
		(start 61.5 95.425)
		(end 62.7 94.225)
		(width 0.75)
		(layer "F.Cu")
		(net 2)
	)
	(segment
		(start 170.304468 132.595532)
		(end 170.6 132.3)
		(width 0.1)
		(layer "F.Cu")
		(net 2)
	)
	(segment
		(start 215.864632 92.670856)
		(end 215.864632 93.064632)
		(width 0.2)
		(layer "F.Cu")
		(net 2)
	)
	(segment
		(start 203.755 119.355)
		(end 203.1 118.7)
		(width 0.2)
		(layer "F.Cu")
		(net 2)
	)
	(segment
		(start 168 63.3)
		(end 168.29 63.01)
		(width 0.3)
		(layer "F.Cu")
		(net 2)
	)
	(segment
		(start 138.8 104.68)
		(end 139.4 105.28)
		(width 0.2)
		(layer "F.Cu")
		(net 2)
	)
	(segment
		(start 194.62 125.3)
		(end 194.62 127.3)
		(width 0.2)
		(layer "F.Cu")
		(net 2)
	)
	(segment
		(start 168.29 63.01)
		(end 168.81 63.01)
		(width 0.3)
		(layer "F.Cu")
		(net 2)
	)
	(segment
		(start 215.864632 93.064632)
		(end 216 93.2)
		(width 0.2)
		(layer "F.Cu")
		(net 2)
	)
	(segment
		(start 67.8 83.7)
		(end 67.4 83.3)
		(width 0.2)
		(layer "F.Cu")
		(net 2)
	)
	(segment
		(start 140.62 135.05)
		(end 140.62 135.77)
		(width 0.3)
		(layer "F.Cu")
		(net 2)
	)
	(segment
		(start 209.754 133.084)
		(end 209.77 133.1)
		(width 0.2)
		(layer "F.Cu")
		(net 2)
	)
	(segment
		(start 209.77 133.47)
		(end 210 133.7)
		(width 0.2)
		(layer "F.Cu")
		(net 2)
	)
	(segment
		(start 168.81 62.01)
		(end 168.4 61.6)
		(width 0.3)
		(layer "F.Cu")
		(net 2)
	)
	(segment
		(start 67.4 82.2)
		(end 64.5 79.3)
		(width 0.2)
		(layer "F.Cu")
		(net 2)
	)
	(segment
		(start 61.463 86.843)
		(end 61.05 86.43)
		(width 0.2)
		(layer "F.Cu")
		(net 2)
	)
	(segment
		(start 67.8 85.4)
		(end 67.8 83.7)
		(width 0.2)
		(layer "F.Cu")
		(net 2)
	)
	(segment
		(start 101.4 127.2)
		(end 100.8 127.2)
		(width 0.5)
		(layer "F.Cu")
		(net 2)
	)
	(segment
		(start 210.155 119.065)
		(end 210.92 118.3)
		(width 0.2)
		(layer "F.Cu")
		(net 2)
	)
	(segment
		(start 199.565 121.7)
		(end 198.7 121.7)
		(width 0.2)
		(layer "F.Cu")
		(net 2)
	)
	(segment
		(start 61.463 87.741)
		(end 61.463 86.843)
		(width 0.2)
		(layer "F.Cu")
		(net 2)
	)
	(segment
		(start 187.5 123.5)
		(end 187.499 123.499)
		(width 0.2)
		(layer "F.Cu")
		(net 2)
	)
	(segment
		(start 151.95 107.5)
		(end 151.98 107.5)
		(width 0.2)
		(layer "F.Cu")
		(net 2)
	)
	(segment
		(start 139 105.8)
		(end 139.431999 105.8)
		(width 0.2)
		(layer "F.Cu")
		(net 2)
	)
	(segment
		(start 157.2 114.8)
		(end 157.2 111.2)
		(width 0.2)
		(layer "F.Cu")
		(net 2)
	)
	(segment
		(start 153.35 97.2)
		(end 153.8 97.2)
		(width 0.2)
		(layer "F.Cu")
		(net 2)
	)
	(segment
		(start 170.304468 132.64)
		(end 170.304468 132.595532)
		(width 0.1)
		(layer "F.Cu")
		(net 2)
	)
	(segment
		(start 213.865632 85.634368)
		(end 213.9 85.6)
		(width 0.2)
		(layer "F.Cu")
		(net 2)
	)
	(segment
		(start 152.236 120.25)
		(end 152.236 121.264)
		(width 0.2)
		(layer "F.Cu")
		(net 2)
	)
	(segment
		(start 205.353 132.197)
		(end 205.3 132.25)
		(width 0.2)
		(layer "F.Cu")
		(net 2)
	)
	(segment
		(start 197.695 125.3)
		(end 198.5 125.3)
		(width 0.2)
		(layer "F.Cu")
		(net 2)
	)
	(segment
		(start 216 93.2)
		(end 216.2 93.2)
		(width 0.2)
		(layer "F.Cu")
		(net 2)
	)
	(segment
		(start 214.046 103.325)
		(end 212.28 103.325)
		(width 0.3)
		(layer "F.Cu")
		(net 2)
	)
	(segment
		(start 64.2 93.4)
		(end 64.2 89.9)
		(width 0.75)
		(layer "F.Cu")
		(net 2)
	)
	(segment
		(start 212.42 135.7)
		(end 212.4 135.68)
		(width 0.2)
		(layer "F.Cu")
		(net 2)
	)
	(segment
		(start 64.8 103.1)
		(end 63.8 102.1)
		(width 0.75)
		(layer "F.Cu")
		(net 2)
	)
	(segment
		(start 100.8 126.6)
		(end 100.8 123.3)
		(width 0.5)
		(layer "F.Cu")
		(net 2)
	)
	(segment
		(start 152.236 121.264)
		(end 152 121.5)
		(width 0.2)
		(layer "F.Cu")
		(net 2)
	)
	(segment
		(start 60.824 123.474)
		(end 60.824 111.44)
		(width 0.75)
		(layer "F.Cu")
		(net 2)
	)
	(via
		(at 168.5 131.4)
		(size 0.45)
		(drill 0.1)
		(layers "F.Cu" "B.Cu")
		(remove_unused_layers yes)
		(keep_end_layers yes)
		(free yes)
		(zone_layer_connections "In2.Cu")
		(net 2)
	)
	(via
		(at 212.28 103.325)
		(size 0.45)
		(drill 0.1)
		(layers "F.Cu" "B.Cu")
		(net 2)
	)
	(via
		(at 102 127.2)
		(size 0.45)
		(drill 0.1)
		(layers "F.Cu" "B.Cu")
		(free yes)
		(net 2)
	)
	(via
		(at 167.35 130.8)
		(size 0.45)
		(drill 0.1)
		(layers "F.Cu" "B.Cu")
		(remove_unused_layers yes)
		(keep_end_layers yes)
		(free yes)
		(zone_layer_connections "In2.Cu")
		(net 2)
	)
	(via
		(at 200.4 135.7)
		(size 0.45)
		(drill 0.1)
		(layers "F.Cu" "B.Cu")
		(net 2)
	)
	(via
		(at 199.226 144.75)
		(size 0.45)
		(drill 0.1)
		(layers "F.Cu" "B.Cu")
		(net 2)
	)
	(via
		(at 151.95 107.5)
		(size 0.45)
		(drill 0.1)
		(layers "F.Cu" "B.Cu")
		(net 2)
	)
	(via
		(at 168 65.1)
		(size 0.45)
		(drill 0.1)
		(layers "F.Cu" "B.Cu")
		(net 2)
	)
	(via
		(at 102 128.4)
		(size 0.45)
		(drill 0.1)
		(layers "F.Cu" "B.Cu")
		(free yes)
		(net 2)
	)
	(via
		(at 123.8 93.4)
		(size 0.45)
		(drill 0.1)
		(layers "F.Cu" "B.Cu")
		(free yes)
		(net 2)
	)
	(via
		(at 213.3 135.7)
		(size 0.45)
		(drill 0.1)
		(layers "F.Cu" "B.Cu")
		(net 2)
	)
	(via
		(at 123.9 139)
		(size 0.45)
		(drill 0.1)
		(layers "F.Cu" "B.Cu")
		(free yes)
		(net 2)
	)
	(via
		(at 60.81 122.9)
		(size 0.45)
		(drill 0.1)
		(layers "F.Cu" "B.Cu")
		(free yes)
		(net 2)
	)
	(via
		(at 123.4 94)
		(size 0.45)
		(drill 0.1)
		(layers "F.Cu" "B.Cu")
		(free yes)
		(net 2)
	)
	(via
		(at 216.4 93)
		(size 0.45)
		(drill 0.1)
		(layers "F.Cu" "B.Cu")
		(net 2)
	)
	(via
		(at 124 92.8)
		(size 0.45)
		(drill 0.1)
		(layers "F.Cu" "B.Cu")
		(free yes)
		(net 2)
	)
	(via
		(at 188.426 149.7)
		(size 0.45)
		(drill 0.1)
		(layers "F.Cu" "B.Cu")
		(net 2)
	)
	(via
		(at 60.81 121.64)
		(size 0.45)
		(drill 0.1)
		(layers "F.Cu" "B.Cu")
		(free yes)
		(net 2)
	)
	(via
		(at 168.5 133.2)
		(size 0.45)
		(drill 0.1)
		(layers "F.Cu" "B.Cu")
		(remove_unused_layers yes)
		(keep_end_layers yes)
		(free yes)
		(zone_layer_connections "In2.Cu")
		(net 2)
	)
	(via
		(at 150.3 121.5)
		(size 0.45)
		(drill 0.1)
		(layers "F.Cu" "B.Cu")
		(net 2)
	)
	(via
		(at 210 133.7)
		(size 0.45)
		(drill 0.1)
		(layers "F.Cu" "B.Cu")
		(net 2)
	)
	(via
		(at 64.5 79.3)
		(size 0.45)
		(drill 0.1)
		(layers "F.Cu" "B.Cu")
		(net 2)
	)
	(via
		(at 167.35 130.2)
		(size 0.45)
		(drill 0.1)
		(layers "F.Cu" "B.Cu")
		(remove_unused_layers yes)
		(keep_end_layers yes)
		(free yes)
		(zone_layer_connections "In2.Cu")
		(net 2)
	)
	(via
		(at 137.3 66.5)
		(size 0.45)
		(drill 0.1)
		(layers "F.Cu" "B.Cu")
		(net 2)
	)
	(via
		(at 141.2 65.4)
		(size 0.45)
		(drill 0.1)
		(layers "F.Cu" "B.Cu")
		(net 2)
	)
	(via
		(at 100.8 127.2)
		(size 0.45)
		(drill 0.1)
		(layers "F.Cu" "B.Cu")
		(free yes)
		(net 2)
	)
	(via
		(at 101.75 61.5)
		(size 0.45)
		(drill 0.1)
		(layers "F.Cu" "B.Cu")
		(net 2)
	)
	(via
		(at 123.8 119.8)
		(size 0.45)
		(drill 0.1)
		(layers "F.Cu" "B.Cu")
		(free yes)
		(net 2)
	)
	(via
		(at 166.75 132.6)
		(size 0.45)
		(drill 0.1)
		(layers "F.Cu" "B.Cu")
		(remove_unused_layers yes)
		(keep_end_layers yes)
		(free yes)
		(zone_layer_connections "In2.Cu")
		(net 2)
	)
	(via
		(at 102 127.8)
		(size 0.45)
		(drill 0.1)
		(layers "F.Cu" "B.Cu")
		(free yes)
		(net 2)
	)
	(via
		(at 122.8 94)
		(size 0.45)
		(drill 0.1)
		(layers "F.Cu" "B.Cu")
		(free yes)
		(net 2)
	)
	(via
		(at 190.1 83.2)
		(size 0.45)
		(drill 0.1)
		(layers "F.Cu" "B.Cu")
		(net 2)
	)
	(via
		(at 125.2 141.8)
		(size 0.45)
		(drill 0.1)
		(layers "F.Cu" "B.Cu")
		(net 2)
	)
	(via
		(at 108.2 132.3)
		(size 0.45)
		(drill 0.1)
		(layers "F.Cu" "B.Cu")
		(net 2)
	)
	(via
		(at 123.2 93.4)
		(size 0.45)
		(drill 0.1)
		(layers "F.Cu" "B.Cu")
		(free yes)
		(net 2)
	)
	(via
		(at 101.4 126.6)
		(size 0.45)
		(drill 0.1)
		(layers "F.Cu" "B.Cu")
		(free yes)
		(net 2)
	)
	(via
		(at 60.8 122.3)
		(size 0.45)
		(drill 0.1)
		(layers "F.Cu" "B.Cu")
		(free yes)
		(net 2)
	)
	(via
		(at 122.7 138.6)
		(size 0.45)
		(drill 0.1)
		(layers "F.Cu" "B.Cu")
		(free yes)
		(net 2)
	)
	(via
		(at 68.9 64.3)
		(size 0.45)
		(drill 0.1)
		(layers "F.Cu" "B.Cu")
		(net 2)
	)
	(via
		(at 167.35 131.4)
		(size 0.45)
		(drill 0.1)
		(layers "F.Cu" "B.Cu")
		(remove_unused_layers yes)
		(keep_end_layers yes)
		(free yes)
		(zone_layer_connections "In2.Cu")
		(net 2)
	)
	(via
		(at 144.6 66.4)
		(size 0.45)
		(drill 0.1)
		(layers "F.Cu" "B.Cu")
		(net 2)
	)
	(via
		(at 166.75 133.2)
		(size 0.45)
		(drill 0.1)
		(layers "F.Cu" "B.Cu")
		(remove_unused_layers yes)
		(keep_end_layers yes)
		(free yes)
		(zone_layer_connections "In2.Cu")
		(net 2)
	)
	(via
		(at 123.4 92.8)
		(size 0.45)
		(drill 0.1)
		(layers "F.Cu" "B.Cu")
		(free yes)
		(net 2)
	)
	(via
		(at 227.2 108.2)
		(size 0.45)
		(drill 0.1)
		(layers "F.Cu" "B.Cu")
		(net 2)
	)
	(via
		(at 209.976 143)
		(size 0.45)
		(drill 0.1)
		(layers "F.Cu" "B.Cu")
		(net 2)
	)
	(via
		(at 210.92 118.3)
		(size 0.45)
		(drill 0.1)
		(layers "F.Cu" "B.Cu")
		(net 2)
	)
	(via
		(at 210.2 61.4)
		(size 0.45)
		(drill 0.1)
		(layers "F.Cu" "B.Cu")
		(free yes)
		(net 2)
	)
	(via
		(at 210.8 61.3)
		(size 0.45)
		(drill 0.1)
		(layers "F.Cu" "B.Cu")
		(free yes)
		(net 2)
	)
	(via
		(at 123.2 138)
		(size 0.45)
		(drill 0.1)
		(layers "F.Cu" "B.Cu")
		(free yes)
		(net 2)
	)
	(via
		(at 101.4 128.4)
		(size 0.45)
		(drill 0.1)
		(layers "F.Cu" "B.Cu")
		(free yes)
		(net 2)
	)
	(via
		(at 198.5 127.3)
		(size 0.45)
		(drill 0.1)
		(layers "F.Cu" "B.Cu")
		(net 2)
	)
	(via
		(at 147 121.2)
		(size 0.45)
		(drill 0.1)
		(layers "F.Cu" "B.Cu")
		(net 2)
	)
	(via
		(at 166.75 130.2)
		(size 0.45)
		(drill 0.1)
		(layers "F.Cu" "B.Cu")
		(remove_unused_layers yes)
		(keep_end_layers yes)
		(free yes)
		(zone_layer_connections "In2.Cu")
		(net 2)
	)
	(via
		(at 166.75 129)
		(size 0.45)
		(drill 0.1)
		(layers "F.Cu" "B.Cu")
		(remove_unused_layers yes)
		(keep_end_layers yes)
		(free yes)
		(zone_layer_connections "In2.Cu")
		(net 2)
	)
	(via
		(at 210.8 60.7)
		(size 0.45)
		(drill 0.1)
		(layers "F.Cu" "B.Cu")
		(free yes)
		(net 2)
	)
	(via
		(at 167.35 132)
		(size 0.45)
		(drill 0.1)
		(layers "F.Cu" "B.Cu")
		(remove_unused_layers yes)
		(keep_end_layers yes)
		(free yes)
		(zone_layer_connections "In2.Cu")
		(net 2)
	)
	(via
		(at 168.5 132)
		(size 0.45)
		(drill 0.1)
		(layers "F.Cu" "B.Cu")
		(remove_unused_layers yes)
		(keep_end_layers yes)
		(free yes)
		(zone_layer_connections "In2.Cu")
		(net 2)
	)
	(via
		(at 168.5 130.8)
		(size 0.45)
		(drill 0.1)
		(layers "F.Cu" "B.Cu")
		(remove_unused_layers yes)
		(keep_end_layers yes)
		(free yes)
		(zone_layer_connections "In2.Cu")
		(net 2)
	)
	(via
		(at 122.6 93.4)
		(size 0.45)
		(drill 0.1)
		(layers "F.Cu" "B.Cu")
		(free yes)
		(net 2)
	)
	(via
		(at 167.35 129)
		(size 0.45)
		(drill 0.1)
		(layers "F.Cu" "B.Cu")
		(remove_unused_layers yes)
		(keep_end_layers yes)
		(free yes)
		(zone_layer_connections "In2.Cu")
		(net 2)
	)
	(via
		(at 238.7 106.1)
		(size 0.45)
		(drill 0.1)
		(layers "F.Cu" "B.Cu")
		(net 2)
	)
	(via
		(at 205.7 67)
		(size 0.45)
		(drill 0.1)
		(layers "F.Cu" "B.Cu")
		(net 2)
	)
	(via
		(at 90.24 146.9)
		(size 0.45)
		(drill 0.1)
		(layers "F.Cu" "B.Cu")
		(net 2)
	)
	(via
		(at 168.4 61.6)
		(size 0.45)
		(drill 0.1)
		(layers "F.Cu" "B.Cu")
		(net 2)
	)
	(via
		(at 205.3 132.25)
		(size 0.45)
		(drill 0.1)
		(layers "F.Cu" "B.Cu")
		(net 2)
	)
	(via
		(at 153.8 109.5)
		(size 0.45)
		(drill 0.1)
		(layers "F.Cu" "B.Cu")
		(net 2)
	)
	(via
		(at 60.824 123.474)
		(size 0.45)
		(drill 0.1)
		(layers "F.Cu" "B.Cu")
		(free yes)
		(net 2)
	)
	(via
		(at 123.2 138.6)
		(size 0.45)
		(drill 0.1)
		(layers "F.Cu" "B.Cu")
		(free yes)
		(net 2)
	)
	(via
		(at 210.2 60.8)
		(size 0.45)
		(drill 0.1)
		(layers "F.Cu" "B.Cu")
		(free yes)
		(net 2)
	)
	(via
		(at 167.9 129.6)
		(size 0.45)
		(drill 0.1)
		(layers "F.Cu" "B.Cu")
		(remove_unused_layers yes)
		(keep_end_layers yes)
		(free yes)
		(zone_layer_connections "In2.Cu")
		(net 2)
	)
	(via
		(at 166.75 129.6)
		(size 0.45)
		(drill 0.1)
		(layers "F.Cu" "B.Cu")
		(remove_unused_layers yes)
		(keep_end_layers yes)
		(free yes)
		(zone_layer_connections "In2.Cu")
		(net 2)
	)
	(via
		(at 157.8 115.4)
		(size 0.45)
		(drill 0.1)
		(layers "F.Cu" "B.Cu")
		(net 2)
	)
	(via
		(at 167.9 130.8)
		(size 0.45)
		(drill 0.1)
		(layers "F.Cu" "B.Cu")
		(remove_unused_layers yes)
		(keep_end_layers yes)
		(free yes)
		(zone_layer_connections "In2.Cu")
		(net 2)
	)
	(via
		(at 198.6 69.4)
		(size 0.45)
		(drill 0.1)
		(layers "F.Cu" "B.Cu")
		(net 2)
	)
	(via
		(at 102.6 127.8)
		(size 0.45)
		(drill 0.1)
		(layers "F.Cu" "B.Cu")
		(free yes)
		(net 2)
	)
	(via
		(at 101.4 127.2)
		(size 0.45)
		(drill 0.1)
		(layers "F.Cu" "B.Cu")
		(free yes)
		(net 2)
	)
	(via
		(at 201.7 132.6)
		(size 0.45)
		(drill 0.1)
		(layers "F.Cu" "B.Cu")
		(net 2)
	)
	(via
		(at 134 66.6)
		(size 0.45)
		(drill 0.1)
		(layers "F.Cu" "B.Cu")
		(net 2)
	)
	(via
		(at 218.4 84.8)
		(size 0.45)
		(drill 0.1)
		(layers "F.Cu" "B.Cu")
		(net 2)
	)
	(via
		(at 123.1 120.1)
		(size 0.45)
		(drill 0.1)
		(layers "F.Cu" "B.Cu")
		(free yes)
		(net 2)
	)
	(via
		(at 127.6 151.2)
		(size 0.45)
		(drill 0.1)
		(layers "F.Cu" "B.Cu")
		(net 2)
	)
	(via
		(at 167.9 132)
		(size 0.45)
		(drill 0.1)
		(layers "F.Cu" "B.Cu")
		(remove_unused_layers yes)
		(keep_end_layers yes)
		(free yes)
		(zone_layer_connections "In2.Cu")
		(net 2)
	)
	(via
		(at 167.9 129)
		(size 0.45)
		(drill 0.1)
		(layers "F.Cu" "B.Cu")
		(remove_unused_layers yes)
		(keep_end_layers yes)
		(free yes)
		(zone_layer_connections "In2.Cu")
		(net 2)
	)
	(via
		(at 168.5 132.6)
		(size 0.45)
		(drill 0.1)
		(layers "F.Cu" "B.Cu")
		(remove_unused_layers yes)
		(keep_end_layers yes)
		(free yes)
		(zone_layer_connections "In2.Cu")
		(net 2)
	)
	(via
		(at 194 127.3)
		(size 0.45)
		(drill 0.1)
		(layers "F.Cu" "B.Cu")
		(net 2)
	)
	(via
		(at 140.62 135.05)
		(size 0.45)
		(drill 0.1)
		(layers "F.Cu" "B.Cu")
		(net 2)
	)
	(via
		(at 209.976 148)
		(size 0.45)
		(drill 0.1)
		(layers "F.Cu" "B.Cu")
		(net 2)
	)
	(via
		(at 133 152.9)
		(size 0.45)
		(drill 0.1)
		(layers "F.Cu" "B.Cu")
		(net 2)
	)
	(via
		(at 213.9 85.6)
		(size 0.45)
		(drill 0.1)
		(layers "F.Cu" "B.Cu")
		(net 2)
	)
	(via
		(at 167.9 131.4)
		(size 0.45)
		(drill 0.1)
		(layers "F.Cu" "B.Cu")
		(remove_unused_layers yes)
		(keep_end_layers yes)
		(free yes)
		(zone_layer_connections "In2.Cu")
		(net 2)
	)
	(via
		(at 208.4 72.7)
		(size 0.45)
		(drill 0.1)
		(layers "F.Cu" "B.Cu")
		(net 2)
	)
	(via
		(at 167.9 130.2)
		(size 0.45)
		(drill 0.1)
		(layers "F.Cu" "B.Cu")
		(remove_unused_layers yes)
		(keep_end_layers yes)
		(free yes)
		(zone_layer_connections "In2.Cu")
		(net 2)
	)
	(via
		(at 122.8 92.8)
		(size 0.45)
		(drill 0.1)
		(layers "F.Cu" "B.Cu")
		(free yes)
		(net 2)
	)
	(via
		(at 103.2 128.4)
		(size 0.45)
		(drill 0.1)
		(layers "F.Cu" "B.Cu")
		(free yes)
		(net 2)
	)
	(via
		(at 167.35 133.2)
		(size 0.45)
		(drill 0.1)
		(layers "F.Cu" "B.Cu")
		(remove_unused_layers yes)
		(keep_end_layers yes)
		(free yes)
		(zone_layer_connections "In2.Cu")
		(net 2)
	)
	(via
		(at 210.8 61.9)
		(size 0.45)
		(drill 0.1)
		(layers "F.Cu" "B.Cu")
		(free yes)
		(net 2)
	)
	(via
		(at 123.2 120.7)
		(size 0.45)
		(drill 0.1)
		(layers "F.Cu" "B.Cu")
		(free yes)
		(net 2)
	)
	(via
		(at 204.8 79.2)
		(size 0.45)
		(drill 0.1)
		(layers "F.Cu" "B.Cu")
		(net 2)
	)
	(via
		(at 166.25 58)
		(size 0.45)
		(drill 0.1)
		(layers "F.Cu" "B.Cu")
		(net 2)
	)
	(via
		(at 189.976 138.15)
		(size 0.45)
		(drill 0.1)
		(layers "F.Cu" "B.Cu")
		(net 2)
	)
	(via
		(at 198.6 121.8)
		(size 0.45)
		(drill 0.1)
		(layers "F.Cu" "B.Cu")
		(remove_unused_layers yes)
		(keep_end_layers yes)
		(zone_layer_connections "In2.Cu")
		(net 2)
	)
	(via
		(at 198.5 125.3)
		(size 0.45)
		(drill 0.1)
		(layers "F.Cu" "B.Cu")
		(remove_unused_layers yes)
		(keep_end_layers yes)
		(zone_layer_connections "In2.Cu")
		(net 2)
	)
	(via
		(at 217.5 119.6)
		(size 0.45)
		(drill 0.1)
		(layers "F.Cu" "B.Cu")
		(net 2)
	)
	(via
		(at 214.4 96.4)
		(size 0.45)
		(drill 0.1)
		(layers "F.Cu" "B.Cu")
		(net 2)
	)
	(via
		(at 195.6 132.9)
		(size 0.45)
		(drill 0.1)
		(layers "F.Cu" "B.Cu")
		(net 2)
	)
	(via
		(at 101.4 127.8)
		(size 0.45)
		(drill 0.1)
		(layers "F.Cu" "B.Cu")
		(free yes)
		(net 2)
	)
	(via
		(at 124 94)
		(size 0.45)
		(drill 0.1)
		(layers "F.Cu" "B.Cu")
		(free yes)
		(net 2)
	)
	(via
		(at 129.8 143)
		(size 0.45)
		(drill 0.1)
		(layers "F.Cu" "B.Cu")
		(net 2)
	)
	(via
		(at 122.7 138)
		(size 0.45)
		(drill 0.1)
		(layers "F.Cu" "B.Cu")
		(free yes)
		(net 2)
	)
	(via
		(at 215.2 133.8)
		(size 0.45)
		(drill 0.1)
		(layers "F.Cu" "B.Cu")
		(net 2)
	)
	(via
		(at 213.8 108.2)
		(size 0.45)
		(drill 0.1)
		(layers "F.Cu" "B.Cu")
		(net 2)
	)
	(via
		(at 167.35 129.6)
		(size 0.45)
		(drill 0.1)
		(layers "F.Cu" "B.Cu")
		(remove_unused_layers yes)
		(keep_end_layers yes)
		(free yes)
		(zone_layer_connections "In2.Cu")
		(net 2)
	)
	(via
		(at 140.65 135.8)
		(size 0.45)
		(drill 0.1)
		(layers "F.Cu" "B.Cu")
		(net 2)
	)
	(via
		(at 199.226 145.5)
		(size 0.45)
		(drill 0.1)
		(layers "F.Cu" "B.Cu")
		(net 2)
	)
	(via
		(at 226.6 95.9)
		(size 0.45)
		(drill 0.1)
		(layers "F.Cu" "B.Cu")
		(net 2)
	)
	(via
		(at 167.9 132.6)
		(size 0.45)
		(drill 0.1)
		(layers "F.Cu" "B.Cu")
		(remove_unused_layers yes)
		(keep_end_layers yes)
		(free yes)
		(zone_layer_connections "In2.Cu")
		(net 2)
	)
	(via
		(at 131.4 147.2)
		(size 0.45)
		(drill 0.1)
		(layers "F.Cu" "B.Cu")
		(net 2)
	)
	(via
		(at 123.8 120.55)
		(size 0.45)
		(drill 0.1)
		(layers "F.Cu" "B.Cu")
		(free yes)
		(net 2)
	)
	(via
		(at 125.8 105.8)
		(size 0.45)
		(drill 0.1)
		(layers "F.Cu" "B.Cu")
		(net 2)
	)
	(via
		(at 168.5 130.2)
		(size 0.45)
		(drill 0.1)
		(layers "F.Cu" "B.Cu")
		(remove_unused_layers yes)
		(keep_end_layers yes)
		(free yes)
		(zone_layer_connections "In2.Cu")
		(net 2)
	)
	(via
		(at 133.4 66.6)
		(size 0.45)
		(drill 0.1)
		(layers "F.Cu" "B.Cu")
		(net 2)
	)
	(via
		(at 110 137.2)
		(size 0.45)
		(drill 0.1)
		(layers "F.Cu" "B.Cu")
		(net 2)
	)
	(via
		(at 166.75 131.4)
		(size 0.45)
		(drill 0.1)
		(layers "F.Cu" "B.Cu")
		(remove_unused_layers yes)
		(keep_end_layers yes)
		(free yes)
		(zone_layer_connections "In2.Cu")
		(net 2)
	)
	(via
		(at 122.6 120.6)
		(size 0.45)
		(drill 0.1)
		(layers "F.Cu" "B.Cu")
		(free yes)
		(net 2)
	)
	(via
		(at 62.9 64.8)
		(size 0.45)
		(drill 0.1)
		(layers "F.Cu" "B.Cu")
		(net 2)
	)
	(via
		(at 100.8 126.6)
		(size 0.45)
		(drill 0.1)
		(layers "F.Cu" "B.Cu")
		(free yes)
		(net 2)
	)
	(via
		(at 195.8 73)
		(size 0.45)
		(drill 0.1)
		(layers "F.Cu" "B.Cu")
		(net 2)
	)
	(via
		(at 205.9 106.6)
		(size 0.45)
		(drill 0.1)
		(layers "F.Cu" "B.Cu")
		(net 2)
	)
	(via
		(at 203.1 118.4)
		(size 0.45)
		(drill 0.1)
		(layers "F.Cu" "B.Cu")
		(net 2)
	)
	(via
		(at 125.8 108.8)
		(size 0.45)
		(drill 0.1)
		(layers "F.Cu" "B.Cu")
		(net 2)
	)
	(via
		(at 221.9 107.4)
		(size 0.45)
		(drill 0.1)
		(layers "F.Cu" "B.Cu")
		(net 2)
	)
	(via
		(at 212 92.6)
		(size 0.45)
		(drill 0.1)
		(layers "F.Cu" "B.Cu")
		(net 2)
	)
	(via
		(at 131.8 131.6)
		(size 0.45)
		(drill 0.1)
		(layers "F.Cu" "B.Cu")
		(net 2)
	)
	(via
		(at 108.6 137.1)
		(size 0.45)
		(drill 0.1)
		(layers "F.Cu" "B.Cu")
		(net 2)
	)
	(via
		(at 125.8 131.8)
		(size 0.45)
		(drill 0.1)
		(layers "F.Cu" "B.Cu")
		(net 2)
	)
	(via
		(at 167.35 132.6)
		(size 0.45)
		(drill 0.1)
		(layers "F.Cu" "B.Cu")
		(remove_unused_layers yes)
		(keep_end_layers yes)
		(free yes)
		(zone_layer_connections "In2.Cu")
		(net 2)
	)
	(via
		(at 168.5 129)
		(size 0.45)
		(drill 0.1)
		(layers "F.Cu" "B.Cu")
		(remove_unused_layers yes)
		(keep_end_layers yes)
		(free yes)
		(zone_layer_connections "In2.Cu")
		(net 2)
	)
	(via
		(at 102.6 128.4)
		(size 0.45)
		(drill 0.1)
		(layers "F.Cu" "B.Cu")
		(free yes)
		(net 2)
	)
	(via
		(at 134.7 106.9)
		(size 0.45)
		(drill 0.1)
		(layers "F.Cu" "B.Cu")
		(net 2)
	)
	(via
		(at 187.5 123.5)
		(size 0.45)
		(drill 0.1)
		(layers "F.Cu" "B.Cu")
		(net 2)
	)
	(via
		(at 210.2 62)
		(size 0.45)
		(drill 0.1)
		(layers "F.Cu" "B.Cu")
		(free yes)
		(net 2)
	)
	(via
		(at 153.1 95.4)
		(size 0.45)
		(drill 0.1)
		(layers "F.Cu" "B.Cu")
		(net 2)
	)
	(via
		(at 166.75 130.8)
		(size 0.45)
		(drill 0.1)
		(layers "F.Cu" "B.Cu")
		(remove_unused_layers yes)
		(keep_end_layers yes)
		(free yes)
		(zone_layer_connections "In2.Cu")
		(net 2)
	)
	(via
		(at 166.75 132)
		(size 0.45)
		(drill 0.1)
		(layers "F.Cu" "B.Cu")
		(remove_unused_layers yes)
		(keep_end_layers yes)
		(free yes)
		(zone_layer_connections "In2.Cu")
		(net 2)
	)
	(via
		(at 123.9 137.6)
		(size 0.45)
		(drill 0.1)
		(layers "F.Cu" "B.Cu")
		(free yes)
		(net 2)
	)
	(via
		(at 216.6 124.7)
		(size 0.45)
		(drill 0.1)
		(layers "F.Cu" "B.Cu")
		(net 2)
	)
	(via
		(at 167.9 133.2)
		(size 0.45)
		(drill 0.1)
		(layers "F.Cu" "B.Cu")
		(remove_unused_layers yes)
		(keep_end_layers yes)
		(free yes)
		(zone_layer_connections "In2.Cu")
		(net 2)
	)
	(via
		(at 168.5 129.6)
		(size 0.45)
		(drill 0.1)
		(layers "F.Cu" "B.Cu")
		(remove_unused_layers yes)
		(keep_end_layers yes)
		(free yes)
		(zone_layer_connections "In2.Cu")
		(net 2)
	)
	(via
		(at 117.4 116)
		(size 0.45)
		(drill 0.1)
		(layers "F.Cu" "B.Cu")
		(net 2)
	)
	(via
		(at 204.4 65.2)
		(size 0.45)
		(drill 0.1)
		(layers "F.Cu" "B.Cu")
		(net 2)
	)
	(segment
		(start 125.08 131.85)
		(end 125.75 131.85)
		(width 0.2)
		(layer "B.Cu")
		(net 2)
	)
	(segment
		(start 137.3 66.5)
		(end 137 66.5)
		(width 0.2)
		(layer "B.Cu")
		(net 2)
	)
	(segment
		(start 142.653 64.667)
		(end 142.6 64.72)
		(width 0.3)
		(layer "B.Cu")
		(net 2)
	)
	(segment
		(start 67.7 63.1)
		(end 67.16 63.1)
		(width 0.2)
		(layer "B.Cu")
		(net 2)
	)
	(segment
		(start 218.216999 86.7)
		(end 218.714999 87.198)
		(width 0.1)
		(layer "B.Cu")
		(net 2)
	)
	(segment
		(start 213.28 90.785001)
		(end 214.954999 90.785001)
		(width 0.1)
		(layer "B.Cu")
		(net 2)
	)
	(segment
		(start 125.08 105.8)
		(end 125.8 105.8)
		(width 0.1)
		(layer "B.Cu")
		(net 2)
	)
	(segment
		(start 127.553 150.344)
		(end 127.553 151.153)
		(width 0.2)
		(layer "B.Cu")
		(net 2)
	)
	(segment
		(start 102.48 61.52)
		(end 101.77 61.52)
		(width 0.2)
		(layer "B.Cu")
		(net 2)
	)
	(segment
		(start 209.206 148)
		(end 209.976 148)
		(width 0.1)
		(layer "B.Cu")
		(net 2)
	)
	(segment
		(start 199.226 144.75)
		(end 200.026 144.75)
		(width 0.2)
		(layer "B.Cu")
		(net 2)
	)
	(segment
		(start 134 66.6)
		(end 133.4 66.6)
		(width 0.3)
		(layer "B.Cu")
		(net 2)
	)
	(segment
		(start 215.52 88.2)
		(end 216 88.2)
		(width 0.1)
		(layer "B.Cu")
		(net 2)
	)
	(segment
		(start 209.206 143)
		(end 209.976 143)
		(width 0.1)
		(layer "B.Cu")
		(net 2)
	)
	(segment
		(start 126.3325 143.059)
		(end 126.0835 142.81)
		(width 0.2)
		(layer "B.Cu")
		(net 2)
	)
	(segment
		(start 204.8 79.2)
		(end 205.42 79.2)
		(width 0.2)
		(layer "B.Cu")
		(net 2)
	)
	(segment
		(start 197.6 70.12)
		(end 198.6 70.12)
		(width 0.2)
		(layer "B.Cu")
		(net 2)
	)
	(segment
		(start 134.8 63.526)
		(end 134.653 63.379)
		(width 0.3)
		(layer "B.Cu")
		(net 2)
	)
	(segment
		(start 199.65 65.95)
		(end 199.65 65.06)
		(width 0.2)
		(layer "B.Cu")
		(net 2)
	)
	(segment
		(start 128.3305 149.5665)
		(end 127.553 150.344)
		(width 0.1)
		(layer "B.Cu")
		(net 2)
	)
	(segment
		(start 209.1 72)
		(end 208.4 72.7)
		(width 0.1)
		(layer "B.Cu")
		(net 2)
	)
	(segment
		(start 130.2 151.7)
		(end 129.12 151.7)
		(width 0.1)
		(layer "B.Cu")
		(net 2)
	)
	(segment
		(start 213.28 90.78)
		(end 212.8 90.3)
		(width 0.1)
		(layer "B.Cu")
		(net 2)
	)
	(segment
		(start 238.68 106.8)
		(end 238.68 106.12)
		(width 0.1)
		(layer "B.Cu")
		(net 2)
	)
	(segment
		(start 206.52 66.95)
		(end 205.75 66.95)
		(width 0.1)
		(layer "B.Cu")
		(net 2)
	)
	(segment
		(start 134.8 64.72)
		(end 134.8 63.526)
		(width 0.3)
		(layer "B.Cu")
		(net 2)
	)
	(segment
		(start 167.39 58)
		(end 166.25 58)
		(width 0.1)
		(layer "B.Cu")
		(net 2)
	)
	(segment
		(start 213.9 85.6)
		(end 214.4 86.1)
		(width 0.2)
		(layer "B.Cu")
		(net 2)
	)
	(segment
		(start 205.88 106.58)
		(end 205.9 106.6)
		(width 0.3)
		(layer "B.Cu")
		(net 2)
	)
	(segment
		(start 213.6 85.3)
		(end 213.9 85.6)
		(width 0.1)
		(layer "B.Cu")
		(net 2)
	)
	(segment
		(start 201.98 64.82)
		(end 203 63.8)
		(width 0.2)
		(layer "B.Cu")
		(net 2)
	)
	(segment
		(start 134.8 64.72)
		(end 134.68 64.72)
		(width 0.3)
		(layer "B.Cu")
		(net 2)
	)
	(segment
		(start 204.78 130.98)
		(end 205.3 130.98)
		(width 0.2)
		(layer "B.Cu")
		(net 2)
	)
	(segment
		(start 129.727 131.277)
		(end 130.277 131.277)
		(width 0.2)
		(layer "B.Cu")
		(net 2)
	)
	(segment
		(start 216.58 125.5)
		(end 216.58 124.72)
		(width 0.1)
		(layer "B.Cu")
		(net 2)
	)
	(segment
		(start 215.52 90.22)
		(end 215.98 90.22)
		(width 0.1)
		(layer "B.Cu")
		(net 2)
	)
	(segment
		(start 144.6 65.68)
		(end 144.6 66.4)
		(width 0.2)
		(layer "B.Cu")
		(net 2)
	)
	(segment
		(start 213.78 83.82)
		(end 213.6 84)
		(width 0.1)
		(layer "B.Cu")
		(net 2)
	)
	(segment
		(start 168 63.88)
		(end 168 65.1)
		(width 0.2)
		(layer "B.Cu")
		(net 2)
	)
	(segment
		(start 62.9 64.8)
		(end 62.9 63.7)
		(width 0.2)
		(layer "B.Cu")
		(net 2)
	)
	(segment
		(start 109.995 137.205)
		(end 110 137.2)
		(width 0.2)
		(layer "B.Cu")
		(net 2)
	)
	(segment
		(start 127.3335 149.027)
		(end 127.3335 150.1245)
		(width 0.2)
		(layer "B.Cu")
		(net 2)
	)
	(segment
		(start 204 63.8)
		(end 204.4 64.2)
		(width 0.2)
		(layer "B.Cu")
		(net 2)
	)
	(segment
		(start 63.5 63.1)
		(end 63.97 63.1)
		(width 0.2)
		(layer "B.Cu")
		(net 2)
	)
	(segment
		(start 62.9 63.7)
		(end 63.5 63.1)
		(width 0.2)
		(layer "B.Cu")
		(net 2)
	)
	(segment
		(start 213.6 84)
		(end 213.6 85.3)
		(width 0.1)
		(layer "B.Cu")
		(net 2)
	)
	(segment
		(start 194 127.3)
		(end 194.7 127.3)
		(width 0.2)
		(layer "B.Cu")
		(net 2)
	)
	(segment
		(start 212.8 90.3)
		(end 212.8 88.8)
		(width 0.1)
		(layer "B.Cu")
		(net 2)
	)
	(segment
		(start 203.3 130.02)
		(end 203.82 130.02)
		(width 0.2)
		(layer "B.Cu")
		(net 2)
	)
	(segment
		(start 212.8 87.14)
		(end 213.28 86.66)
		(width 0.1)
		(layer "B.Cu")
		(net 2)
	)
	(segment
		(start 130.12 151.69)
		(end 130.89 151.69)
		(width 0.1)
		(layer "B.Cu")
		(net 2)
	)
	(segment
		(start 238.68 106.12)
		(end 238.7 106.1)
		(width 0.1)
		(layer "B.Cu")
		(net 2)
	)
	(segment
		(start 142.653 63.379)
		(end 142.653 64.667)
		(width 0.3)
		(layer "B.Cu")
		(net 2)
	)
	(segment
		(start 130.5575 147.299)
		(end 131.301 147.299)
		(width 0.2)
		(layer "B.Cu")
		(net 2)
	)
	(segment
		(start 199.65 65.06)
		(end 199.89 64.82)
		(width 0.2)
		(layer "B.Cu")
		(net 2)
	)
	(segment
		(start 108.555 137.95)
		(end 108.555 137.145)
		(width 0.2)
		(layer "B.Cu")
		(net 2)
	)
	(segment
		(start 127.553 151.153)
		(end 127.6 151.2)
		(width 0.2)
		(layer "B.Cu")
		(net 2)
	)
	(segment
		(start 222.52 107.4)
		(end 221.9 107.4)
		(width 0.2)
		(layer "B.Cu")
		(net 2)
	)
	(segment
		(start 200.026 144.75)
		(end 200.226 144.55)
		(width 0.2)
		(layer "B.Cu")
		(net 2)
	)
	(segment
		(start 141.2 65.4)
		(end 141.88 64.72)
		(width 0.3)
		(layer "B.Cu")
		(net 2)
	)
	(segment
		(start 204.4 64.2)
		(end 204.4 65.2)
		(width 0.2)
		(layer "B.Cu")
		(net 2)
	)
	(segment
		(start 209.196532 142.990532)
		(end 209.206 143)
		(width 0.1)
		(layer "B.Cu")
		(net 2)
	)
	(segment
		(start 129.727 132.725)
		(end 129.727 131.277)
		(width 0.1)
		(layer "B.Cu")
		(net 2)
	)
	(segment
		(start 209.196532 142)
		(end 209.196532 142.990532)
		(width 0.1)
		(layer "B.Cu")
		(net 2)
	)
	(segment
		(start 136.8 65.68)
		(end 136.8 66.3)
		(width 0.2)
		(layer "B.Cu")
		(net 2)
	)
	(segment
		(start 134 65.4)
		(end 134 66.6)
		(width 0.3)
		(layer "B.Cu")
		(net 2)
	)
	(segment
		(start 213.28 90.785001)
		(end 213.28 90.78)
		(width 0.1)
		(layer "B.Cu")
		(net 2)
	)
	(segment
		(start 209.48 72)
		(end 209.1 72)
		(width 0.1)
		(layer "B.Cu")
		(net 2)
	)
	(segment
		(start 214.4 86.1)
		(end 214.4 86.72)
		(width 0.2)
		(layer "B.Cu")
		(net 2)
	)
	(segment
		(start 116.82 116.58)
		(end 116.26 116.58)
		(width 0.1)
		(layer "B.Cu")
		(net 2)
	)
	(segment
		(start 198.746 145.5)
		(end 198.476 145.77)
		(width 0.2)
		(layer "B.Cu")
		(net 2)
	)
	(segment
		(start 227.2 108.92)
		(end 227.2 108.2)
		(width 0.1)
		(layer "B.Cu")
		(net 2)
	)
	(segment
		(start 130.277 131.277)
		(end 130.52 131.52)
		(width 0.2)
		(layer "B.Cu")
		(net 2)
	)
	(segment
		(start 214.5 83.82)
		(end 213.78 83.82)
		(width 0.1)
		(layer "B.Cu")
		(net 2)
	)
	(segment
		(start 198.6 70.12)
		(end 198.6 69.4)
		(width 0.2)
		(layer "B.Cu")
		(net 2)
	)
	(segment
		(start 205.875 104.79)
		(end 205.875 105.795001)
		(width 0.3)
		(layer "B.Cu")
		(net 2)
	)
	(segment
		(start 131.72 131.52)
		(end 131.8 131.6)
		(width 0.2)
		(layer "B.Cu")
		(net 2)
	)
	(segment
		(start 102.48 60.205)
		(end 102.51 60.175)
		(width 0.2)
		(layer "B.Cu")
		(net 2)
	)
	(segment
		(start 132.1 152.9)
		(end 133 152.9)
		(width 0.1)
		(layer "B.Cu")
		(net 2)
	)
	(segment
		(start 129.12 151.7)
		(end 129.1 151.68)
		(width 0.1)
		(layer "B.Cu")
		(net 2)
	)
	(segment
		(start 214.954999 90.785001)
		(end 215.52 90.22)
		(width 0.1)
		(layer "B.Cu")
		(net 2)
	)
	(segment
		(start 101.77 61.52)
		(end 101.75 61.5)
		(width 0.2)
		(layer "B.Cu")
		(net 2)
	)
	(segment
		(start 216 86.8)
		(end 216.1 86.7)
		(width 0.1)
		(layer "B.Cu")
		(net 2)
	)
	(segment
		(start 130.89 151.69)
		(end 132.1 152.9)
		(width 0.1)
		(layer "B.Cu")
		(net 2)
	)
	(segment
		(start 226.62 95.88)
		(end 226.6 95.9)
		(width 0.1)
		(layer "B.Cu")
		(net 2)
	)
	(segment
		(start 203 63.8)
		(end 204 63.8)
		(width 0.2)
		(layer "B.Cu")
		(net 2)
	)
	(segment
		(start 216.1 86.7)
		(end 218.216999 86.7)
		(width 0.1)
		(layer "B.Cu")
		(net 2)
	)
	(segment
		(start 216 90.2)
		(end 216 88.2)
		(width 0.1)
		(layer "B.Cu")
		(net 2)
	)
	(segment
		(start 131.4 147.2)
		(end 132 146.6)
		(width 0.2)
		(layer "B.Cu")
		(net 2)
	)
	(segment
		(start 216.58 125.5)
		(end 216.58 126.5)
		(width 0.1)
		(layer "B.Cu")
		(net 2)
	)
	(segment
		(start 142.6 64.72)
		(end 141.88 64.72)
		(width 0.3)
		(layer "B.Cu")
		(net 2)
	)
	(segment
		(start 109.34 132.3)
		(end 108.2 132.3)
		(width 0.1)
		(layer "B.Cu")
		(net 2)
	)
	(segment
		(start 126.0835 142.81)
		(end 126.0835 141.8)
		(width 0.2)
		(layer "B.Cu")
		(net 2)
	)
	(segment
		(start 199.226 144.75)
		(end 198.746 144.75)
		(width 0.2)
		(layer "B.Cu")
		(net 2)
	)
	(segment
		(start 205.3 130.98)
		(end 205.3 132.25)
		(width 0.2)
		(layer "B.Cu")
		(net 2)
	)
	(segment
		(start 212.8 88.8)
		(end 212.8 87.14)
		(width 0.1)
		(layer "B.Cu")
		(net 2)
	)
	(segment
		(start 68.9 64.3)
		(end 67.7 63.1)
		(width 0.2)
		(layer "B.Cu")
		(net 2)
	)
	(segment
		(start 199.226 145.5)
		(end 199.226 144.75)
		(width 0.2)
		(layer "B.Cu")
		(net 2)
	)
	(segment
		(start 203.82 130.02)
		(end 204.78 130.98)
		(width 0.2)
		(layer "B.Cu")
		(net 2)
	)
	(segment
		(start 127.3335 150.1245)
		(end 127.553 150.344)
		(width 0.2)
		(layer "B.Cu")
		(net 2)
	)
	(segment
		(start 102.205 60.48)
		(end 102.51 60.175)
		(width 0.1)
		(layer "B.Cu")
		(net 2)
	)
	(segment
		(start 134.68 64.72)
		(end 134 65.4)
		(width 0.3)
		(layer "B.Cu")
		(net 2)
	)
	(segment
		(start 209.5 71.98)
		(end 209.48 72)
		(width 0.1)
		(layer "B.Cu")
		(net 2)
	)
	(segment
		(start 108.555 137.145)
		(end 108.6 137.1)
		(width 0.2)
		(layer "B.Cu")
		(net 2)
	)
	(segment
		(start 126.0835 141.8)
		(end 125.2 141.8)
		(width 0.2)
		(layer "B.Cu")
		(net 2)
	)
	(segment
		(start 129.8345 143.0345)
		(end 129.8 143)
		(width 0.1)
		(layer "B.Cu")
		(net 2)
	)
	(segment
		(start 212.824999 88.775001)
		(end 212.8 88.8)
		(width 0.1)
		(layer "B.Cu")
		(net 2)
	)
	(segment
		(start 101.24 60.48)
		(end 102.205 60.48)
		(width 0.1)
		(layer "B.Cu")
		(net 2)
	)
	(segment
		(start 130.52 131.52)
		(end 131 131.52)
		(width 0.2)
		(layer "B.Cu")
		(net 2)
	)
	(segment
		(start 137 66.5)
		(end 136.8 66.3)
		(width 0.2)
		(layer "B.Cu")
		(net 2)
	)
	(segment
		(start 198.746 144.75)
		(end 198.476 144.48)
		(width 0.2)
		(layer "B.Cu")
		(net 2)
	)
	(segment
		(start 205.875 105.795001)
		(end 205.88 105.800001)
		(width 0.3)
		(layer "B.Cu")
		(net 2)
	)
	(segment
		(start 109.995 137.95)
		(end 109.995 137.205)
		(width 0.2)
		(layer "B.Cu")
		(net 2)
	)
	(segment
		(start 216 88.2)
		(end 216 86.8)
		(width 0.1)
		(layer "B.Cu")
		(net 2)
	)
	(segment
		(start 205.75 66.95)
		(end 205.7 67)
		(width 0.1)
		(layer "B.Cu")
		(net 2)
	)
	(segment
		(start 129.8345 144.076)
		(end 129.8345 143.0345)
		(width 0.1)
		(layer "B.Cu")
		(net 2)
	)
	(segment
		(start 102.48 61.52)
		(end 102.48 60.205)
		(width 0.2)
		(layer "B.Cu")
		(net 2)
	)
	(segment
		(start 125.08 108.8)
		(end 125.8 108.8)
		(width 0.1)
		(layer "B.Cu")
		(net 2)
	)
	(segment
		(start 128.3305 149.027)
		(end 128.3305 149.5665)
		(width 0.1)
		(layer "B.Cu")
		(net 2)
	)
	(segment
		(start 125.75 131.85)
		(end 125.8 131.8)
		(width 0.2)
		(layer "B.Cu")
		(net 2)
	)
	(segment
		(start 213.28 86.66)
		(end 214.34 86.66)
		(width 0.1)
		(layer "B.Cu")
		(net 2)
	)
	(segment
		(start 214.34 86.66)
		(end 214.4 86.72)
		(width 0.1)
		(layer "B.Cu")
		(net 2)
	)
	(segment
		(start 202.3 130.02)
		(end 203.3 130.02)
		(width 0.2)
		(layer "B.Cu")
		(net 2)
	)
	(segment
		(start 131.301 147.299)
		(end 131.4 147.2)
		(width 0.2)
		(layer "B.Cu")
		(net 2)
	)
	(segment
		(start 130.12 151.69)
		(end 130.19 151.69)
		(width 0.1)
		(layer "B.Cu")
		(net 2)
	)
	(segment
		(start 132 146.6)
		(end 132 146.48)
		(width 0.2)
		(layer "B.Cu")
		(net 2)
	)
	(segment
		(start 194.7 127.3)
		(end 195.4 126.6)
		(width 0.2)
		(layer "B.Cu")
		(net 2)
	)
	(segment
		(start 215.98 90.22)
		(end 216 90.2)
		(width 0.1)
		(layer "B.Cu")
		(net 2)
	)
	(segment
		(start 227.4 95.88)
		(end 226.62 95.88)
		(width 0.1)
		(layer "B.Cu")
		(net 2)
	)
	(segment
		(start 195.6 132.13)
		(end 195.6 132.9)
		(width 0.1)
		(layer "B.Cu")
		(net 2)
	)
	(segment
		(start 126.3325 144.076)
		(end 126.3325 143.059)
		(width 0.2)
		(layer "B.Cu")
		(net 2)
	)
	(segment
		(start 199.226 145.5)
		(end 198.746 145.5)
		(width 0.2)
		(layer "B.Cu")
		(net 2)
	)
	(segment
		(start 205.88 105.800001)
		(end 205.88 106.58)
		(width 0.3)
		(layer "B.Cu")
		(net 2)
	)
	(segment
		(start 130.11 151.68)
		(end 130.12 151.69)
		(width 0.1)
		(layer "B.Cu")
		(net 2)
	)
	(segment
		(start 131 131.52)
		(end 131.72 131.52)
		(width 0.2)
		(layer "B.Cu")
		(net 2)
	)
	(segment
		(start 117.4 116)
		(end 116.82 116.58)
		(width 0.1)
		(layer "B.Cu")
		(net 2)
	)
	(segment
		(start 216.58 124.72)
		(end 216.6 124.7)
		(width 0.1)
		(layer "B.Cu")
		(net 2)
	)
	(segment
		(start 130.19 151.69)
		(end 130.2 151.7)
		(width 0.1)
		(layer "B.Cu")
		(net 2)
	)
	(segment
		(start 199.89 64.82)
		(end 201.98 64.82)
		(width 0.2)
		(layer "B.Cu")
		(net 2)
	)
	(segment
		(start 213.28 88.775001)
		(end 212.824999 88.775001)
		(width 0.1)
		(layer "B.Cu")
		(net 2)
	)
	(segment
		(start 168.5 57.17)
		(end 168.5 58)
		(width 0.1)
		(layer "F.Cu")
		(net 4)
	)
	(segment
		(start 160.429468 100.105532)
		(end 160.429468 100.775)
		(width 0.2)
		(layer "F.Cu")
		(net 4)
	)
	(segment
		(start 161.729468 102.51)
		(end 161.729468 102.429468)
		(width 0.1)
		(layer "F.Cu")
		(net 4)
	)
	(segment
		(start 160.429468 101.679468)
		(end 160.429468 100.775)
		(width 0.1)
		(layer "F.Cu")
		(net 4)
	)
	(segment
		(start 160.347234 79.967766)
		(end 160.347234 80.652234)
		(width 0.15)
		(layer "F.Cu")
		(net 4)
	)
	(segment
		(start 158.85 79.48)
		(end 159.859468 79.48)
		(width 0.15)
		(layer "F.Cu")
		(net 4)
	)
	(segment
		(start 97.95 56.85)
		(end 96.95 56.85)
		(width 0.1)
		(layer "F.Cu")
		(net 4)
	)
	(segment
		(start 97.95 56.85)
		(end 97.95 57.15)
		(width 0.2)
		(layer "F.Cu")
		(net 4)
	)
	(segment
		(start 165 133.9)
		(end 167.784468 133.9)
		(width 0.3)
		(layer "F.Cu")
		(net 4)
	)
	(segment
		(start 167.784468 133.9)
		(end 168.444468 134.56)
		(width 0.3)
		(layer "F.Cu")
		(net 4)
	)
	(segment
		(start 159.889468 79.51)
		(end 160.347234 79.967766)
		(width 0.15)
		(layer "F.Cu")
		(net 4)
	)
	(segment
		(start 170.049468 119.216)
		(end 170.05 119.216532)
		(width 0.15)
		(layer "F.Cu")
		(net 4)
	)
	(segment
		(start 168.3 119.9)
		(end 168.984 119.216)
		(width 0.3)
		(layer "F.Cu")
		(net 4)
	)
	(segment
		(start 135.930532 68.969468)
		(end 135.930532 70.65)
		(width 0.5)
		(layer "F.Cu")
		(net 4)
	)
	(segment
		(start 168.3 124.4)
		(end 168.3 119.9)
		(width 0.3)
		(layer "F.Cu")
		(net 4)
	)
	(segment
		(start 168.929468 135.045)
		(end 168.444468 134.56)
		(width 0.15)
		(layer "F.Cu")
		(net 4)
	)
	(segment
		(start 147.2 138.1)
		(end 151.4 133.9)
		(width 0.3)
		(layer "F.Cu")
		(net 4)
	)
	(segment
		(start 88.5 58.5)
		(end 89 58)
		(width 0.2)
		(layer "F.Cu")
		(net 4)
	)
	(segment
		(start 95.3 62.5)
		(end 96 61.8)
		(width 0.3)
		(layer "F.Cu")
		(net 4)
	)
	(segment
		(start 142.59 130.84)
		(end 143.36 130.84)
		(width 0.3)
		(layer "F.Cu")
		(net 4)
	)
	(segment
		(start 94.48 62.5)
		(end 95.3 62.5)
		(width 0.3)
		(layer "F.Cu")
		(net 4)
	)
	(segment
		(start 165 127.7)
		(end 168.3 124.4)
		(width 0.3)
		(layer "F.Cu")
		(net 4)
	)
	(segment
		(start 136.4 68.5)
		(end 135.930532 68.969468)
		(width 0.5)
		(layer "F.Cu")
		(net 4)
	)
	(segment
		(start 161.81 102.429468)
		(end 161.729468 102.51)
		(width 0.1)
		(layer "F.Cu")
		(net 4)
	)
	(segment
		(start 171.815 122.315)
		(end 170.515 121.015)
		(width 0.15)
		(layer "F.Cu")
		(net 4)
	)
	(segment
		(start 93.52 64.5)
		(end 93.52 63.5)
		(width 0.1)
		(layer "F.Cu")
		(net 4)
	)
	(segment
		(start 156.13 79.47)
		(end 154.3 81.3)
		(width 0.3)
		(layer "F.Cu")
		(net 4)
	)
	(segment
		(start 161.82 102.429468)
		(end 161.81 102.429468)
		(width 0.1)
		(layer "F.Cu")
		(net 4)
	)
	(segment
		(start 168.984 119.216)
		(end 170.049468 119.216)
		(width 0.3)
		(layer "F.Cu")
		(net 4)
	)
	(segment
		(start 170.515 119.681532)
		(end 170.515 120.401)
		(width 0.15)
		(layer "F.Cu")
		(net 4)
	)
	(segment
		(start 161.729468 103.375)
		(end 161.729468 102.51)
		(width 0.1)
		(layer "F.Cu")
		(net 4)
	)
	(segment
		(start 151.4 133.9)
		(end 165 133.9)
		(width 0.3)
		(layer "F.Cu")
		(net 4)
	)
	(segment
		(start 171.815 123.001)
		(end 171.815 122.315)
		(width 0.15)
		(layer "F.Cu")
		(net 4)
	)
	(segment
		(start 158.84 79.47)
		(end 156.13 79.47)
		(width 0.3)
		(layer "F.Cu")
		(net 4)
	)
	(segment
		(start 161.41 102.11)
		(end 160.86 102.11)
		(width 0.1)
		(layer "F.Cu")
		(net 4)
	)
	(segment
		(start 162.379468 102.589468)
		(end 162.379468 103.375)
		(width 0.1)
		(layer "F.Cu")
		(net 4)
	)
	(segment
		(start 168.929468 135.92)
		(end 168.929468 135.045)
		(width 0.15)
		(layer "F.Cu")
		(net 4)
	)
	(segment
		(start 161.729468 102.429468)
		(end 161.82 102.429468)
		(width 0.1)
		(layer "F.Cu")
		(net 4)
	)
	(segment
		(start 135.95 71.2)
		(end 135.930532 71.180532)
		(width 0.3)
		(layer "F.Cu")
		(net 4)
	)
	(segment
		(start 93.52 63.5)
		(end 93 63.5)
		(width 0.2)
		(layer "F.Cu")
		(net 4)
	)
	(segment
		(start 145.9 138.1)
		(end 147.2 138.1)
		(width 0.3)
		(layer "F.Cu")
		(net 4)
	)
	(segment
		(start 136.4 61.1)
		(end 136.4 68.5)
		(width 0.5)
		(layer "F.Cu")
		(net 4)
	)
	(segment
		(start 159.7 99.565)
		(end 159.888936 99.565)
		(width 0.2)
		(layer "F.Cu")
		(net 4)
	)
	(segment
		(start 98.9 56.55)
		(end 99.9 56.55)
		(width 0.2)
		(layer "F.Cu")
		(net 4)
	)
	(segment
		(start 162.219468 102.429468)
		(end 162.379468 102.589468)
		(width 0.1)
		(layer "F.Cu")
		(net 4)
	)
	(segment
		(start 158.85 79.48)
		(end 158.84 79.47)
		(width 0.3)
		(layer "F.Cu")
		(net 4)
	)
	(segment
		(start 159.888936 99.565)
		(end 160.429468 100.105532)
		(width 0.2)
		(layer "F.Cu")
		(net 4)
	)
	(segment
		(start 97.95 56.85)
		(end 98.6 56.85)
		(width 0.2)
		(layer "F.Cu")
		(net 4)
	)
	(segment
		(start 98.2 57.4)
		(end 98.2 57.925)
		(width 0.2)
		(layer "F.Cu")
		(net 4)
	)
	(segment
		(start 135.930532 71.180532)
		(end 135.930532 70.65)
		(width 0.3)
		(layer "F.Cu")
		(net 4)
	)
	(segment
		(start 143.36 130.84)
		(end 143.4 130.8)
		(width 0.3)
		(layer "F.Cu")
		(net 4)
	)
	(segment
		(start 165 133.9)
		(end 165 127.7)
		(width 0.3)
		(layer "F.Cu")
		(net 4)
	)
	(segment
		(start 161.82 102.429468)
		(end 162.219468 102.429468)
		(width 0.1)
		(layer "F.Cu")
		(net 4)
	)
	(segment
		(start 98.6 56.85)
		(end 98.9 56.55)
		(width 0.2)
		(layer "F.Cu")
		(net 4)
	)
	(segment
		(start 97.95 57.15)
		(end 98.2 57.4)
		(width 0.2)
		(layer "F.Cu")
		(net 4)
	)
	(segment
		(start 88.48 58.5)
		(end 88.5 58.5)
		(width 0.2)
		(layer "F.Cu")
		(net 4)
	)
	(segment
		(start 170.515 121.015)
		(end 170.515 120.401)
		(width 0.15)
		(layer "F.Cu")
		(net 4)
	)
	(segment
		(start 159.859468 79.48)
		(end 159.889468 79.51)
		(width 0.15)
		(layer "F.Cu")
		(net 4)
	)
	(segment
		(start 154.3 81.3)
		(end 154.3 82.7)
		(width 0.3)
		(layer "F.Cu")
		(net 4)
	)
	(segment
		(start 170.05 119.216532)
		(end 170.515 119.681532)
		(width 0.15)
		(layer "F.Cu")
		(net 4)
	)
	(segment
		(start 160.86 102.11)
		(end 160.429468 101.679468)
		(width 0.1)
		(layer "F.Cu")
		(net 4)
	)
	(segment
		(start 105.084999 55.555)
		(end 105.389999 55.25)
		(width 0.2)
		(layer "F.Cu")
		(net 4)
	)
	(segment
		(start 104.04 55.555)
		(end 105.084999 55.555)
		(width 0.2)
		(layer "F.Cu")
		(net 4)
	)
	(segment
		(start 92.1 63.5)
		(end 93 63.5)
		(width 0.2)
		(layer "F.Cu")
		(net 4)
	)
	(segment
		(start 96.95 56.85)
		(end 96.93 56.87)
		(width 0.1)
		(layer "F.Cu")
		(net 4)
	)
	(segment
		(start 161.729468 102.429468)
		(end 161.41 102.11)
		(width 0.1)
		(layer "F.Cu")
		(net 4)
	)
	(via
		(at 143.4 130.8)
		(size 0.45)
		(drill 0.1)
		(layers "F.Cu" "B.Cu")
		(net 4)
	)
	(via
		(at 96 61.8)
		(size 0.45)
		(drill 0.1)
		(layers "F.Cu" "B.Cu")
		(net 4)
	)
	(via
		(at 158.85 79.48)
		(size 0.45)
		(drill 0.1)
		(layers "F.Cu" "B.Cu")
		(remove_unused_layers yes)
		(keep_end_layers yes)
		(zone_layer_connections)
		(net 4)
	)
	(via
		(at 99.9 56.55)
		(size 0.45)
		(drill 0.1)
		(layers "F.Cu" "B.Cu")
		(net 4)
	)
	(via
		(at 93 63.5)
		(size 0.45)
		(drill 0.1)
		(layers "F.Cu" "B.Cu")
		(net 4)
	)
	(via
		(at 101.44 57.73)
		(size 0.45)
		(drill 0.1)
		(layers "F.Cu" "B.Cu")
		(net 4)
	)
	(via
		(at 168.5 58)
		(size 0.45)
		(drill 0.1)
		(layers "F.Cu" "B.Cu")
		(net 4)
	)
	(via
		(at 159.7 99.565)
		(size 0.45)
		(drill 0.1)
		(layers "F.Cu" "B.Cu")
		(net 4)
	)
	(via
		(at 145.9 138.1)
		(size 0.45)
		(drill 0.1)
		(layers "F.Cu" "B.Cu")
		(net 4)
	)
	(via
		(at 89 58)
		(size 0.45)
		(drill 0.1)
		(layers "F.Cu" "B.Cu")
		(net 4)
	)
	(via
		(at 154.3 82.7)
		(size 0.45)
		(drill 0.1)
		(layers "F.Cu" "B.Cu")
		(net 4)
	)
	(via
		(at 170.05 119.216532)
		(size 0.45)
		(drill 0.1)
		(layers "F.Cu" "B.Cu")
		(remove_unused_layers yes)
		(keep_end_layers yes)
		(zone_layer_connections)
		(net 4)
	)
	(via
		(at 135.95 71.2)
		(size 0.45)
		(drill 0.1)
		(layers "F.Cu" "B.Cu")
		(net 4)
	)
	(via
		(at 105.389999 55.25)
		(size 0.45)
		(drill 0.1)
		(layers "F.Cu" "B.Cu")
		(net 4)
	)
	(segment
		(start 153.9 99.965)
		(end 152.065 101.8)
		(width 0.3)
		(layer "B.Cu")
		(net 4)
	)
	(segment
		(start 99.8 59.7)
		(end 99.8 61.2)
		(width 0.3)
		(layer "B.Cu")
		(net 4)
	)
	(segment
		(start 160.8 101.9)
		(end 162.4 101.9)
		(width 0.3)
		(layer "B.Cu")
		(net 4)
	)
	(segment
		(start 99.9 57)
		(end 100.48 57)
		(width 0.2)
		(layer "B.Cu")
		(net 4)
	)
	(segment
		(start 98.4 58.9)
		(end 99 58.9)
		(width 0.3)
		(layer "B.Cu")
		(net 4)
	)
	(segment
		(start 90.66 63.5)
		(end 90.04 62.88)
		(width 0.3)
		(layer "B.Cu")
		(net 4)
	)
	(segment
		(start 153.9 95.6)
		(end 153.9 95.35)
		(width 0.3)
		(layer "B.Cu")
		(net 4)
	)
	(segment
		(start 144.2 138.3)
		(end 144.2 138.4)
		(width 0.3)
		(layer "B.Cu")
		(net 4)
	)
	(segment
		(start 150.7 101.8)
		(end 147.8 98.9)
		(width 0.3)
		(layer "B.Cu")
		(net 4)
	)
	(segment
		(start 154.15 95.6)
		(end 153.9 95.35)
		(width 0.3)
		(layer "B.Cu")
		(net 4)
	)
	(segment
		(start 143.9 138.1)
		(end 144.2 138.4)
		(width 0.3)
		(layer "B.Cu")
		(net 4)
	)
	(segment
		(start 96.3 61.5)
		(end 98.25 61.5)
		(width 0.3)
		(layer "B.Cu")
		(net 4)
	)
	(segment
		(start 136.9 82.7)
		(end 136.9 80.9)
		(width 0.3)
		(layer "B.Cu")
		(net 4)
	)
	(segment
		(start 164.6 116.2)
		(end 167.616532 119.216532)
		(width 0.3)
		(layer "B.Cu")
		(net 4)
	)
	(segment
		(start 105.389999 55.25)
		(end 105.39 55.74)
		(width 0.2)
		(layer "B.Cu")
		(net 4)
	)
	(segment
		(start 131.8 84.9)
		(end 133.4 83.3)
		(width 0.3)
		(layer "B.Cu")
		(net 4)
	)
	(segment
		(start 116.4 150.4)
		(end 116.4 144.4)
		(width 0.3)
		(layer "B.Cu")
		(net 4)
	)
	(segment
		(start 117.2 151.2)
		(end 116.4 150.4)
		(width 0.3)
		(layer "B.Cu")
		(net 4)
	)
	(segment
		(start 99.8 61.2)
		(end 99.5 61.5)
		(width 0.3)
		(layer "B.Cu")
		(net 4)
	)
	(segment
		(start 159.888936 99.753936)
		(end 159.888936 100.988936)
		(width 0.3)
		(layer "B.Cu")
		(net 4)
	)
	(segment
		(start 135.95 71.2)
		(end 136.72 71.2)
		(width 0.3)
		(layer "B.Cu")
		(net 4)
	)
	(segment
		(start 167.5 70.1)
		(end 167.5 70.8)
		(width 0.1)
		(layer "B.Cu")
		(net 4)
	)
	(segment
		(start 135.9 79.2)
		(end 137.9 77.2)
		(width 0.3)
		(layer "B.Cu")
		(net 4)
	)
	(segment
		(start 93 63.5)
		(end 93.4 63.5)
		(width 0.3)
		(layer "B.Cu")
		(net 4)
	)
	(segment
		(start 119.22 151.2)
		(end 119.22 149.835)
		(width 0.3)
		(layer "B.Cu")
		(net 4)
	)
	(segment
		(start 144.5 138.1)
		(end 145.9 138.1)
		(width 0.3)
		(layer "B.Cu")
		(net 4)
	)
	(segment
		(start 144.2 138.3)
		(end 144.3 138.3)
		(width 0.3)
		(layer "B.Cu")
		(net 4)
	)
	(segment
		(start 89 60.4)
		(end 89 58)
		(width 0.3)
		(layer "B.Cu")
		(net 4)
	)
	(segment
		(start 132.6 70.4)
		(end 129.3 67.1)
		(width 0.3)
		(layer "B.Cu")
		(net 4)
	)
	(segment
		(start 164.6 104.1)
		(end 164.6 116.2)
		(width 0.3)
		(layer "B.Cu")
		(net 4)
	)
	(segment
		(start 153.9 95.6)
		(end 153.9 95.8)
		(width 0.3)
		(layer "B.Cu")
		(net 4)
	)
	(segment
		(start 154.15 95.6)
		(end 154.1 95.6)
		(width 0.3)
		(layer "B.Cu")
		(net 4)
	)
	(segment
		(start 93.4 63.5)
		(end 94.39 62.51)
		(width 0.3)
		(layer "B.Cu")
		(net 4)
	)
	(segment
		(start 153.9 95.35)
		(end 153.9 83.1)
		(width 0.3)
		(layer "B.Cu")
		(net 4)
	)
	(segment
		(start 143.4 132.1)
		(end 143.4 130.8)
		(width 0.3)
		(layer "B.Cu")
		(net 4)
	)
	(segment
		(start 177.12 68.1)
		(end 169.5 68.1)
		(width 0.1)
		(layer "B.Cu")
		(net 4)
	)
	(segment
		(start 144.2 138.4)
		(end 144.5 138.1)
		(width 0.3)
		(layer "B.Cu")
		(net 4)
	)
	(segment
		(start 119.22 151.2)
		(end 117.2 151.2)
		(width 0.3)
		(layer "B.Cu")
		(net 4)
	)
	(segment
		(start 141 138.1)
		(end 143.9 138.1)
		(width 0.3)
		(layer "B.Cu")
		(net 4)
	)
	(segment
		(start 152.065 101.8)
		(end 150.7 101.8)
		(width 0.3)
		(layer "B.Cu")
		(net 4)
	)
	(segment
		(start 144.2 138.4)
		(end 144.2 139.9)
		(width 0.3)
		(layer "B.Cu")
		(net 4)
	)
	(segment
		(start 144 98.9)
		(end 131.8 86.7)
		(width 0.3)
		(layer "B.Cu")
		(net 4)
	)
	(segment
		(start 94.39 62.51)
		(end 96 62.51)
		(width 0.3)
		(layer "B.Cu")
		(net 4)
	)
	(segment
		(start 167.5 70.8)
		(end 166.9 71.4)
		(width 0.1)
		(layer "B.Cu")
		(net 4)
	)
	(segment
		(start 144.3 138.3)
		(end 144.5 138.1)
		(width 0.3)
		(layer "B.Cu")
		(net 4)
	)
	(segment
		(start 152.8 74.8)
		(end 157.55 79.55)
		(width 0.1)
		(layer "B.Cu")
		(net 4)
	)
	(segment
		(start 168.5 59)
		(end 169.2 59.7)
		(width 0.1)
		(layer "B.Cu")
		(net 4)
	)
	(segment
		(start 108.76 56.3)
		(end 108.2 55.74)
		(width 0.3)
		(layer "B.Cu")
		(net 4)
	)
	(segment
		(start 98 58.5)
		(end 98.4 58.9)
		(width 0.3)
		(layer "B.Cu")
		(net 4)
	)
	(segment
		(start 137.9 77.2)
		(end 137.9 73.5)
		(width 0.3)
		(layer "B.Cu")
		(net 4)
	)
	(segment
		(start 108.2 55.74)
		(end 105.39 55.74)
		(width 0.3)
		(layer "B.Cu")
		(net 4)
	)
	(segment
		(start 105.39 55.74)
		(end 103.46 55.74)
		(width 0.3)
		(layer "B.Cu")
		(net 4)
	)
	(segment
		(start 162.4 101.9)
		(end 164.6 104.1)
		(width 0.3)
		(layer "B.Cu")
		(net 4)
	)
	(segment
		(start 169.64 58)
		(end 168.5 58)
		(width 0.1)
		(layer "B.Cu")
		(net 4)
	)
	(segment
		(start 153.9 95.8)
		(end 153.9 99.965)
		(width 0.3)
		(layer "B.Cu")
		(net 4)
	)
	(segment
		(start 136.72 70.62)
		(end 136.5 70.4)
		(width 0.3)
		(layer "B.Cu")
		(net 4)
	)
	(segment
		(start 136.9 80.9)
		(end 135.9 79.9)
		(width 0.3)
		(layer "B.Cu")
		(net 4)
	)
	(segment
		(start 167.616532 119.216532)
		(end 170.05 119.216532)
		(width 0.3)
		(layer "B.Cu")
		(net 4)
	)
	(segment
		(start 144.2 138.1)
		(end 144.2 137.8)
		(width 0.3)
		(layer "B.Cu")
		(net 4)
	)
	(segment
		(start 135.9 79.9)
		(end 135.9 79.2)
		(width 0.3)
		(layer "B.Cu")
		(net 4)
	)
	(segment
		(start 144 138.1)
		(end 144.2 138.1)
		(width 0.3)
		(layer "B.Cu")
		(net 4)
	)
	(segment
		(start 144 138.1)
		(end 144.2 138.3)
		(width 0.3)
		(layer "B.Cu")
		(net 4)
	)
	(segment
		(start 144.2 137.8)
		(end 144.2 132.9)
		(width 0.3)
		(layer "B.Cu")
		(net 4)
	)
	(segment
		(start 143.9 138.1)
		(end 144 138.1)
		(width 0.3)
		(layer "B.Cu")
		(net 4)
	)
	(segment
		(start 147.8 98.9)
		(end 144 98.9)
		(width 0.3)
		(layer "B.Cu")
		(net 4)
	)
	(segment
		(start 100.48 57)
		(end 100.5 57.02)
		(width 0.2)
		(layer "B.Cu")
		(net 4)
	)
	(segment
		(start 98.2 57)
		(end 98 57.2)
		(width 0.3)
		(layer "B.Cu")
		(net 4)
	)
	(segment
		(start 169.2 59.7)
		(end 169.2 67.8)
		(width 0.1)
		(layer "B.Cu")
		(net 4)
	)
	(segment
		(start 111.91 56.3)
		(end 108.76 56.3)
		(width 0.3)
		(layer "B.Cu")
		(net 4)
	)
	(segment
		(start 116.4 144.4)
		(end 120 140.8)
		(width 0.3)
		(layer "B.Cu")
		(net 4)
	)
	(segment
		(start 159.7 99.565)
		(end 159.888936 99.753936)
		(width 0.3)
		(layer "B.Cu")
		(net 4)
	)
	(segment
		(start 154.1 95.6)
		(end 153.9 95.8)
		(width 0.3)
		(layer "B.Cu")
		(net 4)
	)
	(segment
		(start 102.18 57.02)
		(end 101.44 57.02)
		(width 0.3)
		(layer "B.Cu")
		(net 4)
	)
	(segment
		(start 90.04 61.44)
		(end 89 60.4)
		(width 0.3)
		(layer "B.Cu")
		(net 4)
	)
	(segment
		(start 93 63.5)
		(end 90.66 63.5)
		(width 0.3)
		(layer "B.Cu")
		(net 4)
	)
	(segment
		(start 98 57.2)
		(end 98 58.5)
		(width 0.3)
		(layer "B.Cu")
		(net 4)
	)
	(segment
		(start 144.2 132.9)
		(end 143.4 132.1)
		(width 0.3)
		(layer "B.Cu")
		(net 4)
	)
	(segment
		(start 96 61.8)
		(end 96.3 61.5)
		(width 0.3)
		(layer "B.Cu")
		(net 4)
	)
	(segment
		(start 99.9 57)
		(end 99.9 56.55)
		(width 0.2)
		(layer "B.Cu")
		(net 4)
	)
	(segment
		(start 159.7 99.565)
		(end 159.565 99.565)
		(width 0.3)
		(layer "B.Cu")
		(net 4)
	)
	(segment
		(start 136.72 71.2)
		(end 136.72 70.62)
		(width 0.3)
		(layer "B.Cu")
		(net 4)
	)
	(segment
		(start 155.6 95.6)
		(end 154.15 95.6)
		(width 0.3)
		(layer "B.Cu")
		(net 4)
	)
	(segment
		(start 169.5 68.1)
		(end 169.4 68)
		(width 0.1)
		(layer "B.Cu")
		(net 4)
	)
	(segment
		(start 137.9 73.5)
		(end 136.72 72.32)
		(width 0.3)
		(layer "B.Cu")
		(net 4)
	)
	(segment
		(start 131.8 86.7)
		(end 131.8 84.9)
		(width 0.3)
		(layer "B.Cu")
		(net 4)
	)
	(segment
		(start 144.2 137.8)
		(end 143.9 138.1)
		(width 0.3)
		(layer "B.Cu")
		(net 4)
	)
	(segment
		(start 148.7 144.4)
		(end 148.7 146.301)
		(width 0.3)
		(layer "B.Cu")
		(net 4)
	)
	(segment
		(start 90.04 62.88)
		(end 90.04 61.44)
		(width 0.3)
		(layer "B.Cu")
		(net 4)
	)
	(segment
		(start 152.8 73.4)
		(end 152.8 74.8)
		(width 0.1)
		(layer "B.Cu")
		(net 4)
	)
	(segment
		(start 138.3 140.8)
		(end 141 138.1)
		(width 0.3)
		(layer "B.Cu")
		(net 4)
	)
	(segment
		(start 96 62.51)
		(end 96 61.8)
		(width 0.3)
		(layer "B.Cu")
		(net 4)
	)
	(segment
		(start 169.5 68.1)
		(end 167.5 70.1)
		(width 0.1)
		(layer "B.Cu")
		(net 4)
	)
	(segment
		(start 120 140.8)
		(end 138.3 140.8)
		(width 0.3)
		(layer "B.Cu")
		(net 4)
	)
	(segment
		(start 99.5 61.5)
		(end 98.25 61.5)
		(width 0.3)
		(layer "B.Cu")
		(net 4)
	)
	(segment
		(start 144.2 138.1)
		(end 144.5 138.1)
		(width 0.3)
		(layer "B.Cu")
		(net 4)
	)
	(segment
		(start 118.71 63.1)
		(end 111.91 56.3)
		(width 0.3)
		(layer "B.Cu")
		(net 4)
	)
	(segment
		(start 103.46 55.74)
		(end 102.18 57.02)
		(width 0.3)
		(layer "B.Cu")
		(net 4)
	)
	(segment
		(start 168.5 57.98)
		(end 168.5 59)
		(width 0.1)
		(layer "B.Cu")
		(net 4)
	)
	(segment
		(start 129.3 64.6)
		(end 127.8 63.1)
		(width 0.3)
		(layer "B.Cu")
		(net 4)
	)
	(segment
		(start 154.15 95.6)
		(end 153.9 95.6)
		(width 0.3)
		(layer "B.Cu")
		(net 4)
	)
	(segment
		(start 136.5 70.4)
		(end 132.6 70.4)
		(width 0.3)
		(layer "B.Cu")
		(net 4)
	)
	(segment
		(start 129.3 67.1)
		(end 129.3 64.6)
		(width 0.3)
		(layer "B.Cu")
		(net 4)
	)
	(segment
		(start 99.101 57)
		(end 98.2 57)
		(width 0.3)
		(layer "B.Cu")
		(net 4)
	)
	(segment
		(start 127.8 63.1)
		(end 118.71 63.1)
		(width 0.3)
		(layer "B.Cu")
		(net 4)
	)
	(segment
		(start 136.3 83.3)
		(end 136.9 82.7)
		(width 0.3)
		(layer "B.Cu")
		(net 4)
	)
	(segment
		(start 159.888936 100.988936)
		(end 160.8 101.9)
		(width 0.3)
		(layer "B.Cu")
		(net 4)
	)
	(segment
		(start 101.44 57.73)
		(end 101.44 57.02)
		(width 0.1)
		(layer "B.Cu")
		(net 4)
	)
	(segment
		(start 99.101 57)
		(end 99.9 57)
		(width 0.2)
		(layer "B.Cu")
		(net 4)
	)
	(segment
		(start 144.2 138.1)
		(end 144.2 138.4)
		(width 0.3)
		(layer "B.Cu")
		(net 4)
	)
	(segment
		(start 136.72 72.32)
		(end 136.72 71.2)
		(width 0.3)
		(layer "B.Cu")
		(net 4)
	)
	(segment
		(start 177.82 67.4)
		(end 177.12 68.1)
		(width 0.1)
		(layer "B.Cu")
		(net 4)
	)
	(segment
		(start 119.22 149.835)
		(end 119.095 149.71)
		(width 0.3)
		(layer "B.Cu")
		(net 4)
	)
	(segment
		(start 166.9 71.4)
		(end 154.8 71.4)
		(width 0.1)
		(layer "B.Cu")
		(net 4)
	)
	(segment
		(start 157.55 79.55)
		(end 158.85 79.55)
		(width 0.1)
		(layer "B.Cu")
		(net 4)
	)
	(segment
		(start 101.44 57.02)
		(end 100.5 57.02)
		(width 0.3)
		(layer "B.Cu")
		(net 4)
	)
	(segment
		(start 159.565 99.565)
		(end 155.6 95.6)
		(width 0.3)
		(layer "B.Cu")
		(net 4)
	)
	(segment
		(start 153.9 83.1)
		(end 154.3 82.7)
		(width 0.3)
		(layer "B.Cu")
		(net 4)
	)
	(segment
		(start 99 58.9)
		(end 99.8 59.7)
		(width 0.3)
		(layer "B.Cu")
		(net 4)
	)
	(segment
		(start 169.2 67.8)
		(end 169.4 68)
		(width 0.1)
		(layer "B.Cu")
		(net 4)
	)
	(segment
		(start 154.8 71.4)
		(end 152.8 73.4)
		(width 0.1)
		(layer "B.Cu")
		(net 4)
	)
	(segment
		(start 144.2 139.9)
		(end 148.7 144.4)
		(width 0.3)
		(layer "B.Cu")
		(net 4)
	)
	(segment
		(start 144.5 138.1)
		(end 144.2 137.8)
		(width 0.3)
		(layer "B.Cu")
		(net 4)
	)
	(segment
		(start 133.4 83.3)
		(end 136.3 83.3)
		(width 0.3)
		(layer "B.Cu")
		(net 4)
	)
	(segment
		(start 65 82.2)
		(end 63.2 80.4)
		(width 0.75)
		(layer "F.Cu")
		(net 5)
	)
	(segment
		(start 170.75 57.14)
		(end 170.75 58)
		(width 0.1)
		(layer "F.Cu")
		(net 5)
	)
	(segment
		(start 157.06 142.09)
		(end 156.85 141.88)
		(width 0.15)
		(layer "F.Cu")
		(net 5)
	)
	(segment
		(start 65.68 86.35)
		(end 65.61234 86.35)
		(width 0.5)
		(layer "F.Cu")
		(net 5)
	)
	(segment
		(start 63.3 80.9)
		(end 63.7 80.9)
		(width 0.5)
		(layer "F.Cu")
		(net 5)
	)
	(segment
		(start 167 150.2)
		(end 167 146.825)
		(width 0.2)
		(layer "F.Cu")
		(net 5)
	)
	(segment
		(start 213.912407 98.692991)
		(end 212.912407 98.692991)
		(width 0.3)
		(layer "F.Cu")
		(net 5)
	)
	(segment
		(start 214.445 100.125)
		(end 214.445 99.745)
		(width 0.3)
		(layer "F.Cu")
		(net 5)
	)
	(segment
		(start 199.23 73.5)
		(end 199.23 72.77)
		(width 0.2)
		(layer "F.Cu")
		(net 5)
	)
	(segment
		(start 212.912407 98.692991)
		(end 212.912407 99.287593)
		(width 0.3)
		(layer "F.Cu")
		(net 5)
	)
	(segment
		(start 167 146.825)
		(end 167 146.075)
		(width 0.3)
		(layer "F.Cu")
		(net 5)
	)
	(segment
		(start 63.9 80.4)
		(end 63.9 81)
		(width 0.75)
		(layer "F.Cu")
		(net 5)
	)
	(segment
		(start 65.68 87.578)
		(end 65.803 87.701)
		(width 0.5)
		(layer "F.Cu")
		(net 5)
	)
	(segment
		(start 199.201 73.529)
		(end 199.23 73.5)
		(width 0.2)
		(layer "F.Cu")
		(net 5)
	)
	(segment
		(start 63.9 81)
		(end 63.2 81)
		(width 0.75)
		(layer "F.Cu")
		(net 5)
	)
	(segment
		(start 65 85.73766)
		(end 65.61234 86.35)
		(width 0.5)
		(layer "F.Cu")
		(net 5)
	)
	(segment
		(start 199.201 75.13)
		(end 199.201 73.529)
		(width 0.2)
		(layer "F.Cu")
		(net 5)
	)
	(segment
		(start 144.541 128.85)
		(end 144.65 128.959)
		(width 0.3)
		(layer "F.Cu")
		(net 5)
	)
	(segment
		(start 143.774391 128.85)
		(end 144.541 128.85)
		(width 0.3)
		(layer "F.Cu")
		(net 5)
	)
	(segment
		(start 65 85.73766)
		(end 65 84.6)
		(width 0.5)
		(layer "F.Cu")
		(net 5)
	)
	(segment
		(start 145.105391 128.959)
		(end 144.65 128.959)
		(width 0.3)
		(layer "F.Cu")
		(net 5)
	)
	(segment
		(start 143.774391 129.625609)
		(end 143.75 129.65)
		(width 0.5)
		(layer "F.Cu")
		(net 5)
	)
	(segment
		(start 213.912407 99.212407)
		(end 213.912407 98.692991)
		(width 0.3)
		(layer "F.Cu")
		(net 5)
	)
	(segment
		(start 138.25 135.8)
		(end 138.2 135.85)
		(width 0.3)
		(layer "F.Cu")
		(net 5)
	)
	(segment
		(start 199.201 82.201)
		(end 199.201 81.831)
		(width 0.2)
		(layer "F.Cu")
		(net 5)
	)
	(segment
		(start 172.3 116.945468)
		(end 171.919468 117.326)
		(width 0.1)
		(layer "F.Cu")
		(net 5)
	)
	(segment
		(start 63.9 80.4)
		(end 63.2 80.4)
		(width 0.75)
		(layer "F.Cu")
		(net 5)
	)
	(segment
		(start 199.4 82.8)
		(end 199.4 83.39)
		(width 0.2)
		(layer "F.Cu")
		(net 5)
	)
	(segment
		(start 199.23 72.77)
		(end 199.25 72.75)
		(width 0.2)
		(layer "F.Cu")
		(net 5)
	)
	(segment
		(start 65 84.6)
		(end 65 82.2)
		(width 0.75)
		(layer "F.Cu")
		(net 5)
	)
	(segment
		(start 138.25 135.05)
		(end 138.25 135.8)
		(width 0.3)
		(layer "F.Cu")
		(net 5)
	)
	(segment
		(start 171.3 115.966)
		(end 172.066 115.966)
		(width 0.1)
		(layer "F.Cu")
		(net 5)
	)
	(segment
		(start 65.68 86.35)
		(end 65.68 87.578)
		(width 0.5)
		(layer "F.Cu")
		(net 5)
	)
	(segment
		(start 172.066 115.966)
		(end 172.3 116.2)
		(width 0.1)
		(layer "F.Cu")
		(net 5)
	)
	(segment
		(start 167.499 150.4)
		(end 167.2 150.4)
		(width 0.2)
		(layer "F.Cu")
		(net 5)
	)
	(segment
		(start 142.4 128.85)
		(end 142.4 129.65)
		(width 0.5)
		(layer "F.Cu")
		(net 5)
	)
	(segment
		(start 143.774391 128.85)
		(end 143.774391 129.625609)
		(width 0.5)
		(layer "F.Cu")
		(net 5)
	)
	(segment
		(start 172.3 116.2)
		(end 172.3 116.945468)
		(width 0.1)
		(layer "F.Cu")
		(net 5)
	)
	(segment
		(start 199.4 83.39)
		(end 199.27 83.52)
		(width 0.2)
		(layer "F.Cu")
		(net 5)
	)
	(segment
		(start 212.912407 99.287593)
		(end 212.9 99.3)
		(width 0.3)
		(layer "F.Cu")
		(net 5)
	)
	(segment
		(start 199.4 82.8)
		(end 199.4 82.4)
		(width 0.2)
		(layer "F.Cu")
		(net 5)
	)
	(segment
		(start 63.2 81)
		(end 63.3 80.9)
		(width 0.5)
		(layer "F.Cu")
		(net 5)
	)
	(segment
		(start 214.445 99.745)
		(end 213.912407 99.212407)
		(width 0.3)
		(layer "F.Cu")
		(net 5)
	)
	(segment
		(start 199.4 82.4)
		(end 199.201 82.201)
		(width 0.2)
		(layer "F.Cu")
		(net 5)
	)
	(segment
		(start 63.2 81)
		(end 63.2 80.4)
		(width 0.75)
		(layer "F.Cu")
		(net 5)
	)
	(segment
		(start 63.7 80.9)
		(end 65 82.2)
		(width 0.5)
		(layer "F.Cu")
		(net 5)
	)
	(segment
		(start 143.774391 128.85)
		(end 142.4 128.85)
		(width 0.3)
		(layer "F.Cu")
		(net 5)
	)
	(segment
		(start 157.06 142.98)
		(end 157.06 142.09)
		(width 0.15)
		(layer "F.Cu")
		(net 5)
	)
	(segment
		(start 167.2 150.4)
		(end 167 150.2)
		(width 0.2)
		(layer "F.Cu")
		(net 5)
	)
	(via
		(at 63.2 80.4)
		(size 0.45)
		(drill 0.1)
		(layers "F.Cu" "B.Cu")
		(net 5)
	)
	(via
		(at 236.7 84.4)
		(size 0.45)
		(drill 0.1)
		(layers "F.Cu" "B.Cu")
		(free yes)
		(net 5)
	)
	(via
		(at 169.5 116.4)
		(size 0.45)
		(drill 0.1)
		(layers "F.Cu" "B.Cu")
		(remove_unused_layers yes)
		(keep_end_layers yes)
		(free yes)
		(zone_layer_connections "In4.Cu")
		(net 5)
	)
	(via
		(at 222.1 119.4)
		(size 0.45)
		(drill 0.1)
		(layers "F.Cu" "B.Cu")
		(net 5)
	)
	(via
		(at 235.2 135.8)
		(size 0.45)
		(drill 0.1)
		(layers "F.Cu" "B.Cu")
		(free yes)
		(net 5)
	)
	(via
		(at 234 135.8)
		(size 0.45)
		(drill 0.1)
		(layers "F.Cu" "B.Cu")
		(free yes)
		(net 5)
	)
	(via
		(at 142.4 129.65)
		(size 0.45)
		(drill 0.1)
		(layers "F.Cu" "B.Cu")
		(net 5)
	)
	(via
		(at 168.95 118.2)
		(size 0.45)
		(drill 0.1)
		(layers "F.Cu" "B.Cu")
		(remove_unused_layers yes)
		(keep_end_layers yes)
		(free yes)
		(zone_layer_connections "In4.Cu")
		(net 5)
	)
	(via
		(at 169.5 115.2)
		(size 0.45)
		(drill 0.1)
		(layers "F.Cu" "B.Cu")
		(remove_unused_layers yes)
		(keep_end_layers yes)
		(free yes)
		(zone_layer_connections "In4.Cu")
		(net 5)
	)
	(via
		(at 235.3 97.25)
		(size 0.45)
		(drill 0.1)
		(layers "F.Cu" "B.Cu")
		(free yes)
		(net 5)
	)
	(via
		(at 168.35 118.2)
		(size 0.45)
		(drill 0.1)
		(layers "F.Cu" "B.Cu")
		(remove_unused_layers yes)
		(keep_end_layers yes)
		(free yes)
		(zone_layer_connections "In4.Cu")
		(net 5)
	)
	(via
		(at 169.5 117.6)
		(size 0.45)
		(drill 0.1)
		(layers "F.Cu" "B.Cu")
		(remove_unused_layers yes)
		(keep_end_layers yes)
		(free yes)
		(zone_layer_connections "In4.Cu")
		(net 5)
	)
	(via
		(at 168.35 114.6)
		(size 0.45)
		(drill 0.1)
		(layers "F.Cu" "B.Cu")
		(remove_unused_layers yes)
		(keep_end_layers yes)
		(free yes)
		(zone_layer_connections "In4.Cu")
		(net 5)
	)
	(via
		(at 168.35 117.6)
		(size 0.45)
		(drill 0.1)
		(layers "F.Cu" "B.Cu")
		(remove_unused_layers yes)
		(keep_end_layers yes)
		(free yes)
		(zone_layer_connections "In4.Cu")
		(net 5)
	)
	(via
		(at 234.7 97.25)
		(size 0.45)
		(drill 0.1)
		(layers "F.Cu" "B.Cu")
		(free yes)
		(net 5)
	)
	(via
		(at 234.7 96.65)
		(size 0.45)
		(drill 0.1)
		(layers "F.Cu" "B.Cu")
		(free yes)
		(net 5)
	)
	(via
		(at 212.9 99.3)
		(size 0.45)
		(drill 0.1)
		(layers "F.Cu" "B.Cu")
		(net 5)
	)
	(via
		(at 236.7 83.8)
		(size 0.45)
		(drill 0.1)
		(layers "F.Cu" "B.Cu")
		(free yes)
		(net 5)
	)
	(via
		(at 104.2 133)
		(size 0.45)
		(drill 0.1)
		(layers "F.Cu" "B.Cu")
		(free yes)
		(net 5)
	)
	(via
		(at 199.85 72.75)
		(size 0.45)
		(drill 0.1)
		(layers "F.Cu" "B.Cu")
		(net 5)
	)
	(via
		(at 234.6 123.2)
		(size 0.45)
		(drill 0.1)
		(layers "F.Cu" "B.Cu")
		(free yes)
		(net 5)
	)
	(via
		(at 218.7 119.7)
		(size 0.45)
		(drill 0.1)
		(layers "F.Cu" "B.Cu")
		(net 5)
	)
	(via
		(at 103.4 133)
		(size 0.45)
		(drill 0.1)
		(layers "F.Cu" "B.Cu")
		(free yes)
		(net 5)
	)
	(via
		(at 170.1 115.2)
		(size 0.45)
		(drill 0.1)
		(layers "F.Cu" "B.Cu")
		(remove_unused_layers yes)
		(keep_end_layers yes)
		(free yes)
		(zone_layer_connections "In4.Cu")
		(net 5)
	)
	(via
		(at 202.9 101)
		(size 0.45)
		(drill 0.1)
		(layers "F.Cu" "B.Cu")
		(net 5)
	)
	(via
		(at 236.35 110.75)
		(size 0.45)
		(drill 0.1)
		(layers "F.Cu" "B.Cu")
		(free yes)
		(net 5)
	)
	(via
		(at 235.32 96.6)
		(size 0.45)
		(drill 0.1)
		(layers "F.Cu" "B.Cu")
		(free yes)
		(net 5)
	)
	(via
		(at 168.95 116.4)
		(size 0.45)
		(drill 0.1)
		(layers "F.Cu" "B.Cu")
		(remove_unused_layers yes)
		(keep_end_layers yes)
		(free yes)
		(zone_layer_connections "In4.Cu")
		(net 5)
	)
	(via
		(at 236.1 84.4)
		(size 0.45)
		(drill 0.1)
		(layers "F.Cu" "B.Cu")
		(free yes)
		(net 5)
	)
	(via
		(at 168.35 114)
		(size 0.45)
		(drill 0.1)
		(layers "F.Cu" "B.Cu")
		(remove_unused_layers yes)
		(keep_end_layers yes)
		(free yes)
		(zone_layer_connections "In4.Cu")
		(net 5)
	)
	(via
		(at 170.1 118.2)
		(size 0.45)
		(drill 0.1)
		(layers "F.Cu" "B.Cu")
		(remove_unused_layers yes)
		(keep_end_layers yes)
		(free yes)
		(zone_layer_connections "In4.Cu")
		(net 5)
	)
	(via
		(at 168.95 114)
		(size 0.45)
		(drill 0.1)
		(layers "F.Cu" "B.Cu")
		(remove_unused_layers yes)
		(keep_end_layers yes)
		(free yes)
		(zone_layer_connections "In4.Cu")
		(net 5)
	)
	(via
		(at 168.35 117)
		(size 0.45)
		(drill 0.1)
		(layers "F.Cu" "B.Cu")
		(remove_unused_layers yes)
		(keep_end_layers yes)
		(free yes)
		(zone_layer_connections "In4.Cu")
		(net 5)
	)
	(via
		(at 201.65 72.75)
		(size 0.45)
		(drill 0.1)
		(layers "F.Cu" "B.Cu")
		(net 5)
	)
	(via
		(at 235.2 123.8)
		(size 0.45)
		(drill 0.1)
		(layers "F.Cu" "B.Cu")
		(free yes)
		(net 5)
	)
	(via
		(at 236.35 123.8)
		(size 0.45)
		(drill 0.1)
		(layers "F.Cu" "B.Cu")
		(free yes)
		(net 5)
	)
	(via
		(at 169.5 118.2)
		(size 0.45)
		(drill 0.1)
		(layers "F.Cu" "B.Cu")
		(remove_unused_layers yes)
		(keep_end_layers yes)
		(free yes)
		(zone_layer_connections "In4.Cu")
		(net 5)
	)
	(via
		(at 215.5 109.5)
		(size 0.45)
		(drill 0.1)
		(layers "F.Cu" "B.Cu")
		(net 5)
	)
	(via
		(at 170.1 114.6)
		(size 0.45)
		(drill 0.1)
		(layers "F.Cu" "B.Cu")
		(remove_unused_layers yes)
		(keep_end_layers yes)
		(free yes)
		(zone_layer_connections "In4.Cu")
		(net 5)
	)
	(via
		(at 235.25 110.75)
		(size 0.45)
		(drill 0.1)
		(layers "F.Cu" "B.Cu")
		(free yes)
		(net 5)
	)
	(via
		(at 102.6 133)
		(size 0.45)
		(drill 0.1)
		(layers "F.Cu" "B.Cu")
		(free yes)
		(net 5)
	)
	(via
		(at 234.1 97.25)
		(size 0.45)
		(drill 0.1)
		(layers "F.Cu" "B.Cu")
		(free yes)
		(net 5)
	)
	(via
		(at 236.1 83.8)
		(size 0.45)
		(drill 0.1)
		(layers "F.Cu" "B.Cu")
		(free yes)
		(net 5)
	)
	(via
		(at 170.75 58)
		(size 0.45)
		(drill 0.1)
		(layers "F.Cu" "B.Cu")
		(net 5)
	)
	(via
		(at 170.1 116.4)
		(size 0.45)
		(drill 0.1)
		(layers "F.Cu" "B.Cu")
		(remove_unused_layers yes)
		(keep_end_layers yes)
		(free yes)
		(zone_layer_connections "In4.Cu")
		(net 5)
	)
	(via
		(at 235.8 123.8)
		(size 0.45)
		(drill 0.1)
		(layers "F.Cu" "B.Cu")
		(free yes)
		(net 5)
	)
	(via
		(at 101.6 131)
		(size 0.45)
		(drill 0.1)
		(layers "F.Cu" "B.Cu")
		(free yes)
		(net 5)
	)
	(via
		(at 234.6 109.7)
		(size 0.45)
		(drill 0.1)
		(layers "F.Cu" "B.Cu")
		(free yes)
		(net 5)
	)
	(via
		(at 104.6 133.6)
		(size 0.45)
		(drill 0.1)
		(layers "F.Cu" "B.Cu")
		(free yes)
		(net 5)
	)
	(via
		(at 63.9 81)
		(size 0.45)
		(drill 0.1)
		(layers "F.Cu" "B.Cu")
		(net 5)
	)
	(via
		(at 168.35 115.2)
		(size 0.45)
		(drill 0.1)
		(layers "F.Cu" "B.Cu")
		(remove_unused_layers yes)
		(keep_end_layers yes)
		(free yes)
		(zone_layer_connections "In4.Cu")
		(net 5)
	)
	(via
		(at 63.9 80.4)
		(size 0.45)
		(drill 0.1)
		(layers "F.Cu" "B.Cu")
		(net 5)
	)
	(via
		(at 170.1 114)
		(size 0.45)
		(drill 0.1)
		(layers "F.Cu" "B.Cu")
		(remove_unused_layers yes)
		(keep_end_layers yes)
		(free yes)
		(zone_layer_connections "In4.Cu")
		(net 5)
	)
	(via
		(at 199.4 82.8)
		(size 0.45)
		(drill 0.1)
		(layers "F.Cu" "B.Cu")
		(net 5)
	)
	(via
		(at 170.1 117)
		(size 0.45)
		(drill 0.1)
		(layers "F.Cu" "B.Cu")
		(remove_unused_layers yes)
		(keep_end_layers yes)
		(free yes)
		(zone_layer_connections "In4.Cu")
		(net 5)
	)
	(via
		(at 236.95 123.8)
		(size 0.45)
		(drill 0.1)
		(layers "F.Cu" "B.Cu")
		(free yes)
		(net 5)
	)
	(via
		(at 166.99 146.065)
		(size 0.45)
		(drill 0.1)
		(layers "F.Cu" "B.Cu")
		(net 5)
	)
	(via
		(at 63.2 81)
		(size 0.45)
		(drill 0.1)
		(layers "F.Cu" "B.Cu")
		(net 5)
	)
	(via
		(at 170.1 117.6)
		(size 0.45)
		(drill 0.1)
		(layers "F.Cu" "B.Cu")
		(remove_unused_layers yes)
		(keep_end_layers yes)
		(free yes)
		(zone_layer_connections "In4.Cu")
		(net 5)
	)
	(via
		(at 169.5 115.8)
		(size 0.45)
		(drill 0.1)
		(layers "F.Cu" "B.Cu")
		(remove_unused_layers yes)
		(keep_end_layers yes)
		(free yes)
		(zone_layer_connections "In4.Cu")
		(net 5)
	)
	(via
		(at 188.25 127.95)
		(size 0.45)
		(drill 0.1)
		(layers "F.Cu" "B.Cu")
		(remove_unused_layers yes)
		(keep_end_layers yes)
		(zone_layer_connections "In4.Cu")
		(net 5)
	)
	(via
		(at 219 109.5)
		(size 0.45)
		(drill 0.1)
		(layers "F.Cu" "B.Cu")
		(net 5)
	)
	(via
		(at 200.5 72.75)
		(size 0.45)
		(drill 0.1)
		(layers "F.Cu" "B.Cu")
		(net 5)
	)
	(via
		(at 104.8 131)
		(size 0.45)
		(drill 0.1)
		(layers "F.Cu" "B.Cu")
		(free yes)
		(net 5)
	)
	(via
		(at 169.5 114.6)
		(size 0.45)
		(drill 0.1)
		(layers "F.Cu" "B.Cu")
		(remove_unused_layers yes)
		(keep_end_layers yes)
		(free yes)
		(zone_layer_connections "In4.Cu")
		(net 5)
	)
	(via
		(at 239 94)
		(size 0.45)
		(drill 0.1)
		(layers "F.Cu" "B.Cu")
		(net 5)
	)
	(via
		(at 102.2 131)
		(size 0.45)
		(drill 0.1)
		(layers "F.Cu" "B.Cu")
		(free yes)
		(net 5)
	)
	(via
		(at 168.95 117)
		(size 0.45)
		(drill 0.1)
		(layers "F.Cu" "B.Cu")
		(remove_unused_layers yes)
		(keep_end_layers yes)
		(free yes)
		(zone_layer_connections "In4.Cu")
		(net 5)
	)
	(via
		(at 143.75 129.65)
		(size 0.45)
		(drill 0.1)
		(layers "F.Cu" "B.Cu")
		(net 5)
	)
	(via
		(at 138.2 135.85)
		(size 0.45)
		(drill 0.1)
		(layers "F.Cu" "B.Cu")
		(net 5)
	)
	(via
		(at 233.4 135.8)
		(size 0.45)
		(drill 0.1)
		(layers "F.Cu" "B.Cu")
		(free yes)
		(net 5)
	)
	(via
		(at 168.95 117.6)
		(size 0.45)
		(drill 0.1)
		(layers "F.Cu" "B.Cu")
		(remove_unused_layers yes)
		(keep_end_layers yes)
		(free yes)
		(zone_layer_connections "In4.Cu")
		(net 5)
	)
	(via
		(at 199.25 72.75)
		(size 0.45)
		(drill 0.1)
		(layers "F.Cu" "B.Cu")
		(net 5)
	)
	(via
		(at 168.95 115.2)
		(size 0.45)
		(drill 0.1)
		(layers "F.Cu" "B.Cu")
		(remove_unused_layers yes)
		(keep_end_layers yes)
		(free yes)
		(zone_layer_connections "In4.Cu")
		(net 5)
	)
	(via
		(at 168.95 115.8)
		(size 0.45)
		(drill 0.1)
		(layers "F.Cu" "B.Cu")
		(remove_unused_layers yes)
		(keep_end_layers yes)
		(free yes)
		(zone_layer_connections "In4.Cu")
		(net 5)
	)
	(via
		(at 138.25 135.05)
		(size 0.45)
		(drill 0.1)
		(layers "F.Cu" "B.Cu")
		(net 5)
	)
	(via
		(at 169.5 117)
		(size 0.45)
		(drill 0.1)
		(layers "F.Cu" "B.Cu")
		(remove_unused_layers yes)
		(keep_end_layers yes)
		(free yes)
		(zone_layer_connections "In4.Cu")
		(net 5)
	)
	(via
		(at 234.6 135.8)
		(size 0.45)
		(drill 0.1)
		(layers "F.Cu" "B.Cu")
		(free yes)
		(net 5)
	)
	(via
		(at 169.5 114)
		(size 0.45)
		(drill 0.1)
		(layers "F.Cu" "B.Cu")
		(remove_unused_layers yes)
		(keep_end_layers yes)
		(free yes)
		(zone_layer_connections "In4.Cu")
		(net 5)
	)
	(via
		(at 168.35 115.8)
		(size 0.45)
		(drill 0.1)
		(layers "F.Cu" "B.Cu")
		(remove_unused_layers yes)
		(keep_end_layers yes)
		(free yes)
		(zone_layer_connections "In4.Cu")
		(net 5)
	)
	(via
		(at 156.85 141.88)
		(size 0.45)
		(drill 0.1)
		(layers "F.Cu" "B.Cu")
		(net 5)
	)
	(via
		(at 160.8 58)
		(size 0.45)
		(drill 0.1)
		(layers "F.Cu" "B.Cu")
		(net 5)
	)
	(via
		(at 103.6 131)
		(size 0.45)
		(drill 0.1)
		(layers "F.Cu" "B.Cu")
		(free yes)
		(net 5)
	)
	(via
		(at 170.1 115.8)
		(size 0.45)
		(drill 0.1)
		(layers "F.Cu" "B.Cu")
		(remove_unused_layers yes)
		(keep_end_layers yes)
		(free yes)
		(zone_layer_connections "In4.Cu")
		(net 5)
	)
	(via
		(at 235.8 110.75)
		(size 0.45)
		(drill 0.1)
		(layers "F.Cu" "B.Cu")
		(free yes)
		(net 5)
	)
	(via
		(at 201.1 72.75)
		(size 0.45)
		(drill 0.1)
		(layers "F.Cu" "B.Cu")
		(net 5)
	)
	(via
		(at 236.6 63.8)
		(size 0.45)
		(drill 0.1)
		(layers "F.Cu" "B.Cu")
		(net 5)
	)
	(via
		(at 186.94 128)
		(size 0.45)
		(drill 0.1)
		(layers "F.Cu" "B.Cu")
		(remove_unused_layers yes)
		(keep_end_layers yes)
		(zone_layer_connections "In4.Cu")
		(net 5)
	)
	(via
		(at 168.35 116.4)
		(size 0.45)
		(drill 0.1)
		(layers "F.Cu" "B.Cu")
		(remove_unused_layers yes)
		(keep_end_layers yes)
		(free yes)
		(zone_layer_connections "In4.Cu")
		(net 5)
	)
	(via
		(at 234.1 96.65)
		(size 0.45)
		(drill 0.1)
		(layers "F.Cu" "B.Cu")
		(free yes)
		(net 5)
	)
	(via
		(at 103 133.6)
		(size 0.45)
		(drill 0.1)
		(layers "F.Cu" "B.Cu")
		(free yes)
		(net 5)
	)
	(via
		(at 103.8 133.6)
		(size 0.45)
		(drill 0.1)
		(layers "F.Cu" "B.Cu")
		(free yes)
		(net 5)
	)
	(via
		(at 168.95 114.6)
		(size 0.45)
		(drill 0.1)
		(layers "F.Cu" "B.Cu")
		(remove_unused_layers yes)
		(keep_end_layers yes)
		(free yes)
		(zone_layer_connections "In4.Cu")
		(net 5)
	)
	(via
		(at 167 146.825)
		(size 0.45)
		(drill 0.1)
		(layers "F.Cu" "B.Cu")
		(net 5)
	)
	(via
		(at 236.9 110.75)
		(size 0.45)
		(drill 0.1)
		(layers "F.Cu" "B.Cu")
		(free yes)
		(net 5)
	)
	(via
		(at 104.2 131)
		(size 0.45)
		(drill 0.1)
		(layers "F.Cu" "B.Cu")
		(free yes)
		(net 5)
	)
	(segment
		(start 222.583 120.923)
		(end 222.583 119.903)
		(width 0.2)
		(layer "B.Cu")
		(net 5)
	)
	(segment
		(start 234.18 79.6)
		(end 234.18 80.1)
		(width 0.1)
		(layer "B.Cu")
		(net 5)
	)
	(segment
		(start 161.8 57.98)
		(end 160.82 57.98)
		(width 0.1)
		(layer "B.Cu")
		(net 5)
	)
	(segment
		(start 216.543 109.497)
		(end 216.56 109.48)
		(width 0.2)
		(layer "B.Cu")
		(net 5)
	)
	(segment
		(start 222.583 119.903)
		(end 222.58 119.9)
		(width 0.2)
		(layer "B.Cu")
		(net 5)
	)
	(segment
		(start 216.543 110.493)
		(end 216.543 109.497)
		(width 0.2)
		(layer "B.Cu")
		(net 5)
	)
	(segment
		(start 210.128 65.053)
		(end 210.475 65.4)
		(width 0.75)
		(layer "B.Cu")
		(net 5)
	)
	(segment
		(start 202.92 101.800001)
		(end 202.92 101.02)
		(width 0.3)
		(layer "B.Cu")
		(net 5)
	)
	(segment
		(start 239.059002 93.424001)
		(end 239.059002 93.940998)
		(width 0.2)
		(layer "B.Cu")
		(net 5)
	)
	(segment
		(start 235.099 82.747)
		(end 234.047 82.747)
		(width 0.1)
		(layer "B.Cu")
		(net 5)
	)
	(segment
		(start 208.4125 69.4125)
		(end 208.4125 71.2875)
		(width 0.75)
		(layer "B.Cu")
		(net 5)
	)
	(segment
		(start 222.58 119.88)
		(end 222.1 119.4)
		(width 0.2)
		(layer "B.Cu")
		(net 5)
	)
	(segment
		(start 219.09 109.51)
		(end 219.7 109.51)
		(width 0.2)
		(layer "B.Cu")
		(net 5)
	)
	(segment
		(start 210.475 65.4)
		(end 210.475 67.35)
		(width 0.75)
		(layer "B.Cu")
		(net 5)
	)
	(segment
		(start 219 109.5)
		(end 219.08 109.5)
		(width 0.2)
		(layer "B.Cu")
		(net 5)
	)
	(segment
		(start 210.475 67.35)
		(end 208.4125 69.4125)
		(width 0.75)
		(layer "B.Cu")
		(net 5)
	)
	(segment
		(start 234.047 82.747)
		(end 233.9 82.6)
		(width 0.1)
		(layer "B.Cu")
		(net 5)
	)
	(segment
		(start 239.059002 93.940998)
		(end 239 94)
		(width 0.2)
		(layer "B.Cu")
		(net 5)
	)
	(segment
		(start 215.32 100.4)
		(end 214 100.4)
		(width 0.1)
		(layer "B.Cu")
		(net 5)
	)
	(segment
		(start 207.8875 71.8125)
		(end 206.0125 71.8125)
		(width 0.75)
		(layer "B.Cu")
		(net 5)
	)
	(segment
		(start 219.08 109.5)
		(end 219.09 109.51)
		(width 0.2)
		(layer "B.Cu")
		(net 5)
	)
	(segment
		(start 234.28 80.2)
		(end 234.18 80.1)
		(width 0.1)
		(layer "B.Cu")
		(net 5)
	)
	(segment
		(start 219.7 110.506)
		(end 219.683 110.523)
		(width 0.2)
		(layer "B.Cu")
		(net 5)
	)
	(segment
		(start 222.58 119.9)
		(end 222.58 119.88)
		(width 0.2)
		(layer "B.Cu")
		(net 5)
	)
	(segment
		(start 219.2 119.7)
		(end 218.7 119.7)
		(width 0.2)
		(layer "B.Cu")
		(net 5)
	)
	(segment
		(start 201.65 72.75)
		(end 205.15 72.75)
		(width 0.5)
		(layer "B.Cu")
		(net 5)
	)
	(segment
		(start 209.201 65.053)
		(end 210.128 65.053)
		(width 0.75)
		(layer "B.Cu")
		(net 5)
	)
	(segment
		(start 234.18 80.2)
		(end 234.18 80.3)
		(width 0.1)
		(layer "B.Cu")
		(net 5)
	)
	(segment
		(start 219.393 120.904698)
		(end 219.393 119.907)
		(width 0.2)
		(layer "B.Cu")
		(net 5)
	)
	(segment
		(start 234.18 80.52)
		(end 233.9 80.8)
		(width 0.1)
		(layer "B.Cu")
		(net 5)
	)
	(segment
		(start 215.52 109.48)
		(end 215.5 109.5)
		(width 0.2)
		(layer "B.Cu")
		(net 5)
	)
	(segment
		(start 210.4 65.25)
		(end 210.203 65.053)
		(width 0.5)
		(layer "B.Cu")
		(net 5)
	)
	(segment
		(start 234.18 80.1)
		(end 234.18 80.2)
		(width 0.1)
		(layer "B.Cu")
		(net 5)
	)
	(segment
		(start 216.56 109.48)
		(end 215.52 109.48)
		(width 0.2)
		(layer "B.Cu")
		(net 5)
	)
	(segment
		(start 160.82 57.98)
		(end 160.8 58)
		(width 0.1)
		(layer "B.Cu")
		(net 5)
	)
	(segment
		(start 202.92 103.8)
		(end 202.92 102.8)
		(width 0.3)
		(layer "B.Cu")
		(net 5)
	)
	(segment
		(start 206.0125 71.8125)
		(end 205.075 72.75)
		(width 0.75)
		(layer "B.Cu")
		(net 5)
	)
	(segment
		(start 214 100.4)
		(end 212.9 99.3)
		(width 0.1)
		(layer "B.Cu")
		(net 5)
	)
	(segment
		(start 199.25 72.75)
		(end 201.65 72.75)
		(width 0.5)
		(layer "B.Cu")
		(net 5)
	)
	(segment
		(start 205.075 72.75)
		(end 199.25 72.75)
		(width 0.75)
		(layer "B.Cu")
		(net 5)
	)
	(segment
		(start 237.37 80.2)
		(end 237.62 80.45)
		(width 0.1)
		(layer "B.Cu")
		(net 5)
	)
	(segment
		(start 209.201 65.053)
		(end 207.533 65.053)
		(width 0.5)
		(layer "B.Cu")
		(net 5)
	)
	(segment
		(start 234.3 80.2)
		(end 237.37 80.2)
		(width 0.1)
		(layer "B.Cu")
		(net 5)
	)
	(segment
		(start 234.3 80.2)
		(end 234.28 80.2)
		(width 0.1)
		(layer "B.Cu")
		(net 5)
	)
	(segment
		(start 210.4 67.5)
		(end 210.4 65.25)
		(width 0.5)
		(layer "B.Cu")
		(net 5)
	)
	(segment
		(start 207.533 65.053)
		(end 207.48 65)
		(width 0.5)
		(layer "B.Cu")
		(net 5)
	)
	(segment
		(start 208.4125 71.2875)
		(end 207.8875 71.8125)
		(width 0.75)
		(layer "B.Cu")
		(net 5)
	)
	(segment
		(start 234.18 80.3)
		(end 234.18 80.52)
		(width 0.1)
		(layer "B.Cu")
		(net 5)
	)
	(segment
		(start 235.68 63.8)
		(end 236.6 63.8)
		(width 0.2)
		(layer "B.Cu")
		(net 5)
	)
	(segment
		(start 202.92 101.02)
		(end 202.9 101)
		(width 0.3)
		(layer "B.Cu")
		(net 5)
	)
	(segment
		(start 210.203 65.053)
		(end 209.201 65.053)
		(width 0.5)
		(layer "B.Cu")
		(net 5)
	)
	(segment
		(start 219.393 119.907)
		(end 219.4 119.9)
		(width 0.2)
		(layer "B.Cu")
		(net 5)
	)
	(segment
		(start 219.4 119.9)
		(end 219.2 119.7)
		(width 0.2)
		(layer "B.Cu")
		(net 5)
	)
	(segment
		(start 234.18 80.2)
		(end 234.3 80.2)
		(width 0.1)
		(layer "B.Cu")
		(net 5)
	)
	(segment
		(start 171.89 58)
		(end 170.75 58)
		(width 0.1)
		(layer "B.Cu")
		(net 5)
	)
	(segment
		(start 235.099 84.081)
		(end 235.08 84.1)
		(width 0.3)
		(layer "B.Cu")
		(net 5)
	)
	(segment
		(start 219.7 109.51)
		(end 219.7 110.506)
		(width 0.2)
		(layer "B.Cu")
		(net 5)
	)
	(segment
		(start 164 57.98)
		(end 161.8 57.98)
		(width 0.1)
		(layer "B.Cu")
		(net 5)
	)
	(segment
		(start 202.92 102.8)
		(end 202.92 101.800001)
		(width 0.3)
		(layer "B.Cu")
		(net 5)
	)
	(segment
		(start 233.9 82.6)
		(end 233.9 80.8)
		(width 0.1)
		(layer "B.Cu")
		(net 5)
	)
	(segment
		(start 234.28 80.2)
		(end 234.18 80.3)
		(width 0.1)
		(layer "B.Cu")
		(net 5)
	)
	(segment
		(start 61.92 92.78)
		(end 62.1 92.6)
		(width 0.2)
		(layer "F.Cu")
		(net 6)
	)
	(segment
		(start 62.1 92.6)
		(end 62.7 92.6)
		(width 0.2)
		(layer "F.Cu")
		(net 6)
	)
	(segment
		(start 61 92.78)
		(end 61.92 92.78)
		(width 0.2)
		(layer "F.Cu")
		(net 6)
	)
	(via
		(at 62.7 92.6)
		(size 0.45)
		(drill 0.1)
		(layers "F.Cu" "B.Cu")
		(free yes)
		(net 6)
	)
	(via
		(at 62.7 92)
		(size 0.45)
		(drill 0.1)
		(layers "F.Cu" "B.Cu")
		(free yes)
		(net 6)
	)
	(via
		(at 62.7 93.2)
		(size 0.45)
		(drill 0.1)
		(layers "F.Cu" "B.Cu")
		(free yes)
		(net 6)
	)
	(via
		(at 62.7 91.4)
		(size 0.45)
		(drill 0.1)
		(layers "F.Cu" "B.Cu")
		(free yes)
		(net 6)
	)
	(segment
		(start 61.6 91.4)
		(end 62.7 91.4)
		(width 0.1)
		(layer "B.Cu")
		(net 6)
	)
	(segment
		(start 60.6 90.4)
		(end 61.6 91.4)
		(width 0.1)
		(layer "B.Cu")
		(net 6)
	)
	(segment
		(start 60.6 88)
		(end 60.6 90.4)
		(width 0.1)
		(layer "B.Cu")
		(net 6)
	)
	(segment
		(start 63.061 92.961)
		(end 62.7 92.6)
		(width 0.3)
		(layer "B.Cu")
		(net 6)
	)
	(segment
		(start 62.4 87.6)
		(end 61 87.6)
		(width 0.1)
		(layer "B.Cu")
		(net 6)
	)
	(segment
		(start 64.59 92.961)
		(end 63.061 92.961)
		(width 0.3)
		(layer "B.Cu")
		(net 6)
	)
	(segment
		(start 62.8 86.48)
		(end 62.8 87.2)
		(width 0.1)
		(layer "B.Cu")
		(net 6)
	)
	(segment
		(start 64.59 92.461)
		(end 62.839 92.461)
		(width 0.3)
		(layer "B.Cu")
		(net 6)
	)
	(segment
		(start 62.8 87.2)
		(end 62.4 87.6)
		(width 0.1)
		(layer "B.Cu")
		(net 6)
	)
	(segment
		(start 61 87.6)
		(end 60.6 88)
		(width 0.1)
		(layer "B.Cu")
		(net 6)
	)
	(segment
		(start 62.839 92.461)
		(end 62.7 92.6)
		(width 0.3)
		(layer "B.Cu")
		(net 6)
	)
	(segment
		(start 66.1 91.9)
		(end 66.1 92.68)
		(width 0.2)
		(layer "F.Cu")
		(net 7)
	)
	(segment
		(start 66.1 92.68)
		(end 66.12 92.7)
		(width 0.2)
		(layer "F.Cu")
		(net 7)
	)
	(via
		(at 66.8 91.3)
		(size 0.45)
		(drill 0.1)
		(layers "F.Cu" "B.Cu")
		(free yes)
		(net 7)
	)
	(via
		(at 66.1 91.3)
		(size 0.45)
		(drill 0.1)
		(layers "F.Cu" "B.Cu")
		(free yes)
		(net 7)
	)
	(via
		(at 66.8 91.9)
		(size 0.45)
		(drill 0.1)
		(layers "F.Cu" "B.Cu")
		(free yes)
		(net 7)
	)
	(via
		(at 66.1 91.9)
		(size 0.45)
		(drill 0.1)
		(layers "F.Cu" "B.Cu")
		(free yes)
		(net 7)
	)
	(segment
		(start 64.2 86)
		(end 62.08 86)
		(width 0.1)
		(layer "B.Cu")
		(net 7)
	)
	(segment
		(start 66.1 90.1)
		(end 65 89)
		(width 0.1)
		(layer "B.Cu")
		(net 7)
	)
	(segment
		(start 62.08 86)
		(end 61.6 86.48)
		(width 0.1)
		(layer "B.Cu")
		(net 7)
	)
	(segment
		(start 65 89)
		(end 65 86.8)
		(width 0.1)
		(layer "B.Cu")
		(net 7)
	)
	(segment
		(start 66.1 91.3)
		(end 66.1 90.1)
		(width 0.1)
		(layer "B.Cu")
		(net 7)
	)
	(segment
		(start 64.59 91.461)
		(end 65.939 91.461)
		(width 0.3)
		(layer "B.Cu")
		(net 7)
	)
	(segment
		(start 65.939 91.461)
		(end 66.1 91.3)
		(width 0.3)
		(layer "B.Cu")
		(net 7)
	)
	(segment
		(start 65 86.8)
		(end 64.2 86)
		(width 0.1)
		(layer "B.Cu")
		(net 7)
	)
	(segment
		(start 64.59 91.961)
		(end 66.039 91.961)
		(width 0.3)
		(layer "B.Cu")
		(net 7)
	)
	(segment
		(start 66.039 91.961)
		(end 66.1 91.9)
		(width 0.3)
		(layer "B.Cu")
		(net 7)
	)
	(segment
		(start 223.02 54.75)
		(end 222.25 54.75)
		(width 0.1)
		(layer "B.Cu")
		(net 8)
	)
	(segment
		(start 212.6 60.754)
		(end 211.801 61.553)
		(width 0.2)
		(layer "B.Cu")
		(net 8)
	)
	(segment
		(start 217.8 56.87)
		(end 217.8 55.65)
		(width 0.1)
		(layer "B.Cu")
		(net 8)
	)
	(segment
		(start 217 59.4)
		(end 217.157 59.243)
		(width 0.3)
		(layer "B.Cu")
		(net 8)
	)
	(segment
		(start 216.657 59.357)
		(end 216.7 59.4)
		(width 0.3)
		(layer "B.Cu")
		(net 8)
	)
	(segment
		(start 217.157 59.243)
		(end 217.157 58.39)
		(width 0.3)
		(layer "B.Cu")
		(net 8)
	)
	(segment
		(start 217.157 57.513)
		(end 217.51 57.16)
		(width 0.1)
		(layer "B.Cu")
		(net 8)
	)
	(segment
		(start 211.48 60)
		(end 212.6 60)
		(width 0.2)
		(layer "B.Cu")
		(net 8)
	)
	(segment
		(start 216.7 59.4)
		(end 217 59.4)
		(width 0.3)
		(layer "B.Cu")
		(net 8)
	)
	(segment
		(start 216.657 58.39)
		(end 216.657 59.357)
		(width 0.3)
		(layer "B.Cu")
		(net 8)
	)
	(segment
		(start 217.51 57.16)
		(end 217.8 56.87)
		(width 0.1)
		(layer "B.Cu")
		(net 8)
	)
	(segment
		(start 217.157 58.39)
		(end 217.157 57.513)
		(width 0.1)
		(layer "B.Cu")
		(net 8)
	)
	(segment
		(start 222.25 54.75)
		(end 221.85 54.35)
		(width 0.1)
		(layer "B.Cu")
		(net 8)
	)
	(segment
		(start 218.6 54.35)
		(end 217.8 55.15)
		(width 0.1)
		(layer "B.Cu")
		(net 8)
	)
	(segment
		(start 217.8 55.15)
		(end 217.8 55.65)
		(width 0.1)
		(layer "B.Cu")
		(net 8)
	)
	(segment
		(start 212.6 60)
		(end 212.6 60.754)
		(width 0.2)
		(layer "B.Cu")
		(net 8)
	)
	(segment
		(start 221.85 54.35)
		(end 218.6 54.35)
		(width 0.1)
		(layer "B.Cu")
		(net 8)
	)
	(segment
		(start 218.157 59.143)
		(end 218 59.3)
		(width 0.3)
		(layer "B.Cu")
		(net 9)
	)
	(segment
		(start 218.157 58.39)
		(end 218.157 59.143)
		(width 0.3)
		(layer "B.Cu")
		(net 9)
	)
	(segment
		(start 217.657 59.257)
		(end 217.7 59.3)
		(width 0.3)
		(layer "B.Cu")
		(net 9)
	)
	(segment
		(start 218.157 55.243)
		(end 218.157 58.39)
		(width 0.1)
		(layer "B.Cu")
		(net 9)
	)
	(segment
		(start 217.7 59.3)
		(end 218 59.3)
		(width 0.3)
		(layer "B.Cu")
		(net 9)
	)
	(segment
		(start 218.635 54.765)
		(end 218.157 55.243)
		(width 0.1)
		(layer "B.Cu")
		(net 9)
	)
	(segment
		(start 221.535 54.765)
		(end 218.635 54.765)
		(width 0.1)
		(layer "B.Cu")
		(net 9)
	)
	(segment
		(start 217.657 58.39)
		(end 217.657 59.257)
		(width 0.3)
		(layer "B.Cu")
		(net 9)
	)
	(segment
		(start 223.02 56.25)
		(end 221.535 54.765)
		(width 0.1)
		(layer "B.Cu")
		(net 9)
	)
	(segment
		(start 148.088313 148.96)
		(end 148.723313 149.595)
		(width 0.2)
		(layer "B.Cu")
		(net 10)
	)
	(segment
		(start 146.530532 148.96)
		(end 148.088313 148.96)
		(width 0.2)
		(layer "B.Cu")
		(net 10)
	)
	(segment
		(start 147.9 123.45)
		(end 146.6 123.45)
		(width 0.5)
		(layer "F.Cu")
		(net 11)
	)
	(segment
		(start 61.12 62.16)
		(end 62.08 61.2)
		(width 0.1)
		(layer "F.Cu")
		(net 11)
	)
	(segment
		(start 151.2 97.2)
		(end 151.1 97.1)
		(width 0.2)
		(layer "F.Cu")
		(net 11)
	)
	(segment
		(start 148.430067 123.45)
		(end 147.9 123.45)
		(width 0.3)
		(layer "F.Cu")
		(net 11)
	)
	(segment
		(start 146.8 113.8)
		(end 146.52 113.52)
		(width 0.2)
		(layer "F.Cu")
		(net 11)
	)
	(segment
		(start 187.25 57.73)
		(end 187.25 58.5)
		(width 0.2)
		(layer "F.Cu")
		(net 11)
	)
	(segment
		(start 153.95 106.35)
		(end 153.95 106.7)
		(width 0.2)
		(layer "F.Cu")
		(net 11)
	)
	(segment
		(start 151.979998 96.000001)
		(end 151.979998 95.320002)
		(width 0.2)
		(layer "F.Cu")
		(net 11)
	)
	(segment
		(start 67.4 96.595)
		(end 66.905 96.595)
		(width 0.2)
		(layer "F.Cu")
		(net 11)
	)
	(segment
		(start 146.52 113.52)
		(end 146.52 110)
		(width 0.2)
		(layer "F.Cu")
		(net 11)
	)
	(segment
		(start 157.08 117.68)
		(end 157.08 121.4)
		(width 0.2)
		(layer "F.Cu")
		(net 11)
	)
	(segment
		(start 147.9 123.05)
		(end 146.6 123.05)
		(width 0.5)
		(layer "F.Cu")
		(net 11)
	)
	(segment
		(start 97.35 64)
		(end 97.55 64)
		(width 0.1)
		(layer "F.Cu")
		(net 11)
	)
	(segment
		(start 152.724 114.564)
		(end 152.96 114.8)
		(width 0.2)
		(layer "F.Cu")
		(net 11)
	)
	(segment
		(start 153.95 106.7)
		(end 153.85 106.8)
		(width 0.2)
		(layer "F.Cu")
		(net 11)
	)
	(segment
		(start 152.724999 106.8)
		(end 152.724999 107.024999)
		(width 0.2)
		(layer "F.Cu")
		(net 11)
	)
	(segment
		(start 146.6 122.7)
		(end 146.6 123.05)
		(width 0.5)
		(layer "F.Cu")
		(net 11)
	)
	(segment
		(start 147.244391 124.005609)
		(end 147.25 124)
		(width 0.5)
		(layer "F.Cu")
		(net 11)
	)
	(segment
		(start 144.911 135.9)
		(end 146.9 133.911)
		(width 0.3)
		(layer "F.Cu")
		(net 11)
	)
	(segment
		(start 152.724999 107.024999)
		(end 153 107.3)
		(width 0.2)
		(layer "F.Cu")
		(net 11)
	)
	(segment
		(start 155 122.2)
		(end 156.9 122.2)
		(width 0.1)
		(layer "F.Cu")
		(net 11)
	)
	(segment
		(start 63.001 61.801)
		(end 62.8 61.6)
		(width 0.2)
		(layer "F.Cu")
		(net 11)
	)
	(segment
		(start 147.25 124)
		(end 147.25 122.7)
		(width 0.5)
		(layer "F.Cu")
		(net 11)
	)
	(segment
		(start 152.236 117.251)
		(end 152.236 116.336)
		(width 0.2)
		(layer "F.Cu")
		(net 11)
	)
	(segment
		(start 151.1 97.1)
		(end 151.1 96.9)
		(width 0.2)
		(layer "F.Cu")
		(net 11)
	)
	(segment
		(start 75.33 76.37)
		(end 75.35 76.35)
		(width 0.1)
		(layer "F.Cu")
		(net 11)
	)
	(segment
		(start 61.12 62.2)
		(end 61.12 62.16)
		(width 0.1)
		(layer "F.Cu")
		(net 11)
	)
	(segment
		(start 148.547551 133.911)
		(end 149.55 132.908551)
		(width 0.3)
		(layer "F.Cu")
		(net 11)
	)
	(segment
		(start 152.73 120.25)
		(end 152.73 120.63)
		(width 0.1)
		(layer "F.Cu")
		(net 11)
	)
	(segment
		(start 164.87 57)
		(end 164.73 57.14)
		(width 0.1)
		(layer "F.Cu")
		(net 11)
	)
	(segment
		(start 162.3 59.3)
		(end 160.1 61.5)
		(width 0.2)
		(layer "F.Cu")
		(net 11)
	)
	(segment
		(start 152.23 110.33)
		(end 152.1 110.2)
		(width 0.2)
		(layer "F.Cu")
		(net 11)
	)
	(segment
		(start 152.1 110.2)
		(end 150.8 110.2)
		(width 0.2)
		(layer "F.Cu")
		(net 11)
	)
	(segment
		(start 150.9 100.6)
		(end 150.6 100.6)
		(width 0.2)
		(layer "F.Cu")
		(net 11)
	)
	(segment
		(start 74.5 76.37)
		(end 75.33 76.37)
		(width 0.1)
		(layer "F.Cu")
		(net 11)
	)
	(segment
		(start 153.02 107.32)
		(end 153 107.3)
		(width 0.2)
		(layer "F.Cu")
		(net 11)
	)
	(segment
		(start 142.4 109.8)
		(end 142.4 108.803001)
		(width 0.1)
		(layer "F.Cu")
		(net 11)
	)
	(segment
		(start 67.4 96.595)
		(end 67.895 96.1)
		(width 0.2)
		(layer "F.Cu")
		(net 11)
	)
	(segment
		(start 147.244391 124.83)
		(end 147.244391 124.005609)
		(width 0.5)
		(layer "F.Cu")
		(net 11)
	)
	(segment
		(start 143.08 135.04)
		(end 143.08 135.58)
		(width 0.3)
		(layer "F.Cu")
		(net 11)
	)
	(segment
		(start 154.5 121.7)
		(end 155 122.2)
		(width 0.1)
		(layer "F.Cu")
		(net 11)
	)
	(segment
		(start 152.300001 97.175)
		(end 152.300001 96.320004)
		(width 0.2)
		(layer "F.Cu")
		(net 11)
	)
	(segment
		(start 157.56 143.88)
		(end 157.56 144.66)
		(width 0.15)
		(layer "F.Cu")
		(net 11)
	)
	(segment
		(start 164.7 59.3)
		(end 162.3 59.3)
		(width 0.2)
		(layer "F.Cu")
		(net 11)
	)
	(segment
		(start 157.56 144.66)
		(end 157.85 144.95)
		(width 0.15)
		(layer "F.Cu")
		(net 11)
	)
	(segment
		(start 143.4 135.9)
		(end 144.911 135.9)
		(width 0.3)
		(layer "F.Cu")
		(net 11)
	)
	(segment
		(start 149.55 132.908551)
		(end 149.55 124.569933)
		(width 0.3)
		(layer "F.Cu")
		(net 11)
	)
	(segment
		(start 153.85 106.8)
		(end 152.724999 106.8)
		(width 0.2)
		(layer "F.Cu")
		(net 11)
	)
	(segment
		(start 151.1 96.9)
		(end 151.979998 96.020002)
		(width 0.2)
		(layer "F.Cu")
		(net 11)
	)
	(segment
		(start 154.5 121.2)
		(end 154.5 121.7)
		(width 0.1)
		(layer "F.Cu")
		(net 11)
	)
	(segment
		(start 66.55 96.95)
		(end 66.905 96.595)
		(width 0.2)
		(layer "F.Cu")
		(net 11)
	)
	(segment
		(start 153.02 107.5)
		(end 153.02 107.32)
		(width 0.2)
		(layer "F.Cu")
		(net 11)
	)
	(segment
		(start 147.8 113.8)
		(end 146.8 113.8)
		(width 0.2)
		(layer "F.Cu")
		(net 11)
	)
	(segment
		(start 143.08 135.58)
		(end 143.4 135.9)
		(width 0.3)
		(layer "F.Cu")
		(net 11)
	)
	(segment
		(start 152.236 116.336)
		(end 152 116.1)
		(width 0.2)
		(layer "F.Cu")
		(net 11)
	)
	(segment
		(start 146.9 133.911)
		(end 148.547551 133.911)
		(width 0.3)
		(layer "F.Cu")
		(net 11)
	)
	(segment
		(start 156.5 117.1)
		(end 157.08 117.68)
		(width 0.2)
		(layer "F.Cu")
		(net 11)
	)
	(segment
		(start 153.81 106.21)
		(end 153.95 106.35)
		(width 0.2)
		(layer "F.Cu")
		(net 11)
	)
	(segment
		(start 157.08 122.02)
		(end 157.08 121.4)
		(width 0.1)
		(layer "F.Cu")
		(net 11)
	)
	(segment
		(start 153.375 106.21)
		(end 153.81 106.21)
		(width 0.2)
		(layer "F.Cu")
		(net 11)
	)
	(segment
		(start 152.724999 106.235)
		(end 152.724999 106.8)
		(width 0.2)
		(layer "F.Cu")
		(net 11)
	)
	(segment
		(start 96.95 64.4)
		(end 97.35 64)
		(width 0.1)
		(layer "F.Cu")
		(net 11)
	)
	(segment
		(start 154.39 102.61)
		(end 154.4 102.6)
		(width 0.2)
		(layer "F.Cu")
		(net 11)
	)
	(segment
		(start 65.15 96.95)
		(end 66.05 96.95)
		(width 0.1)
		(layer "F.Cu")
		(net 11)
	)
	(segment
		(start 61.12 64.2)
		(end 60.6 64.2)
		(width 0.2)
		(layer "F.Cu")
		(net 11)
	)
	(segment
		(start 152 116.1)
		(end 150 116.1)
		(width 0.2)
		(layer "F.Cu")
		(net 11)
	)
	(segment
		(start 146.6 123.05)
		(end 146.6 123.45)
		(width 0.5)
		(layer "F.Cu")
		(net 11)
	)
	(segment
		(start 151.979998 96.020002)
		(end 151.979998 96.000001)
		(width 0.2)
		(layer "F.Cu")
		(net 11)
	)
	(segment
		(start 151.65 100.8)
		(end 151.1 100.8)
		(width 0.2)
		(layer "F.Cu")
		(net 11)
	)
	(segment
		(start 147.9 122.7)
		(end 147.9 123.05)
		(width 0.5)
		(layer "F.Cu")
		(net 11)
	)
	(segment
		(start 152.96 114.8)
		(end 153.8 114.8)
		(width 0.2)
		(layer "F.Cu")
		(net 11)
	)
	(segment
		(start 147.9 123.05)
		(end 147.9 123.45)
		(width 0.5)
		(layer "F.Cu")
		(net 11)
	)
	(segment
		(start 156.9 122.2)
		(end 157.08 122.02)
		(width 0.1)
		(layer "F.Cu")
		(net 11)
	)
	(segment
		(start 152.73 120.63)
		(end 152.9 120.8)
		(width 0.1)
		(layer "F.Cu")
		(net 11)
	)
	(segment
		(start 151.979998 95.320002)
		(end 152 95.3)
		(width 0.2)
		(layer "F.Cu")
		(net 11)
	)
	(segment
		(start 152.9 120.8)
		(end 154.1 120.8)
		(width 0.1)
		(layer "F.Cu")
		(net 11)
	)
	(segment
		(start 157.56 143.88)
		(end 157.56 142.98)
		(width 0.15)
		(layer "F.Cu")
		(net 11)
	)
	(segment
		(start 67.895 96.1)
		(end 70.5 96.1)
		(width 0.2)
		(layer "F.Cu")
		(net 11)
	)
	(segment
		(start 152.23 110.75)
		(end 152.23 110.33)
		(width 0.2)
		(layer "F.Cu")
		(net 11)
	)
	(segment
		(start 156.5 116.7)
		(end 156.5 117.1)
		(width 0.2)
		(layer "F.Cu")
		(net 11)
	)
	(segment
		(start 152.300001 96.320004)
		(end 151.979998 96.000001)
		(width 0.2)
		(layer "F.Cu")
		(net 11)
	)
	(segment
		(start 149.55 124.569933)
		(end 148.430067 123.45)
		(width 0.3)
		(layer "F.Cu")
		(net 11)
	)
	(segment
		(start 63.67 61.801)
		(end 63.001 61.801)
		(width 0.2)
		(layer "F.Cu")
		(net 11)
	)
	(segment
		(start 165.25 58.75)
		(end 164.7 59.3)
		(width 0.2)
		(layer "F.Cu")
		(net 11)
	)
	(segment
		(start 66.05 96.95)
		(end 66.55 96.95)
		(width 0.2)
		(layer "F.Cu")
		(net 11)
	)
	(segment
		(start 148.3 76.7)
		(end 148.3 72)
		(width 0.5)
		(layer "F.Cu")
		(net 11)
	)
	(segment
		(start 165.25 57)
		(end 165.25 58.75)
		(width 0.2)
		(layer "F.Cu")
		(net 11)
	)
	(segment
		(start 62.48 61.6)
		(end 62.08 61.2)
		(width 0.2)
		(layer "F.Cu")
		(net 11)
	)
	(segment
		(start 82.86 59.25)
		(end 82.25 59.25)
		(width 0.1)
		(layer "F.Cu")
		(net 11)
	)
	(segment
		(start 62.8 61.6)
		(end 62.48 61.6)
		(width 0.2)
		(layer "F.Cu")
		(net 11)
	)
	(segment
		(start 164.73 57.14)
		(end 164.03 57.14)
		(width 0.1)
		(layer "F.Cu")
		(net 11)
	)
	(segment
		(start 165.25 57)
		(end 164.87 57)
		(width 0.1)
		(layer "F.Cu")
		(net 11)
	)
	(segment
		(start 150.9 100.6)
		(end 151.1 100.8)
		(width 0.2)
		(layer "F.Cu")
		(net 11)
	)
	(segment
		(start 160.1 61.5)
		(end 158.5 61.5)
		(width 0.2)
		(layer "F.Cu")
		(net 11)
	)
	(segment
		(start 153.375 102.61)
		(end 154.39 102.61)
		(width 0.2)
		(layer "F.Cu")
		(net 11)
	)
	(segment
		(start 151.65 97.2)
		(end 151.2 97.2)
		(width 0.2)
		(layer "F.Cu")
		(net 11)
	)
	(segment
		(start 152.724 113.749)
		(end 152.724 114.564)
		(width 0.2)
		(layer "F.Cu")
		(net 11)
	)
	(segment
		(start 142.4 108.803001)
		(end 142.226999 108.63)
		(width 0.1)
		(layer "F.Cu")
		(net 11)
	)
	(segment
		(start 147.9 122.7)
		(end 146.6 122.7)
		(width 0.5)
		(layer "F.Cu")
		(net 11)
	)
	(segment
		(start 154.1 120.8)
		(end 154.5 121.2)
		(width 0.1)
		(layer "F.Cu")
		(net 11)
	)
	(via
		(at 197.9 55.9)
		(size 0.45)
		(drill 0.1)
		(layers "F.Cu" "B.Cu")
		(net 11)
	)
	(via
		(at 154.4 110.2)
		(size 0.45)
		(drill 0.1)
		(layers "F.Cu" "B.Cu")
		(net 11)
	)
	(via
		(at 147.9 122.7)
		(size 0.45)
		(drill 0.1)
		(layers "F.Cu" "B.Cu")
		(remove_unused_layers yes)
		(keep_end_layers yes)
		(zone_layer_connections "In4.Cu")
		(net 11)
	)
	(via
		(at 79.9 134.3)
		(size 0.45)
		(drill 0.1)
		(layers "F.Cu" "B.Cu")
		(net 11)
	)
	(via
		(at 203.5 74)
		(size 0.45)
		(drill 0.1)
		(layers "F.Cu" "B.Cu")
		(net 11)
	)
	(via
		(at 142.4 109.8)
		(size 0.45)
		(drill 0.1)
		(layers "F.Cu" "B.Cu")
		(net 11)
	)
	(via
		(at 147.25 123.45)
		(size 0.45)
		(drill 0.1)
		(layers "F.Cu" "B.Cu")
		(remove_unused_layers yes)
		(keep_end_layers yes)
		(zone_layer_connections "In4.Cu")
		(net 11)
	)
	(via
		(at 147.8 113.8)
		(size 0.45)
		(drill 0.1)
		(layers "F.Cu" "B.Cu")
		(net 11)
	)
	(via
		(at 150.8 110.2)
		(size 0.45)
		(drill 0.1)
		(layers "F.Cu" "B.Cu")
		(net 11)
	)
	(via
		(at 82.6 66.6)
		(size 0.45)
		(drill 0.1)
		(layers "F.Cu" "B.Cu")
		(net 11)
	)
	(via
		(at 150.6 100.6)
		(size 0.45)
		(drill 0.1)
		(layers "F.Cu" "B.Cu")
		(net 11)
	)
	(via
		(at 79.9 133.7)
		(size 0.45)
		(drill 0.1)
		(layers "F.Cu" "B.Cu")
		(net 11)
	)
	(via
		(at 79.3 134.3)
		(size 0.45)
		(drill 0.1)
		(layers "F.Cu" "B.Cu")
		(net 11)
	)
	(via
		(at 187.25 58.5)
		(size 0.45)
		(drill 0.1)
		(layers "F.Cu" "B.Cu")
		(net 11)
	)
	(via
		(at 148.3 76.7)
		(size 0.45)
		(drill 0.1)
		(layers "F.Cu" "B.Cu")
		(net 11)
	)
	(via
		(at 82.25 59.25)
		(size 0.45)
		(drill 0.1)
		(layers "F.Cu" "B.Cu")
		(net 11)
	)
	(via
		(at 147.9 123.45)
		(size 0.45)
		(drill 0.1)
		(layers "F.Cu" "B.Cu")
		(remove_unused_layers yes)
		(keep_end_layers yes)
		(zone_layer_connections "In4.Cu")
		(net 11)
	)
	(via
		(at 60.6 64.2)
		(size 0.45)
		(drill 0.1)
		(layers "F.Cu" "B.Cu")
		(net 11)
	)
	(via
		(at 158.5 61.5)
		(size 0.45)
		(drill 0.1)
		(layers "F.Cu" "B.Cu")
		(net 11)
	)
	(via
		(at 159.75 65)
		(size 0.45)
		(drill 0.1)
		(layers "F.Cu" "B.Cu")
		(net 11)
	)
	(via
		(at 150 116.1)
		(size 0.45)
		(drill 0.1)
		(layers "F.Cu" "B.Cu")
		(net 11)
	)
	(via
		(at 162.7 62.3)
		(size 0.45)
		(drill 0.1)
		(layers "F.Cu" "B.Cu")
		(net 11)
	)
	(via
		(at 219.9 94.7)
		(size 0.45)
		(drill 0.1)
		(layers "F.Cu" "B.Cu")
		(net 11)
	)
	(via
		(at 154.4 102.6)
		(size 0.45)
		(drill 0.1)
		(layers "F.Cu" "B.Cu")
		(net 11)
	)
	(via
		(at 96.95 64.4)
		(size 0.45)
		(drill 0.1)
		(layers "F.Cu" "B.Cu")
		(net 11)
	)
	(via
		(at 152 95.3)
		(size 0.45)
		(drill 0.1)
		(layers "F.Cu" "B.Cu")
		(net 11)
	)
	(via
		(at 147.25 124)
		(size 0.45)
		(drill 0.1)
		(layers "F.Cu" "B.Cu")
		(net 11)
	)
	(via
		(at 153 107.3)
		(size 0.45)
		(drill 0.1)
		(layers "F.Cu" "B.Cu")
		(net 11)
	)
	(via
		(at 148.3 72)
		(size 0.45)
		(drill 0.1)
		(layers "F.Cu" "B.Cu")
		(net 11)
	)
	(via
		(at 79.9 133.1)
		(size 0.45)
		(drill 0.1)
		(layers "F.Cu" "B.Cu")
		(net 11)
	)
	(via
		(at 146.6 122.7)
		(size 0.45)
		(drill 0.1)
		(layers "F.Cu" "B.Cu")
		(remove_unused_layers yes)
		(keep_end_layers yes)
		(zone_layer_connections "In4.Cu")
		(net 11)
	)
	(via
		(at 146.6 123.45)
		(size 0.45)
		(drill 0.1)
		(layers "F.Cu" "B.Cu")
		(remove_unused_layers yes)
		(keep_end_layers yes)
		(zone_layer_connections "In4.Cu")
		(net 11)
	)
	(via
		(at 153.8 114.8)
		(size 0.45)
		(drill 0.1)
		(layers "F.Cu" "B.Cu")
		(net 11)
	)
	(via
		(at 147.25 122.7)
		(size 0.45)
		(drill 0.1)
		(layers "F.Cu" "B.Cu")
		(remove_unused_layers yes)
		(keep_end_layers yes)
		(zone_layer_connections "In4.Cu")
		(net 11)
	)
	(via
		(at 70.5 96.1)
		(size 0.45)
		(drill 0.1)
		(layers "F.Cu" "B.Cu")
		(net 11)
	)
	(via
		(at 144.9 135.9)
		(size 0.45)
		(drill 0.1)
		(layers "F.Cu" "B.Cu")
		(net 11)
	)
	(via
		(at 159.3 70.4)
		(size 0.45)
		(drill 0.1)
		(layers "F.Cu" "B.Cu")
		(net 11)
	)
	(via
		(at 79.3 133.7)
		(size 0.45)
		(drill 0.1)
		(layers "F.Cu" "B.Cu")
		(net 11)
	)
	(via
		(at 79.3 133.1)
		(size 0.45)
		(drill 0.1)
		(layers "F.Cu" "B.Cu")
		(net 11)
	)
	(via
		(at 75.35 76.35)
		(size 0.45)
		(drill 0.1)
		(layers "F.Cu" "B.Cu")
		(net 11)
	)
	(via
		(at 199 68.8)
		(size 0.45)
		(drill 0.1)
		(layers "F.Cu" "B.Cu")
		(net 11)
	)
	(via
		(at 157.85 144.95)
		(size 0.45)
		(drill 0.1)
		(layers "F.Cu" "B.Cu")
		(net 11)
	)
	(via
		(at 62.8 61.6)
		(size 0.45)
		(drill 0.1)
		(layers "F.Cu" "B.Cu")
		(net 11)
	)
	(via
		(at 165.25 57)
		(size 0.45)
		(drill 0.1)
		(layers "F.Cu" "B.Cu")
		(net 11)
	)
	(via
		(at 156.5 116.7)
		(size 0.45)
		(drill 0.1)
		(layers "F.Cu" "B.Cu")
		(net 11)
	)
	(segment
		(start 219.9 94.7)
		(end 218.5 94.7)
		(width 0.1)
		(layer "B.Cu")
		(net 11)
	)
	(segment
		(start 143.8 71.22)
		(end 144.17 71.22)
		(width 0.1)
		(layer "B.Cu")
		(net 11)
	)
	(segment
		(start 199.15 67.25)
		(end 198.93 67.47)
		(width 0.2)
		(layer "B.Cu")
		(net 11)
	)
	(segment
		(start 198.93 67.47)
		(end 198.93 68.02)
		(width 0.2)
		(layer "B.Cu")
		(net 11)
	)
	(segment
		(start 159.82 69.79)
		(end 159.82 69.88)
		(width 0.5)
		(layer "B.Cu")
		(net 11)
	)
	(segment
		(start 152.75 94.55)
		(end 152.75 83.6)
		(width 0.5)
		(layer "B.Cu")
		(net 11)
	)
	(segment
		(start 165.25 55.95)
		(end 165.72 55.48)
		(width 0.1)
		(layer "B.Cu")
		(net 11)
	)
	(segment
		(start 217.932132 95.392)
		(end 217.932132 95.267868)
		(width 0.1)
		(layer "B.Cu")
		(net 11)
	)
	(segment
		(start 152.75 81.15)
		(end 148.3 76.7)
		(width 0.5)
		(layer "B.Cu")
		(net 11)
	)
	(segment
		(start 205.176 149.05)
		(end 210.576 149.05)
		(width 0.3)
		(layer "B.Cu")
		(net 11)
	)
	(segment
		(start 165.72 55.48)
		(end 169.62 55.48)
		(width 0.1)
		(layer "B.Cu")
		(net 11)
	)
	(segment
		(start 154.8 70.4)
		(end 159.3 70.4)
		(width 0.5)
		(layer "B.Cu")
		(net 11)
	)
	(segment
		(start 204.376 148.25)
		(end 205.176 149.05)
		(width 0.3)
		(layer "B.Cu")
		(net 11)
	)
	(segment
		(start 144.55 71.6)
		(end 144.55 72.6)
		(width 0.1)
		(layer "B.Cu")
		(net 11)
	)
	(segment
		(start 210.926 144.65)
		(end 210.276 144)
		(width 0.3)
		(layer "B.Cu")
		(net 11)
	)
	(segment
		(start 160.086 65.336)
		(end 159.75 65)
		(width 0.1)
		(layer "B.Cu")
		(net 11)
	)
	(segment
		(start 148.3 76.35)
		(end 148.3 76.7)
		(width 0.1)
		(layer "B.Cu")
		(net 11)
	)
	(segment
		(start 152 95.3)
		(end 152.75 94.55)
		(width 0.5)
		(layer "B.Cu")
		(net 11)
	)
	(segment
		(start 153.2 72)
		(end 154.8 70.4)
		(width 0.5)
		(layer "B.Cu")
		(net 11)
	)
	(segment
		(start 153 81.45)
		(end 152.75 81.2)
		(width 0.5)
		(layer "B.Cu")
		(net 11)
	)
	(segment
		(start 149.9 135.9)
		(end 157.85 143.85)
		(width 0.3)
		(layer "B.Cu")
		(net 11)
	)
	(segment
		(start 159.82 69.88)
		(end 159.3 70.4)
		(width 0.5)
		(layer "B.Cu")
		(net 11)
	)
	(segment
		(start 162.68 62.32)
		(end 162.7 62.3)
		(width 0.1)
		(layer "B.Cu")
		(net 11)
	)
	(segment
		(start 152.75 81.2)
		(end 152.75 81.15)
		(width 0.5)
		(layer "B.Cu")
		(net 11)
	)
	(segment
		(start 65 62.6)
		(end 65 63.1)
		(width 0.2)
		(layer "B.Cu")
		(net 11)
	)
	(segment
		(start 148.3 72)
		(end 153.2 72)
		(width 0.5)
		(layer "B.Cu")
		(net 11)
	)
	(segment
		(start 160.086 69.524)
		(end 159.82 69.79)
		(width 0.3)
		(layer "B.Cu")
		(net 11)
	)
	(segment
		(start 161.92 62.32)
		(end 162.68 62.32)
		(width 0.1)
		(layer "B.Cu")
		(net 11)
	)
	(segment
		(start 210.576 149.05)
		(end 210.926 148.7)
		(width 0.3)
		(layer "B.Cu")
		(net 11)
	)
	(segment
		(start 160.086 68.739)
		(end 160.086 69.524)
		(width 0.3)
		(layer "B.Cu")
		(net 11)
	)
	(segment
		(start 219.88 94.72)
		(end 219.9 94.7)
		(width 0.1)
		(layer "B.Cu")
		(net 11)
	)
	(segment
		(start 199.15 65.95)
		(end 199.15 66.85)
		(width 0.2)
		(layer "B.Cu")
		(net 11)
	)
	(segment
		(start 219.88 95.4)
		(end 219.88 94.72)
		(width 0.1)
		(layer "B.Cu")
		(net 11)
	)
	(segment
		(start 170.735 60.3)
		(end 170.805 60.23)
		(width 0.1)
		(layer "B.Cu")
		(net 11)
	)
	(segment
		(start 65 62.6)
		(end 64 61.6)
		(width 0.2)
		(layer "B.Cu")
		(net 11)
	)
	(segment
		(start 198.93 68.73)
		(end 199 68.8)
		(width 0.2)
		(layer "B.Cu")
		(net 11)
	)
	(segment
		(start 199.15 66.85)
		(end 199.15 67.25)
		(width 0.2)
		(layer "B.Cu")
		(net 11)
	)
	(segment
		(start 198.676 150.95)
		(end 201.376 148.25)
		(width 0.3)
		(layer "B.Cu")
		(net 11)
	)
	(segment
		(start 169.65 58.94)
		(end 169.65 60.3)
		(width 0.1)
		(layer "B.Cu")
		(net 11)
	)
	(segment
		(start 144.55 72.6)
		(end 148.3 76.35)
		(width 0.1)
		(layer "B.Cu")
		(net 11)
	)
	(segment
		(start 142.8 71.22)
		(end 143.8 71.22)
		(width 0.1)
		(layer "B.Cu")
		(net 11)
	)
	(segment
		(start 164.6 148.4)
		(end 167.15 150.95)
		(width 0.3)
		(layer "B.Cu")
		(net 11)
	)
	(segment
		(start 169.65 60.3)
		(end 170.735 60.3)
		(width 0.1)
		(layer "B.Cu")
		(net 11)
	)
	(segment
		(start 144.17 71.22)
		(end 144.55 71.6)
		(width 0.1)
		(layer "B.Cu")
		(net 11)
	)
	(segment
		(start 169.62 55.48)
		(end 170.18 56.04)
		(width 0.1)
		(layer "B.Cu")
		(net 11)
	)
	(segment
		(start 167.15 150.95)
		(end 198.676 150.95)
		(width 0.3)
		(layer "B.Cu")
		(net 11)
	)
	(segment
		(start 210.276 144)
		(end 209.206 144)
		(width 0.3)
		(layer "B.Cu")
		(net 11)
	)
	(segment
		(start 210.926 148.7)
		(end 210.926 144.65)
		(width 0.3)
		(layer "B.Cu")
		(net 11)
	)
	(segment
		(start 158.51 62.29)
		(end 158.51 61.51)
		(width 0.1)
		(layer "B.Cu")
		(net 11)
	)
	(segment
		(start 153 83.35)
		(end 153 81.45)
		(width 0.5)
		(layer "B.Cu")
		(net 11)
	)
	(segment
		(start 170.18 58.41)
		(end 169.65 58.94)
		(width 0.1)
		(layer "B.Cu")
		(net 11)
	)
	(segment
		(start 161.3 148.4)
		(end 164.6 148.4)
		(width 0.3)
		(layer "B.Cu")
		(net 11)
	)
	(segment
		(start 157.85 144.95)
		(end 157.85 143.85)
		(width 0.3)
		(layer "B.Cu")
		(net 11)
	)
	(segment
		(start 152.75 83.6)
		(end 153 83.35)
		(width 0.5)
		(layer "B.Cu")
		(net 11)
	)
	(segment
		(start 65 63.1)
		(end 66.15 63.1)
		(width 0.2)
		(layer "B.Cu")
		(net 11)
	)
	(segment
		(start 217.932132 95.267868)
		(end 218.5 94.7)
		(width 0.1)
		(layer "B.Cu")
		(net 11)
	)
	(segment
		(start 201.376 148.25)
		(end 204.376 148.25)
		(width 0.3)
		(layer "B.Cu")
		(net 11)
	)
	(segment
		(start 165.25 57)
		(end 165.25 55.95)
		(width 0.1)
		(layer "B.Cu")
		(net 11)
	)
	(segment
		(start 170.18 56.04)
		(end 170.18 58.41)
		(width 0.1)
		(layer "B.Cu")
		(net 11)
	)
	(segment
		(start 157.85 144.95)
		(end 161.3 148.4)
		(width 0.3)
		(layer "B.Cu")
		(net 11)
	)
	(segment
		(start 160.086 65.74)
		(end 160.086 65.336)
		(width 0.1)
		(layer "B.Cu")
		(net 11)
	)
	(segment
		(start 198.93 68.02)
		(end 198.93 68.73)
		(width 0.2)
		(layer "B.Cu")
		(net 11)
	)
	(segment
		(start 158.51 61.51)
		(end 158.5 61.5)
		(width 0.1)
		(layer "B.Cu")
		(net 11)
	)
	(segment
		(start 149.9 135.9)
		(end 144.9 135.9)
		(width 0.3)
		(layer "B.Cu")
		(net 11)
	)
	(segment
		(start 64 61.6)
		(end 62.8 61.6)
		(width 0.2)
		(layer "B.Cu")
		(net 11)
	)
	(segment
		(start 205.3 84.7)
		(end 203.5 82.9)
		(width 0.2)
		(layer "In4.Cu")
		(net 11)
	)
	(segment
		(start 219.9 91.6)
		(end 221.1 90.4)
		(width 0.2)
		(layer "In4.Cu")
		(net 11)
	)
	(segment
		(start 205.3 85)
		(end 205.3 84.7)
		(width 0.2)
		(layer "In4.Cu")
		(net 11)
	)
	(segment
		(start 203.5 82.9)
		(end 203.5 74)
		(width 0.2)
		(layer "In4.Cu")
		(net 11)
	)
	(segment
		(start 221.1 90.4)
		(end 221.1 88.7)
		(width 0.2)
		(layer "In4.Cu")
		(net 11)
	)
	(segment
		(start 207.3 87)
		(end 205.3 85)
		(width 0.2)
		(layer "In4.Cu")
		(net 11)
	)
	(segment
		(start 219.4 87)
		(end 221.1 88.7)
		(width 0.2)
		(layer "In4.Cu")
		(net 11)
	)
	(segment
		(start 219.4 87)
		(end 207.3 87)
		(width 0.2)
		(layer "In4.Cu")
		(net 11)
	)
	(segment
		(start 219.9 94.7)
		(end 219.9 91.6)
		(width 0.2)
		(layer "In4.Cu")
		(net 11)
	)
	(segment
		(start 165.25 57)
		(end 185.75 57)
		(width 0.2)
		(layer "In5.Cu")
		(net 11)
	)
	(segment
		(start 191.1 58.5)
		(end 194 55.6)
		(width 0.2)
		(layer "In5.Cu")
		(net 11)
	)
	(segment
		(start 83.6 65.2)
		(end 83.6 65.6)
		(width 0.1)
		(layer "In5.Cu")
		(net 11)
	)
	(segment
		(start 197.6 55.6)
		(end 197.9 55.9)
		(width 0.2)
		(layer "In5.Cu")
		(net 11)
	)
	(segment
		(start 159.3 70.4)
		(end 159.3 65.45)
		(width 0.2)
		(layer "In5.Cu")
		(net 11)
	)
	(segment
		(start 159.3 65.45)
		(end 159.75 65)
		(width 0.2)
		(layer "In5.Cu")
		(net 11)
	)
	(segment
		(start 203.5 72.2)
		(end 199.9 68.6)
		(width 0.2)
		(layer "In5.Cu")
		(net 11)
	)
	(segment
		(start 82.25 59.25)
		(end 83.6 60.6)
		(width 0.1)
		(layer "In5.Cu")
		(net 11)
	)
	(segment
		(start 159.3 70.4)
		(end 159.3 65.449999)
		(width 0.5)
		(layer "In5.Cu")
		(net 11)
	)
	(segment
		(start 159.3 65.449999)
		(end 159.718413 65.031586)
		(width 0.5)
		(layer "In5.Cu")
		(net 11)
	)
	(segment
		(start 194 55.6)
		(end 197.6 55.6)
		(width 0.2)
		(layer "In5.Cu")
		(net 11)
	)
	(segment
		(start 83.6 65.2)
		(end 83.6 65.39)
		(width 0.1)
		(layer "In5.Cu")
		(net 11)
	)
	(segment
		(start 199.2 68.6)
		(end 199 68.8)
		(width 0.2)
		(layer "In5.Cu")
		(net 11)
	)
	(segment
		(start 83.6 60.6)
		(end 83.6 65.2)
		(width 0.1)
		(layer "In5.Cu")
		(net 11)
	)
	(segment
		(start 94.55 65.39)
		(end 95.54 64.4)
		(width 0.1)
		(layer "In5.Cu")
		(net 11)
	)
	(segment
		(start 199.9 68.6)
		(end 199.2 68.6)
		(width 0.2)
		(layer "In5.Cu")
		(net 11)
	)
	(segment
		(start 187.25 58.5)
		(end 191.1 58.5)
		(width 0.2)
		(layer "In5.Cu")
		(net 11)
	)
	(segment
		(start 203.5 74)
		(end 203.5 72.2)
		(width 0.2)
		(layer "In5.Cu")
		(net 11)
	)
	(segment
		(start 83.6 65.39)
		(end 94.55 65.39)
		(width 0.1)
		(layer "In5.Cu")
		(net 11)
	)
	(segment
		(start 95.54 64.4)
		(end 96.95 64.4)
		(width 0.1)
		(layer "In5.Cu")
		(net 11)
	)
	(segment
		(start 185.75 57)
		(end 187.25 58.5)
		(width 0.2)
		(layer "In5.Cu")
		(net 11)
	)
	(segment
		(start 83.6 65.6)
		(end 82.6 66.6)
		(width 0.1)
		(layer "In5.Cu")
		(net 11)
	)
	(segment
		(start 158.5 61.5)
		(end 158.5 63.813173)
		(width 0.5)
		(layer "In7.Cu")
		(net 11)
	)
	(segment
		(start 199 63.9)
		(end 199 68.8)
		(width 0.2)
		(layer "In7.Cu")
		(net 11)
	)
	(segment
		(start 198.3 63.2)
		(end 199 63.9)
		(width 0.2)
		(layer "In7.Cu")
		(net 11)
	)
	(segment
		(start 158.5 63.813173)
		(end 159.718413 65.031586)
		(width 0.5)
		(layer "In7.Cu")
		(net 11)
	)
	(segment
		(start 197.9 55.9)
		(end 197.9 58.5)
		(width 0.2)
		(layer "In7.Cu")
		(net 11)
	)
	(segment
		(start 160.1 62.3)
		(end 162.7 62.3)
		(width 0.5)
		(layer "In7.Cu")
		(net 11)
	)
	(segment
		(start 197.9 58.5)
		(end 198.3 58.9)
		(width 0.2)
		(layer "In7.Cu")
		(net 11)
	)
	(segment
		(start 159.3 61.5)
		(end 160.1 62.3)
		(width 0.5)
		(layer "In7.Cu")
		(net 11)
	)
	(segment
		(start 198.3 58.9)
		(end 198.3 63.2)
		(width 0.2)
		(layer "In7.Cu")
		(net 11)
	)
	(segment
		(start 158.5 61.5)
		(end 159.3 61.5)
		(width 0.5)
		(layer "In7.Cu")
		(net 11)
	)
	(segment
		(start 151 89.5)
		(end 151 86.919468)
		(width 0.5)
		(layer "F.Cu")
		(net 12)
	)
	(segment
		(start 161.734468 97.665)
		(end 161.935 97.665)
		(width 0.1)
		(layer "F.Cu")
		(net 12)
	)
	(segment
		(start 87 80.425)
		(end 87 80.35)
		(width 0.3)
		(layer "F.Cu")
		(net 12)
	)
	(segment
		(start 162.7 96.9)
		(end 162.7 96.4)
		(width 0.1)
		(layer "F.Cu")
		(net 12)
	)
	(segment
		(start 87 80.35)
		(end 87.230532 80.119468)
		(width 0.3)
		(layer "F.Cu")
		(net 12)
	)
	(segment
		(start 144.930532 76.65)
		(end 144.95 76.65)
		(width 0.1)
		(layer "F.Cu")
		(net 12)
	)
	(segment
		(start 86.530532 81.15)
		(end 86.530532 80.730532)
		(width 0.3)
		(layer "F.Cu")
		(net 12)
	)
	(segment
		(start 146.930532 81.119468)
		(end 146.95 81.1)
		(width 0.1)
		(layer "F.Cu")
		(net 12)
	)
	(segment
		(start 162.7 96.4)
		(end 162.525 96.225)
		(width 0.1)
		(layer "F.Cu")
		(net 12)
	)
	(segment
		(start 86.5 80.7)
		(end 86.5 79.819468)
		(width 0.3)
		(layer "F.Cu")
		(net 12)
	)
	(segment
		(start 86.5 79.819468)
		(end 86.330532 79.65)
		(width 0.3)
		(layer "F.Cu")
		(net 12)
	)
	(segment
		(start 149.5 91)
		(end 151 89.5)
		(width 0.5)
		(layer "F.Cu")
		(net 12)
	)
	(segment
		(start 86.530532 80.730532)
		(end 86.5 80.7)
		(width 0.3)
		(layer "F.Cu")
		(net 12)
	)
	(segment
		(start 146.930532 81.15)
		(end 146.930532 81.119468)
		(width 0.1)
		(layer "F.Cu")
		(net 12)
	)
	(segment
		(start 87.230532 80.119468)
		(end 87.230532 79.65)
		(width 0.3)
		(layer "F.Cu")
		(net 12)
	)
	(segment
		(start 151 86.919468)
		(end 146.730532 82.65)
		(width 0.5)
		(layer "F.Cu")
		(net 12)
	)
	(segment
		(start 179.75 57.19)
		(end 179.75 58)
		(width 0.1)
		(layer "F.Cu")
		(net 12)
	)
	(segment
		(start 162.525 96.225)
		(end 161.844468 96.225)
		(width 0.1)
		(layer "F.Cu")
		(net 12)
	)
	(segment
		(start 148.599999 91)
		(end 149.5 91)
		(width 0.5)
		(layer "F.Cu")
		(net 12)
	)
	(segment
		(start 161.935 97.665)
		(end 162.7 96.9)
		(width 0.1)
		(layer "F.Cu")
		(net 12)
	)
	(via
		(at 160.75 96.6)
		(size 0.45)
		(drill 0.1)
		(layers "F.Cu" "B.Cu")
		(remove_unused_layers yes)
		(keep_end_layers yes)
		(free yes)
		(zone_layer_connections "In4.Cu")
		(net 12)
	)
	(via
		(at 88.33 75.15)
		(size 0.45)
		(drill 0.1)
		(layers "F.Cu" "B.Cu")
		(net 12)
	)
	(via
		(at 159.6 96)
		(size 0.45)
		(drill 0.1)
		(layers "F.Cu" "B.Cu")
		(remove_unused_layers yes)
		(keep_end_layers yes)
		(free yes)
		(zone_layer_connections "In4.Cu")
		(net 12)
	)
	(via
		(at 86.52 75.15)
		(size 0.45)
		(drill 0.1)
		(layers "F.Cu" "B.Cu")
		(net 12)
	)
	(via
		(at 159 97.2)
		(size 0.45)
		(drill 0.1)
		(layers "F.Cu" "B.Cu")
		(remove_unused_layers yes)
		(keep_end_layers yes)
		(free yes)
		(zone_layer_connections "In4.Cu")
		(net 12)
	)
	(via
		(at 159.6 96.6)
		(size 0.45)
		(drill 0.1)
		(layers "F.Cu" "B.Cu")
		(remove_unused_layers yes)
		(keep_end_layers yes)
		(free yes)
		(zone_layer_connections "In4.Cu")
		(net 12)
	)
	(via
		(at 159 96)
		(size 0.45)
		(drill 0.1)
		(layers "F.Cu" "B.Cu")
		(remove_unused_layers yes)
		(keep_end_layers yes)
		(free yes)
		(zone_layer_connections "In4.Cu")
		(net 12)
	)
	(via
		(at 160.75 95.4)
		(size 0.45)
		(drill 0.1)
		(layers "F.Cu" "B.Cu")
		(remove_unused_layers yes)
		(keep_end_layers yes)
		(free yes)
		(zone_layer_connections "In4.Cu")
		(net 12)
	)
	(via
		(at 86.53 78.16)
		(size 0.45)
		(drill 0.1)
		(layers "F.Cu" "B.Cu")
		(net 12)
	)
	(via
		(at 179.75 58)
		(size 0.45)
		(drill 0.1)
		(layers "F.Cu" "B.Cu")
		(net 12)
	)
	(via
		(at 160.75 96)
		(size 0.45)
		(drill 0.1)
		(layers "F.Cu" "B.Cu")
		(remove_unused_layers yes)
		(keep_end_layers yes)
		(free yes)
		(zone_layer_connections "In4.Cu")
		(net 12)
	)
	(via
		(at 87.44 78.15)
		(size 0.45)
		(drill 0.1)
		(layers "F.Cu" "B.Cu")
		(net 12)
	)
	(via
		(at 87.23 73.64)
		(size 0.45)
		(drill 0.1)
		(layers "F.Cu" "B.Cu")
		(net 12)
	)
	(via
		(at 87 80.425)
		(size 0.45)
		(drill 0.1)
		(layers "F.Cu" "B.Cu")
		(net 12)
	)
	(via
		(at 144.95 76.65)
		(size 0.45)
		(drill 0.1)
		(layers "F.Cu" "B.Cu")
		(net 12)
	)
	(via
		(at 88.7 81.85)
		(size 0.45)
		(drill 0.1)
		(layers "F.Cu" "B.Cu")
		(net 12)
	)
	(via
		(at 85.3 82.1)
		(size 0.45)
		(drill 0.1)
		(layers "F.Cu" "B.Cu")
		(net 12)
	)
	(via
		(at 86.33 76.65)
		(size 0.45)
		(drill 0.1)
		(layers "F.Cu" "B.Cu")
		(net 12)
	)
	(via
		(at 88.33 78.15)
		(size 0.45)
		(drill 0.1)
		(layers "F.Cu" "B.Cu")
		(net 12)
	)
	(via
		(at 160.15 97.2)
		(size 0.45)
		(drill 0.1)
		(layers "F.Cu" "B.Cu")
		(remove_unused_layers yes)
		(keep_end_layers yes)
		(free yes)
		(zone_layer_connections "In4.Cu")
		(net 12)
	)
	(via
		(at 87.42 75.15)
		(size 0.45)
		(drill 0.1)
		(layers "F.Cu" "B.Cu")
		(net 12)
	)
	(via
		(at 87.44 81.14)
		(size 0.45)
		(drill 0.1)
		(layers "F.Cu" "B.Cu")
		(net 12)
	)
	(via
		(at 86.33 73.65)
		(size 0.45)
		(drill 0.1)
		(layers "F.Cu" "B.Cu")
		(net 12)
	)
	(via
		(at 160.15 95.4)
		(size 0.45)
		(drill 0.1)
		(layers "F.Cu" "B.Cu")
		(remove_unused_layers yes)
		(keep_end_layers yes)
		(free yes)
		(zone_layer_connections "In4.Cu")
		(net 12)
	)
	(via
		(at 146.95 81.1)
		(size 0.45)
		(drill 0.1)
		(layers "F.Cu" "B.Cu")
		(net 12)
	)
	(via
		(at 153.6 73.6)
		(size 0.45)
		(drill 0.1)
		(layers "F.Cu" "B.Cu")
		(net 12)
	)
	(via
		(at 160.15 96.6)
		(size 0.45)
		(drill 0.1)
		(layers "F.Cu" "B.Cu")
		(remove_unused_layers yes)
		(keep_end_layers yes)
		(free yes)
		(zone_layer_connections "In4.Cu")
		(net 12)
	)
	(via
		(at 85.3 80.8)
		(size 0.45)
		(drill 0.1)
		(layers "F.Cu" "B.Cu")
		(net 12)
	)
	(via
		(at 159 96.6)
		(size 0.45)
		(drill 0.1)
		(layers "F.Cu" "B.Cu")
		(remove_unused_layers yes)
		(keep_end_layers yes)
		(free yes)
		(zone_layer_connections "In4.Cu")
		(net 12)
	)
	(via
		(at 87.23 79.64)
		(size 0.45)
		(drill 0.1)
		(layers "F.Cu" "B.Cu")
		(net 12)
	)
	(via
		(at 88.33 72.15)
		(size 0.45)
		(drill 0.1)
		(layers "F.Cu" "B.Cu")
		(net 12)
	)
	(via
		(at 159 95.4)
		(size 0.45)
		(drill 0.1)
		(layers "F.Cu" "B.Cu")
		(remove_unused_layers yes)
		(keep_end_layers yes)
		(free yes)
		(zone_layer_connections "In4.Cu")
		(net 12)
	)
	(via
		(at 159.6 95.4)
		(size 0.45)
		(drill 0.1)
		(layers "F.Cu" "B.Cu")
		(remove_unused_layers yes)
		(keep_end_layers yes)
		(free yes)
		(zone_layer_connections "In4.Cu")
		(net 12)
	)
	(via
		(at 160.75 97.2)
		(size 0.45)
		(drill 0.1)
		(layers "F.Cu" "B.Cu")
		(remove_unused_layers yes)
		(keep_end_layers yes)
		(free yes)
		(zone_layer_connections "In4.Cu")
		(net 12)
	)
	(via
		(at 87 82)
		(size 0.45)
		(drill 0.1)
		(layers "F.Cu" "B.Cu")
		(net 12)
	)
	(via
		(at 159.6 97.2)
		(size 0.45)
		(drill 0.1)
		(layers "F.Cu" "B.Cu")
		(remove_unused_layers yes)
		(keep_end_layers yes)
		(free yes)
		(zone_layer_connections "In4.Cu")
		(net 12)
	)
	(via
		(at 87.24 76.65)
		(size 0.45)
		(drill 0.1)
		(layers "F.Cu" "B.Cu")
		(net 12)
	)
	(via
		(at 160.15 96)
		(size 0.45)
		(drill 0.1)
		(layers "F.Cu" "B.Cu")
		(remove_unused_layers yes)
		(keep_end_layers yes)
		(free yes)
		(zone_layer_connections "In4.Cu")
		(net 12)
	)
	(segment
		(start 144.95 76.48)
		(end 145.1 76.33)
		(width 0.2)
		(layer "B.Cu")
		(net 12)
	)
	(segment
		(start 177.49 69.51)
		(end 178.7 68.3)
		(width 0.1)
		(layer "B.Cu")
		(net 12)
	)
	(segment
		(start 153.6 73.6)
		(end 154 73.6)
		(width 0.1)
		(layer "B.Cu")
		(net 12)
	)
	(segment
		(start 89.8 74.32)
		(end 88.68 74.32)
		(width 0.2)
		(layer "B.Cu")
		(net 12)
	)
	(segment
		(start 88.33 74.67)
		(end 88.33 75.15)
		(width 0.2)
		(layer "B.Cu")
		(net 12)
	)
	(segment
		(start 88.9 78.8)
		(end 88.33 78.23)
		(width 0.2)
		(layer "B.Cu")
		(net 12)
	)
	(segment
		(start 146.18 81.2)
		(end 146.85 81.2)
		(width 0.2)
		(layer "B.Cu")
		(net 12)
	)
	(segment
		(start 144.95 76.65)
		(end 144.95 76.48)
		(width 0.2)
		(layer "B.Cu")
		(net 12)
	)
	(segment
		(start 93.2 67.8)
		(end 93.5 67.5)
		(width 0.2)
		(layer "B.Cu")
		(net 12)
	)
	(segment
		(start 89.32 78.8)
		(end 88.9 78.8)
		(width 0.2)
		(layer "B.Cu")
		(net 12)
	)
	(segment
		(start 169.49 69.51)
		(end 177.49 69.51)
		(width 0.1)
		(layer "B.Cu")
		(net 12)
	)
	(segment
		(start 155.8 71.8)
		(end 167.2 71.8)
		(width 0.1)
		(layer "B.Cu")
		(net 12)
	)
	(segment
		(start 154 73.6)
		(end 155.8 71.8)
		(width 0.1)
		(layer "B.Cu")
		(net 12)
	)
	(segment
		(start 146.85 81.2)
		(end 146.95 81.1)
		(width 0.2)
		(layer "B.Cu")
		(net 12)
	)
	(segment
		(start 179.75 64.35)
		(end 179.75 57.98)
		(width 0.1)
		(layer "B.Cu")
		(net 12)
	)
	(segment
		(start 167.2 71.8)
		(end 169.49 69.51)
		(width 0.1)
		(layer "B.Cu")
		(net 12)
	)
	(segment
		(start 181.9 66.5)
		(end 179.75 64.35)
		(width 0.1)
		(layer "B.Cu")
		(net 12)
	)
	(segment
		(start 88.68 74.32)
		(end 88.33 74.67)
		(width 0.2)
		(layer "B.Cu")
		(net 12)
	)
	(segment
		(start 93.5 67.5)
		(end 93.5 66.099)
		(width 0.2)
		(layer "B.Cu")
		(net 12)
	)
	(segment
		(start 89.9 79.38)
		(end 89.32 78.8)
		(width 0.2)
		(layer "B.Cu")
		(net 12)
	)
	(segment
		(start 181.9 67.9)
		(end 181.9 66.5)
		(width 0.1)
		(layer "B.Cu")
		(net 12)
	)
	(segment
		(start 88.33 78.23)
		(end 88.33 78.15)
		(width 0.2)
		(layer "B.Cu")
		(net 12)
	)
	(segment
		(start 181.5 68.3)
		(end 181.9 67.9)
		(width 0.1)
		(layer "B.Cu")
		(net 12)
	)
	(segment
		(start 178.7 68.3)
		(end 181.5 68.3)
		(width 0.1)
		(layer "B.Cu")
		(net 12)
	)
	(segment
		(start 180.89 58)
		(end 179.75 58)
		(width 0.1)
		(layer "B.Cu")
		(net 12)
	)
	(segment
		(start 92.68 67.8)
		(end 93.2 67.8)
		(width 0.2)
		(layer "B.Cu")
		(net 12)
	)
	(segment
		(start 88.33 72.15)
		(end 92.68 67.8)
		(width 0.2)
		(layer "B.Cu")
		(net 12)
	)
	(segment
		(start 179.125 88.51)
		(end 179.125 89.1)
		(width 0.15)
		(layer "F.Cu")
		(net 13)
	)
	(segment
		(start 183.75 122.25)
		(end 178.75 122.25)
		(width 1)
		(layer "F.Cu")
		(net 13)
	)
	(segment
		(start 132.2 54.98)
		(end 131.93 54.71)
		(width 0.1)
		(layer "F.Cu")
		(net 13)
	)
	(segment
		(start 132.2 57.11)
		(end 132.2 54.98)
		(width 0.1)
		(layer "F.Cu")
		(net 13)
	)
	(segment
		(start 133.6 57.38)
		(end 132.47 57.38)
		(width 0.1)
		(layer "F.Cu")
		(net 13)
	)
	(segment
		(start 180.425 141.06)
		(end 180.425 141.65)
		(width 0.2)
		(layer "F.Cu")
		(net 13)
	)
	(segment
		(start 176.33 141.31)
		(end 177.78 139.86)
		(width 1)
		(layer "F.Cu")
		(net 13)
	)
	(segment
		(start 184.668 123.168)
		(end 183.75 122.25)
		(width 1)
		(layer "F.Cu")
		(net 13)
	)
	(segment
		(start 132.47 57.38)
		(end 132.2 57.11)
		(width 0.1)
		(layer "F.Cu")
		(net 13)
	)
	(segment
		(start 128.709212 60.975)
		(end 128.119213 60.975)
		(width 0.2)
		(layer "F.Cu")
		(net 13)
	)
	(segment
		(start 130.064999 60.975)
		(end 130.069999 60.98)
		(width 0.2)
		(layer "F.Cu")
		(net 13)
	)
	(segment
		(start 180.425 109.65)
		(end 179.825 110.25)
		(width 0.15)
		(layer "F.Cu")
		(net 13)
	)
	(segment
		(start 129.95 54.71)
		(end 129.029999 55.630001)
		(width 0.1)
		(layer "F.Cu")
		(net 13)
	)
	(segment
		(start 179.125 68.51)
		(end 179.125 69.1)
		(width 0.15)
		(layer "F.Cu")
		(net 13)
	)
	(segment
		(start 176.345 124.655)
		(end 176.345 125.82)
		(width 1)
		(layer "F.Cu")
		(net 13)
	)
	(segment
		(start 184.25 57.14)
		(end 184.25 58)
		(width 0.1)
		(layer "F.Cu")
		(net 13)
	)
	(segment
		(start 180.415 126.06)
		(end 180.415 126.65)
		(width 0.15)
		(layer "F.Cu")
		(net 13)
	)
	(segment
		(start 186.75 112.715734)
		(end 186.75 105.25)
		(width 2)
		(layer "F.Cu")
		(net 13)
	)
	(segment
		(start 179.125 89.1)
		(end 178.525 89.7)
		(width 0.15)
		(layer "F.Cu")
		(net 13)
	)
	(segment
		(start 129.029999 55.630001)
		(end 129.029999 55.68)
		(width 0.1)
		(layer "F.Cu")
		(net 13)
	)
	(segment
		(start 183.75 115.715734)
		(end 186.75 112.715734)
		(width 2)
		(layer "F.Cu")
		(net 13)
	)
	(segment
		(start 180.425 141.65)
		(end 179.825 142.25)
		(width 0.2)
		(layer "F.Cu")
		(net 13)
	)
	(segment
		(start 133.8 56.75)
		(end 133.8 57.18)
		(width 0.1)
		(layer "F.Cu")
		(net 13)
	)
	(segment
		(start 179.125 69.1)
		(end 178.525 69.7)
		(width 0.15)
		(layer "F.Cu")
		(net 13)
	)
	(segment
		(start 178.75 122.25)
		(end 176.345 124.655)
		(width 1)
		(layer "F.Cu")
		(net 13)
	)
	(segment
		(start 181.687 137.653)
		(end 185.216468 134.123532)
		(width 1)
		(layer "F.Cu")
		(net 13)
	)
	(segment
		(start 177.78 138.71)
		(end 178.837 137.653)
		(width 1)
		(layer "F.Cu")
		(net 13)
	)
	(segment
		(start 185.216468 134.123532)
		(end 185.216468 125.716468)
		(width 1)
		(layer "F.Cu")
		(net 13)
	)
	(segment
		(start 128.709212 60.975)
		(end 130.064999 60.975)
		(width 0.2)
		(layer "F.Cu")
		(net 13)
	)
	(segment
		(start 180.415 126.65)
		(end 179.815 127.25)
		(width 0.15)
		(layer "F.Cu")
		(net 13)
	)
	(segment
		(start 128.119213 60.975)
		(end 127.519213 60.375)
		(width 0.2)
		(layer "F.Cu")
		(net 13)
	)
	(segment
		(start 180.425 109.06)
		(end 180.425 109.65)
		(width 0.15)
		(layer "F.Cu")
		(net 13)
	)
	(segment
		(start 184.668 125.168)
		(end 184.668 123.168)
		(width 1)
		(layer "F.Cu")
		(net 13)
	)
	(segment
		(start 185.216468 125.716468)
		(end 184.668 125.168)
		(width 1)
		(layer "F.Cu")
		(net 13)
	)
	(segment
		(start 177.78 139.86)
		(end 177.78 138.71)
		(width 1)
		(layer "F.Cu")
		(net 13)
	)
	(segment
		(start 178.837 137.653)
		(end 181.687 137.653)
		(width 1)
		(layer "F.Cu")
		(net 13)
	)
	(segment
		(start 131.93 54.71)
		(end 129.95 54.71)
		(width 0.1)
		(layer "F.Cu")
		(net 13)
	)
	(segment
		(start 133.8 57.18)
		(end 133.6 57.38)
		(width 0.1)
		(layer "F.Cu")
		(net 13)
	)
	(segment
		(start 183.75 122.25)
		(end 183.75 115.715734)
		(width 2)
		(layer "F.Cu")
		(net 13)
	)
	(via
		(at 206.5 69.6)
		(size 0.45)
		(drill 0.1)
		(layers "F.Cu" "B.Cu")
		(free yes)
		(net 13)
	)
	(via
		(at 173.6 66)
		(size 0.45)
		(drill 0.1)
		(layers "F.Cu" "B.Cu")
		(free yes)
		(net 13)
	)
	(via
		(at 189 101.7)
		(size 0.45)
		(drill 0.1)
		(layers "F.Cu" "B.Cu")
		(remove_unused_layers yes)
		(keep_end_layers yes)
		(free yes)
		(zone_layer_connections "In4.Cu" "In5.Cu")
		(net 13)
	)
	(via
		(at 206.5 69.1)
		(size 0.45)
		(drill 0.1)
		(layers "F.Cu" "B.Cu")
		(free yes)
		(net 13)
	)
	(via
		(at 186.5 91.25)
		(size 0.45)
		(drill 0.1)
		(layers "F.Cu" "B.Cu")
		(remove_unused_layers yes)
		(keep_end_layers yes)
		(free yes)
		(zone_layer_connections "In4.Cu" "In5.Cu")
		(net 13)
	)
	(via
		(at 106.5 147)
		(size 0.45)
		(drill 0.1)
		(layers "F.Cu" "B.Cu")
		(free yes)
		(net 13)
	)
	(via
		(at 184.25 58)
		(size 0.45)
		(drill 0.1)
		(layers "F.Cu" "B.Cu")
		(net 13)
	)
	(via
		(at 188.4 104)
		(size 0.45)
		(drill 0.1)
		(layers "F.Cu" "B.Cu")
		(remove_unused_layers yes)
		(keep_end_layers yes)
		(free yes)
		(zone_layer_connections "In4.Cu" "In5.Cu")
		(net 13)
	)
	(via
		(at 186.5 81)
		(size 0.45)
		(drill 0.1)
		(layers "F.Cu" "B.Cu")
		(remove_unused_layers yes)
		(keep_end_layers yes)
		(free yes)
		(zone_layer_connections "In4.Cu" "In5.Cu")
		(net 13)
	)
	(via
		(at 238.895 60.3)
		(size 0.45)
		(drill 0.1)
		(layers "F.Cu" "B.Cu")
		(net 13)
	)
	(via
		(at 104 142.75)
		(size 0.45)
		(drill 0.1)
		(layers "F.Cu" "B.Cu")
		(free yes)
		(net 13)
	)
	(via
		(at 189 100.5)
		(size 0.45)
		(drill 0.1)
		(layers "F.Cu" "B.Cu")
		(remove_unused_layers yes)
		(keep_end_layers yes)
		(free yes)
		(zone_layer_connections "In4.Cu" "In5.Cu")
		(net 13)
	)
	(via
		(at 188.4 102.8)
		(size 0.45)
		(drill 0.1)
		(layers "F.Cu" "B.Cu")
		(remove_unused_layers yes)
		(keep_end_layers yes)
		(free yes)
		(zone_layer_connections "In4.Cu" "In5.Cu")
		(net 13)
	)
	(via
		(at 206 69.1)
		(size 0.45)
		(drill 0.1)
		(layers "F.Cu" "B.Cu")
		(free yes)
		(net 13)
	)
	(via
		(at 185.25 82.5)
		(size 0.45)
		(drill 0.1)
		(layers "F.Cu" "B.Cu")
		(remove_unused_layers yes)
		(keep_end_layers yes)
		(free yes)
		(zone_layer_connections "In4.Cu" "In5.Cu")
		(net 13)
	)
	(via
		(at 206.5 68.1)
		(size 0.45)
		(drill 0.1)
		(layers "F.Cu" "B.Cu")
		(free yes)
		(net 13)
	)
	(via
		(at 185 81)
		(size 0.45)
		(drill 0.1)
		(layers "F.Cu" "B.Cu")
		(remove_unused_layers yes)
		(keep_end_layers yes)
		(free yes)
		(zone_layer_connections "In4.Cu" "In5.Cu")
		(net 13)
	)
	(via
		(at 189 97.05)
		(size 0.45)
		(drill 0.1)
		(layers "F.Cu" "B.Cu")
		(remove_unused_layers yes)
		(keep_end_layers yes)
		(free yes)
		(zone_layer_connections "In4.Cu" "In5.Cu")
		(net 13)
	)
	(via
		(at 188.4 103.4)
		(size 0.45)
		(drill 0.1)
		(layers "F.Cu" "B.Cu")
		(remove_unused_layers yes)
		(keep_end_layers yes)
		(free yes)
		(zone_layer_connections "In4.Cu" "In5.Cu")
		(net 13)
	)
	(via
		(at 102 142.75)
		(size 0.45)
		(drill 0.1)
		(layers "F.Cu" "B.Cu")
		(free yes)
		(net 13)
	)
	(via
		(at 184.5 91.25)
		(size 0.45)
		(drill 0.1)
		(layers "F.Cu" "B.Cu")
		(remove_unused_layers yes)
		(keep_end_layers yes)
		(free yes)
		(zone_layer_connections "In4.Cu" "In5.Cu")
		(net 13)
	)
	(via
		(at 107.5 146)
		(size 0.45)
		(drill 0.1)
		(layers "F.Cu" "B.Cu")
		(free yes)
		(net 13)
	)
	(via
		(at 189 105.2)
		(size 0.45)
		(drill 0.1)
		(layers "F.Cu" "B.Cu")
		(remove_unused_layers yes)
		(keep_end_layers yes)
		(free yes)
		(zone_layer_connections "In4.Cu" "In5.Cu")
		(net 13)
	)
	(via
		(at 126.769995 56.61)
		(size 0.45)
		(drill 0.1)
		(layers "F.Cu" "B.Cu")
		(net 13)
	)
	(via
		(at 185.5 91.25)
		(size 0.45)
		(drill 0.1)
		(layers "F.Cu" "B.Cu")
		(remove_unused_layers yes)
		(keep_end_layers yes)
		(free yes)
		(zone_layer_connections "In4.Cu" "In5.Cu")
		(net 13)
	)
	(via
		(at 185.75 82.5)
		(size 0.45)
		(drill 0.1)
		(layers "F.Cu" "B.Cu")
		(remove_unused_layers yes)
		(keep_end_layers yes)
		(free yes)
		(zone_layer_connections "In4.Cu" "In5.Cu")
		(net 13)
	)
	(via
		(at 101.5 147)
		(size 0.45)
		(drill 0.1)
		(layers "F.Cu" "B.Cu")
		(free yes)
		(net 13)
	)
	(via
		(at 104.5 143.25)
		(size 0.45)
		(drill 0.1)
		(layers "F.Cu" "B.Cu")
		(free yes)
		(net 13)
	)
	(via
		(at 207 70.1)
		(size 0.45)
		(drill 0.1)
		(layers "F.Cu" "B.Cu")
		(free yes)
		(net 13)
	)
	(via
		(at 206.5 68.6)
		(size 0.45)
		(drill 0.1)
		(layers "F.Cu" "B.Cu")
		(free yes)
		(net 13)
	)
	(via
		(at 205.5 69.6)
		(size 0.45)
		(drill 0.1)
		(layers "F.Cu" "B.Cu")
		(free yes)
		(net 13)
	)
	(via
		(at 101.5 143.25)
		(size 0.45)
		(drill 0.1)
		(layers "F.Cu" "B.Cu")
		(free yes)
		(net 13)
	)
	(via
		(at 186 81)
		(size 0.45)
		(drill 0.1)
		(layers "F.Cu" "B.Cu")
		(remove_unused_layers yes)
		(keep_end_layers yes)
		(free yes)
		(zone_layer_connections "In4.Cu" "In5.Cu")
		(net 13)
	)
	(via
		(at 184.5 81)
		(size 0.45)
		(drill 0.1)
		(layers "F.Cu" "B.Cu")
		(remove_unused_layers yes)
		(keep_end_layers yes)
		(free yes)
		(zone_layer_connections "In4.Cu" "In5.Cu")
		(net 13)
	)
	(via
		(at 107 142.75)
		(size 0.45)
		(drill 0.1)
		(layers "F.Cu" "B.Cu")
		(free yes)
		(net 13)
	)
	(via
		(at 206 69.6)
		(size 0.45)
		(drill 0.1)
		(layers "F.Cu" "B.Cu")
		(free yes)
		(net 13)
	)
	(via
		(at 189 104.6)
		(size 0.45)
		(drill 0.1)
		(layers "F.Cu" "B.Cu")
		(remove_unused_layers yes)
		(keep_end_layers yes)
		(free yes)
		(zone_layer_connections "In4.Cu" "In5.Cu")
		(net 13)
	)
	(via
		(at 206 68.1)
		(size 0.45)
		(drill 0.1)
		(layers "F.Cu" "B.Cu")
		(free yes)
		(net 13)
	)
	(via
		(at 189 97.65)
		(size 0.45)
		(drill 0.1)
		(layers "F.Cu" "B.Cu")
		(remove_unused_layers yes)
		(keep_end_layers yes)
		(free yes)
		(zone_layer_connections "In4.Cu" "In5.Cu")
		(net 13)
	)
	(via
		(at 207 69.1)
		(size 0.45)
		(drill 0.1)
		(layers "F.Cu" "B.Cu")
		(free yes)
		(net 13)
	)
	(via
		(at 174.2 65.4)
		(size 0.45)
		(drill 0.1)
		(layers "F.Cu" "B.Cu")
		(free yes)
		(net 13)
	)
	(via
		(at 107.5 147)
		(size 0.45)
		(drill 0.1)
		(layers "F.Cu" "B.Cu")
		(free yes)
		(net 13)
	)
	(via
		(at 103 145.5)
		(size 0.45)
		(drill 0.1)
		(layers "F.Cu" "B.Cu")
		(free yes)
		(net 13)
	)
	(via
		(at 189 99.3)
		(size 0.45)
		(drill 0.1)
		(layers "F.Cu" "B.Cu")
		(remove_unused_layers yes)
		(keep_end_layers yes)
		(free yes)
		(zone_layer_connections "In4.Cu" "In5.Cu")
		(net 13)
	)
	(via
		(at 176.75 67.25)
		(size 0.45)
		(drill 0.1)
		(layers "F.Cu" "B.Cu")
		(free yes)
		(net 13)
	)
	(via
		(at 105 146.5)
		(size 0.45)
		(drill 0.1)
		(layers "F.Cu" "B.Cu")
		(free yes)
		(net 13)
	)
	(via
		(at 184.75 82.5)
		(size 0.45)
		(drill 0.1)
		(layers "F.Cu" "B.Cu")
		(remove_unused_layers yes)
		(keep_end_layers yes)
		(free yes)
		(zone_layer_connections "In4.Cu" "In5.Cu")
		(net 13)
	)
	(via
		(at 129.530002 56.61)
		(size 0.45)
		(drill 0.1)
		(layers "F.Cu" "B.Cu")
		(net 13)
	)
	(via
		(at 189 99.9)
		(size 0.45)
		(drill 0.1)
		(layers "F.Cu" "B.Cu")
		(remove_unused_layers yes)
		(keep_end_layers yes)
		(free yes)
		(zone_layer_connections "In4.Cu" "In5.Cu")
		(net 13)
	)
	(via
		(at 105.5 143.25)
		(size 0.45)
		(drill 0.1)
		(layers "F.Cu" "B.Cu")
		(free yes)
		(net 13)
	)
	(via
		(at 106 142.75)
		(size 0.45)
		(drill 0.1)
		(layers "F.Cu" "B.Cu")
		(free yes)
		(net 13)
	)
	(via
		(at 101.5 146)
		(size 0.45)
		(drill 0.1)
		(layers "F.Cu" "B.Cu")
		(free yes)
		(net 13)
	)
	(via
		(at 189 95.25)
		(size 0.45)
		(drill 0.1)
		(layers "F.Cu" "B.Cu")
		(remove_unused_layers yes)
		(keep_end_layers yes)
		(free yes)
		(zone_layer_connections "In4.Cu" "In5.Cu")
		(net 13)
	)
	(via
		(at 172.75 67)
		(size 0.45)
		(drill 0.1)
		(layers "F.Cu" "B.Cu")
		(free yes)
		(net 13)
	)
	(via
		(at 188.4 95.25)
		(size 0.45)
		(drill 0.1)
		(layers "F.Cu" "B.Cu")
		(remove_unused_layers yes)
		(keep_end_layers yes)
		(free yes)
		(zone_layer_connections "In4.Cu" "In5.Cu")
		(net 13)
	)
	(via
		(at 184 91.25)
		(size 0.45)
		(drill 0.1)
		(layers "F.Cu" "B.Cu")
		(remove_unused_layers yes)
		(keep_end_layers yes)
		(free yes)
		(zone_layer_connections "In4.Cu" "In5.Cu")
		(net 13)
	)
	(via
		(at 188.4 99.3)
		(size 0.45)
		(drill 0.1)
		(layers "F.Cu" "B.Cu")
		(remove_unused_layers yes)
		(keep_end_layers yes)
		(free yes)
		(zone_layer_connections "In4.Cu" "In5.Cu")
		(net 13)
	)
	(via
		(at 103 146.5)
		(size 0.45)
		(drill 0.1)
		(layers "F.Cu" "B.Cu")
		(free yes)
		(net 13)
	)
	(via
		(at 172 65.4)
		(size 0.45)
		(drill 0.1)
		(layers "F.Cu" "B.Cu")
		(free yes)
		(net 13)
	)
	(via
		(at 104 145.5)
		(size 0.45)
		(drill 0.1)
		(layers "F.Cu" "B.Cu")
		(free yes)
		(net 13)
	)
	(via
		(at 187.1 89.75)
		(size 0.45)
		(drill 0.1)
		(layers "F.Cu" "B.Cu")
		(remove_unused_layers yes)
		(keep_end_layers yes)
		(free yes)
		(zone_layer_connections "In4.Cu" "In5.Cu")
		(net 13)
	)
	(via
		(at 102 145.5)
		(size 0.45)
		(drill 0.1)
		(layers "F.Cu" "B.Cu")
		(free yes)
		(net 13)
	)
	(via
		(at 102.5 147)
		(size 0.45)
		(drill 0.1)
		(layers "F.Cu" "B.Cu")
		(free yes)
		(net 13)
	)
	(via
		(at 188.4 104.6)
		(size 0.45)
		(drill 0.1)
		(layers "F.Cu" "B.Cu")
		(remove_unused_layers yes)
		(keep_end_layers yes)
		(free yes)
		(zone_layer_connections "In4.Cu" "In5.Cu")
		(net 13)
	)
	(via
		(at 187 91.25)
		(size 0.45)
		(drill 0.1)
		(layers "F.Cu" "B.Cu")
		(remove_unused_layers yes)
		(keep_end_layers yes)
		(free yes)
		(zone_layer_connections "In4.Cu" "In5.Cu")
		(net 13)
	)
	(via
		(at 171.4 66)
		(size 0.45)
		(drill 0.1)
		(layers "F.Cu" "B.Cu")
		(free yes)
		(net 13)
	)
	(via
		(at 106.5 146)
		(size 0.45)
		(drill 0.1)
		(layers "F.Cu" "B.Cu")
		(free yes)
		(net 13)
	)
	(via
		(at 188.4 95.85)
		(size 0.45)
		(drill 0.1)
		(layers "F.Cu" "B.Cu")
		(remove_unused_layers yes)
		(keep_end_layers yes)
		(free yes)
		(zone_layer_connections "In4.Cu" "In5.Cu")
		(net 13)
	)
	(via
		(at 103.5 146)
		(size 0.45)
		(drill 0.1)
		(layers "F.Cu" "B.Cu")
		(free yes)
		(net 13)
	)
	(via
		(at 104 146.5)
		(size 0.45)
		(drill 0.1)
		(layers "F.Cu" "B.Cu")
		(free yes)
		(net 13)
	)
	(via
		(at 186 91.25)
		(size 0.45)
		(drill 0.1)
		(layers "F.Cu" "B.Cu")
		(remove_unused_layers yes)
		(keep_end_layers yes)
		(free yes)
		(zone_layer_connections "In4.Cu" "In5.Cu")
		(net 13)
	)
	(via
		(at 205.5 68.6)
		(size 0.45)
		(drill 0.1)
		(layers "F.Cu" "B.Cu")
		(free yes)
		(net 13)
	)
	(via
		(at 104.5 147)
		(size 0.45)
		(drill 0.1)
		(layers "F.Cu" "B.Cu")
		(free yes)
		(net 13)
	)
	(via
		(at 107 145.5)
		(size 0.45)
		(drill 0.1)
		(layers "F.Cu" "B.Cu")
		(free yes)
		(net 13)
	)
	(via
		(at 174.75 67)
		(size 0.45)
		(drill 0.1)
		(layers "F.Cu" "B.Cu")
		(free yes)
		(net 13)
	)
	(via
		(at 185.6 89.75)
		(size 0.45)
		(drill 0.1)
		(layers "F.Cu" "B.Cu")
		(remove_unused_layers yes)
		(keep_end_layers yes)
		(free yes)
		(zone_layer_connections "In4.Cu" "In5.Cu")
		(net 13)
	)
	(via
		(at 178.85 69.25)
		(size 0.45)
		(drill 0.1)
		(layers "F.Cu" "B.Cu")
		(remove_unused_layers yes)
		(keep_end_layers yes)
		(zone_layer_connections "In4.Cu")
		(net 13)
	)
	(via
		(at 188.4 97.05)
		(size 0.45)
		(drill 0.1)
		(layers "F.Cu" "B.Cu")
		(remove_unused_layers yes)
		(keep_end_layers yes)
		(free yes)
		(zone_layer_connections "In4.Cu" "In5.Cu")
		(net 13)
	)
	(via
		(at 206 70.1)
		(size 0.45)
		(drill 0.1)
		(layers "F.Cu" "B.Cu")
		(free yes)
		(net 13)
	)
	(via
		(at 176.8 65.2)
		(size 0.45)
		(drill 0.1)
		(layers "F.Cu" "B.Cu")
		(free yes)
		(net 13)
	)
	(via
		(at 106 145.5)
		(size 0.45)
		(drill 0.1)
		(layers "F.Cu" "B.Cu")
		(free yes)
		(net 13)
	)
	(via
		(at 170.5 67)
		(size 0.45)
		(drill 0.1)
		(layers "F.Cu" "B.Cu")
		(free yes)
		(net 13)
	)
	(via
		(at 129.029999 56.61)
		(size 0.45)
		(drill 0.1)
		(layers "F.Cu" "B.Cu")
		(net 13)
	)
	(via
		(at 207 68.6)
		(size 0.45)
		(drill 0.1)
		(layers "F.Cu" "B.Cu")
		(free yes)
		(net 13)
	)
	(via
		(at 207.5 68.6)
		(size 0.45)
		(drill 0.1)
		(layers "F.Cu" "B.Cu")
		(free yes)
		(net 13)
	)
	(via
		(at 105 142.75)
		(size 0.45)
		(drill 0.1)
		(layers "F.Cu" "B.Cu")
		(free yes)
		(net 13)
	)
	(via
		(at 188.4 101.7)
		(size 0.45)
		(drill 0.1)
		(layers "F.Cu" "B.Cu")
		(remove_unused_layers yes)
		(keep_end_layers yes)
		(free yes)
		(zone_layer_connections "In4.Cu" "In5.Cu")
		(net 13)
	)
	(via
		(at 189 103.4)
		(size 0.45)
		(drill 0.1)
		(layers "F.Cu" "B.Cu")
		(remove_unused_layers yes)
		(keep_end_layers yes)
		(free yes)
		(zone_layer_connections "In4.Cu" "In5.Cu")
		(net 13)
	)
	(via
		(at 189 102.8)
		(size 0.45)
		(drill 0.1)
		(layers "F.Cu" "B.Cu")
		(remove_unused_layers yes)
		(keep_end_layers yes)
		(free yes)
		(zone_layer_connections "In4.Cu" "In5.Cu")
		(net 13)
	)
	(via
		(at 105.5 147)
		(size 0.45)
		(drill 0.1)
		(layers "F.Cu" "B.Cu")
		(free yes)
		(net 13)
	)
	(via
		(at 188.4 100.5)
		(size 0.45)
		(drill 0.1)
		(layers "F.Cu" "B.Cu")
		(remove_unused_layers yes)
		(keep_end_layers yes)
		(free yes)
		(zone_layer_connections "In4.Cu" "In5.Cu")
		(net 13)
	)
	(via
		(at 104.5 146)
		(size 0.45)
		(drill 0.1)
		(layers "F.Cu" "B.Cu")
		(free yes)
		(net 13)
	)
	(via
		(at 185 91.25)
		(size 0.45)
		(drill 0.1)
		(layers "F.Cu" "B.Cu")
		(remove_unused_layers yes)
		(keep_end_layers yes)
		(free yes)
		(zone_layer_connections "In4.Cu" "In5.Cu")
		(net 13)
	)
	(via
		(at 207.5 70.1)
		(size 0.45)
		(drill 0.1)
		(layers "F.Cu" "B.Cu")
		(free yes)
		(net 13)
	)
	(via
		(at 189 96.45)
		(size 0.45)
		(drill 0.1)
		(layers "F.Cu" "B.Cu")
		(remove_unused_layers yes)
		(keep_end_layers yes)
		(free yes)
		(zone_layer_connections "In4.Cu" "In5.Cu")
		(net 13)
	)
	(via
		(at 207.5 69.6)
		(size 0.45)
		(drill 0.1)
		(layers "F.Cu" "B.Cu")
		(free yes)
		(net 13)
	)
	(via
		(at 184.6 89.75)
		(size 0.45)
		(drill 0.1)
		(layers "F.Cu" "B.Cu")
		(remove_unused_layers yes)
		(keep_end_layers yes)
		(free yes)
		(zone_layer_connections "In4.Cu" "In5.Cu")
		(net 13)
	)
	(via
		(at 102.5 146)
		(size 0.45)
		(drill 0.1)
		(layers "F.Cu" "B.Cu")
		(free yes)
		(net 13)
	)
	(via
		(at 184.25 59.9)
		(size 0.45)
		(drill 0.1)
		(layers "F.Cu" "B.Cu")
		(net 13)
	)
	(via
		(at 188.4 96.45)
		(size 0.45)
		(drill 0.1)
		(layers "F.Cu" "B.Cu")
		(remove_unused_layers yes)
		(keep_end_layers yes)
		(free yes)
		(zone_layer_connections "In4.Cu" "In5.Cu")
		(net 13)
	)
	(via
		(at 103.5 147)
		(size 0.45)
		(drill 0.1)
		(layers "F.Cu" "B.Cu")
		(free yes)
		(net 13)
	)
	(via
		(at 207 69.6)
		(size 0.45)
		(drill 0.1)
		(layers "F.Cu" "B.Cu")
		(free yes)
		(net 13)
	)
	(via
		(at 186.6 89.75)
		(size 0.45)
		(drill 0.1)
		(layers "F.Cu" "B.Cu")
		(remove_unused_layers yes)
		(keep_end_layers yes)
		(free yes)
		(zone_layer_connections "In4.Cu" "In5.Cu")
		(net 13)
	)
	(via
		(at 188.4 99.9)
		(size 0.45)
		(drill 0.1)
		(layers "F.Cu" "B.Cu")
		(remove_unused_layers yes)
		(keep_end_layers yes)
		(free yes)
		(zone_layer_connections "In4.Cu" "In5.Cu")
		(net 13)
	)
	(via
		(at 207 68.1)
		(size 0.45)
		(drill 0.1)
		(layers "F.Cu" "B.Cu")
		(free yes)
		(net 13)
	)
	(via
		(at 103.5 143.25)
		(size 0.45)
		(drill 0.1)
		(layers "F.Cu" "B.Cu")
		(free yes)
		(net 13)
	)
	(via
		(at 207.5 69.1)
		(size 0.45)
		(drill 0.1)
		(layers "F.Cu" "B.Cu")
		(free yes)
		(net 13)
	)
	(via
		(at 186.25 82.5)
		(size 0.45)
		(drill 0.1)
		(layers "F.Cu" "B.Cu")
		(remove_unused_layers yes)
		(keep_end_layers yes)
		(free yes)
		(zone_layer_connections "In4.Cu" "In5.Cu")
		(net 13)
	)
	(via
		(at 206 68.6)
		(size 0.45)
		(drill 0.1)
		(layers "F.Cu" "B.Cu")
		(free yes)
		(net 13)
	)
	(via
		(at 105 145.5)
		(size 0.45)
		(drill 0.1)
		(layers "F.Cu" "B.Cu")
		(free yes)
		(net 13)
	)
	(via
		(at 128.529995 56.61)
		(size 0.45)
		(drill 0.1)
		(layers "F.Cu" "B.Cu")
		(net 13)
	)
	(via
		(at 105.5 146)
		(size 0.45)
		(drill 0.1)
		(layers "F.Cu" "B.Cu")
		(free yes)
		(net 13)
	)
	(via
		(at 175.6 66)
		(size 0.45)
		(drill 0.1)
		(layers "F.Cu" "B.Cu")
		(free yes)
		(net 13)
	)
	(via
		(at 176.2 65.6)
		(size 0.45)
		(drill 0.1)
		(layers "F.Cu" "B.Cu")
		(free yes)
		(net 13)
	)
	(via
		(at 102.5 143.25)
		(size 0.45)
		(drill 0.1)
		(layers "F.Cu" "B.Cu")
		(free yes)
		(net 13)
	)
	(via
		(at 101 142.75)
		(size 0.45)
		(drill 0.1)
		(layers "F.Cu" "B.Cu")
		(free yes)
		(net 13)
	)
	(via
		(at 185.1 89.75)
		(size 0.45)
		(drill 0.1)
		(layers "F.Cu" "B.Cu")
		(remove_unused_layers yes)
		(keep_end_layers yes)
		(free yes)
		(zone_layer_connections "In4.Cu" "In5.Cu")
		(net 13)
	)
	(via
		(at 205.5 69.1)
		(size 0.45)
		(drill 0.1)
		(layers "F.Cu" "B.Cu")
		(free yes)
		(net 13)
	)
	(via
		(at 106 146.5)
		(size 0.45)
		(drill 0.1)
		(layers "F.Cu" "B.Cu")
		(free yes)
		(net 13)
	)
	(via
		(at 189 101.1)
		(size 0.45)
		(drill 0.1)
		(layers "F.Cu" "B.Cu")
		(remove_unused_layers yes)
		(keep_end_layers yes)
		(free yes)
		(zone_layer_connections "In4.Cu" "In5.Cu")
		(net 13)
	)
	(via
		(at 205.5 68.1)
		(size 0.45)
		(drill 0.1)
		(layers "F.Cu" "B.Cu")
		(free yes)
		(net 13)
	)
	(via
		(at 102 146.5)
		(size 0.45)
		(drill 0.1)
		(layers "F.Cu" "B.Cu")
		(free yes)
		(net 13)
	)
	(via
		(at 206.5 70.1)
		(size 0.45)
		(drill 0.1)
		(layers "F.Cu" "B.Cu")
		(free yes)
		(net 13)
	)
	(via
		(at 207.5 68.1)
		(size 0.45)
		(drill 0.1)
		(layers "F.Cu" "B.Cu")
		(free yes)
		(net 13)
	)
	(via
		(at 189 104)
		(size 0.45)
		(drill 0.1)
		(layers "F.Cu" "B.Cu")
		(remove_unused_layers yes)
		(keep_end_layers yes)
		(free yes)
		(zone_layer_connections "In4.Cu" "In5.Cu")
		(net 13)
	)
	(via
		(at 127.770002 56.61)
		(size 0.45)
		(drill 0.1)
		(layers "F.Cu" "B.Cu")
		(net 13)
	)
	(via
		(at 107 146.5)
		(size 0.45)
		(drill 0.1)
		(layers "F.Cu" "B.Cu")
		(free yes)
		(net 13)
	)
	(via
		(at 103 142.75)
		(size 0.45)
		(drill 0.1)
		(layers "F.Cu" "B.Cu")
		(free yes)
		(net 13)
	)
	(via
		(at 106.5 143.25)
		(size 0.45)
		(drill 0.1)
		(layers "F.Cu" "B.Cu")
		(free yes)
		(net 13)
	)
	(via
		(at 107.5 143.25)
		(size 0.45)
		(drill 0.1)
		(layers "F.Cu" "B.Cu")
		(free yes)
		(net 13)
	)
	(via
		(at 186.1 89.75)
		(size 0.45)
		(drill 0.1)
		(layers "F.Cu" "B.Cu")
		(remove_unused_layers yes)
		(keep_end_layers yes)
		(free yes)
		(zone_layer_connections "In4.Cu" "In5.Cu")
		(net 13)
	)
	(via
		(at 188.4 105.2)
		(size 0.45)
		(drill 0.1)
		(layers "F.Cu" "B.Cu")
		(remove_unused_layers yes)
		(keep_end_layers yes)
		(free yes)
		(zone_layer_connections "In4.Cu" "In5.Cu")
		(net 13)
	)
	(via
		(at 189 95.85)
		(size 0.45)
		(drill 0.1)
		(layers "F.Cu" "B.Cu")
		(remove_unused_layers yes)
		(keep_end_layers yes)
		(free yes)
		(zone_layer_connections "In4.Cu" "In5.Cu")
		(net 13)
	)
	(via
		(at 188.4 97.65)
		(size 0.45)
		(drill 0.1)
		(layers "F.Cu" "B.Cu")
		(remove_unused_layers yes)
		(keep_end_layers yes)
		(free yes)
		(zone_layer_connections "In4.Cu" "In5.Cu")
		(net 13)
	)
	(via
		(at 127.269999 56.61)
		(size 0.45)
		(drill 0.1)
		(layers "F.Cu" "B.Cu")
		(net 13)
	)
	(via
		(at 185.5 81)
		(size 0.45)
		(drill 0.1)
		(layers "F.Cu" "B.Cu")
		(remove_unused_layers yes)
		(keep_end_layers yes)
		(free yes)
		(zone_layer_connections "In4.Cu" "In5.Cu")
		(net 13)
	)
	(via
		(at 177 69)
		(size 0.45)
		(drill 0.1)
		(layers "F.Cu" "B.Cu")
		(free yes)
		(net 13)
	)
	(via
		(at 188.4 101.1)
		(size 0.45)
		(drill 0.1)
		(layers "F.Cu" "B.Cu")
		(remove_unused_layers yes)
		(keep_end_layers yes)
		(free yes)
		(zone_layer_connections "In4.Cu" "In5.Cu")
		(net 13)
	)
	(segment
		(start 132.875 67.625)
		(end 141.175 67.625)
		(width 1)
		(layer "B.Cu")
		(net 13)
	)
	(segment
		(start 142.25 68.7)
		(end 144 68.7)
		(width 1)
		(layer "B.Cu")
		(net 13)
	)
	(segment
		(start 238.895 61.015)
		(end 238.895 60.3)
		(width 0.3)
		(layer "B.Cu")
		(net 13)
	)
	(segment
		(start 180.71 92.2)
		(end 180.464 91.954)
		(width 0.2)
		(layer "B.Cu")
		(net 13)
	)
	(segment
		(start 184.25 58)
		(end 184.25 59.9)
		(width 0.1)
		(layer "B.Cu")
		(net 13)
	)
	(segment
		(start 141.175 67.625)
		(end 142.25 68.7)
		(width 1)
		(layer "B.Cu")
		(net 13)
	)
	(segment
		(start 146.95 71.65)
		(end 146.95 72.230762)
		(width 1)
		(layer "B.Cu")
		(net 13)
	)
	(segment
		(start 180.459 82.249)
		(end 180.71 82.5)
		(width 0.2)
		(layer "B.Cu")
		(net 13)
	)
	(segment
		(start 131.5 66.25)
		(end 132.875 67.625)
		(width 1)
		(layer "B.Cu")
		(net 13)
	)
	(segment
		(start 182.75 90.475678)
		(end 182.75 89.973)
		(width 0.2)
		(layer "B.Cu")
		(net 13)
	)
	(segment
		(start 185.3 92.45)
		(end 185.3 90)
		(width 1)
		(layer "B.Cu")
		(net 13)
	)
	(segment
		(start 129.530002 56.61)
		(end 126.769995 56.61)
		(width 1)
		(layer "B.Cu")
		(net 13)
	)
	(segment
		(start 131.5 66.25)
		(end 131.5 58.579998)
		(width 1)
		(layer "B.Cu")
		(net 13)
	)
	(segment
		(start 180.834 81.334)
		(end 181.426 81.926)
		(width 0.2)
		(layer "B.Cu")
		(net 13)
	)
	(segment
		(start 170.25 94.75)
		(end 183 94.75)
		(width 1)
		(layer "B.Cu")
		(net 13)
	)
	(segment
		(start 180.459 81.334)
		(end 180.834 81.334)
		(width 0.2)
		(layer "B.Cu")
		(net 13)
	)
	(segment
		(start 183 94.75)
		(end 185.3 92.45)
		(width 1)
		(layer "B.Cu")
		(net 13)
	)
	(segment
		(start 182.474 81.926)
		(end 182.75 81.65)
		(width 0.2)
		(layer "B.Cu")
		(net 13)
	)
	(segment
		(start 181.426 81.926)
		(end 182.474 81.926)
		(width 0.2)
		(layer "B.Cu")
		(net 13)
	)
	(segment
		(start 180.464 91.954)
		(end 181.271678 91.954)
		(width 0.2)
		(layer "B.Cu")
		(net 13)
	)
	(segment
		(start 144 68.7)
		(end 146.95 71.65)
		(width 1)
		(layer "B.Cu")
		(net 13)
	)
	(segment
		(start 180.71 93.1)
		(end 180.71 92.2)
		(width 0.2)
		(layer "B.Cu")
		(net 13)
	)
	(segment
		(start 131.5 58.579998)
		(end 129.530002 56.61)
		(width 1)
		(layer "B.Cu")
		(net 13)
	)
	(segment
		(start 182.75 81.65)
		(end 182.75 81.23)
		(width 0.2)
		(layer "B.Cu")
		(net 13)
	)
	(segment
		(start 158.45 82.95)
		(end 170.25 94.75)
		(width 1)
		(layer "B.Cu")
		(net 13)
	)
	(segment
		(start 157.669238 82.95)
		(end 158.45 82.95)
		(width 1)
		(layer "B.Cu")
		(net 13)
	)
	(segment
		(start 185.39 58)
		(end 184.25 58)
		(width 0.1)
		(layer "B.Cu")
		(net 13)
	)
	(segment
		(start 180.459 81.334)
		(end 180.459 82.249)
		(width 0.2)
		(layer "B.Cu")
		(net 13)
	)
	(segment
		(start 181.271678 91.954)
		(end 182.75 90.475678)
		(width 0.2)
		(layer "B.Cu")
		(net 13)
	)
	(segment
		(start 146.95 72.230762)
		(end 157.669238 82.95)
		(width 1)
		(layer "B.Cu")
		(net 13)
	)
	(segment
		(start 210.46 65.1)
		(end 211.92 63.64)
		(width 0.3)
		(layer "In5.Cu")
		(net 13)
	)
	(segment
		(start 215.29 60.31)
		(end 218.8 56.8)
		(width 0.3)
		(layer "In5.Cu")
		(net 13)
	)
	(segment
		(start 211.92 63.64)
		(end 211.92 61.59)
		(width 0.3)
		(layer "In5.Cu")
		(net 13)
	)
	(segment
		(start 218.8 56.8)
		(end 238.3 56.8)
		(width 0.3)
		(layer "In5.Cu")
		(net 13)
	)
	(segment
		(start 211.92 61.59)
		(end 213.2 60.31)
		(width 0.3)
		(layer "In5.Cu")
		(net 13)
	)
	(segment
		(start 238.3 56.8)
		(end 238.895 57.395)
		(width 0.3)
		(layer "In5.Cu")
		(net 13)
	)
	(segment
		(start 208.2 65.1)
		(end 210.46 65.1)
		(width 0.3)
		(layer "In5.Cu")
		(net 13)
	)
	(segment
		(start 213.2 60.31)
		(end 215.29 60.31)
		(width 0.3)
		(layer "In5.Cu")
		(net 13)
	)
	(segment
		(start 238.895 57.395)
		(end 238.895 60.3)
		(width 0.3)
		(layer "In5.Cu")
		(net 13)
	)
	(segment
		(start 207 68.1)
		(end 207 66.3)
		(width 0.3)
		(layer "In5.Cu")
		(net 13)
	)
	(segment
		(start 207 66.3)
		(end 208.2 65.1)
		(width 0.3)
		(layer "In5.Cu")
		(net 13)
	)
	(segment
		(start 103.515 113.37663)
		(end 103.515 106.915)
		(width 0.19)
		(layer "F.Cu")
		(net 15)
	)
	(segment
		(start 106.315 116.17663)
		(end 103.515 113.37663)
		(width 0.19)
		(layer "F.Cu")
		(net 15)
	)
	(segment
		(start 119.065532 77.385)
		(end 119.180532 77.5)
		(width 0.19)
		(layer "F.Cu")
		(net 15)
	)
	(segment
		(start 106.315 120.12337)
		(end 106.315 116.17663)
		(width 0.19)
		(layer "F.Cu")
		(net 15)
	)
	(segment
		(start 108.22337 129.185)
		(end 103.515 124.47663)
		(width 0.19)
		(layer "F.Cu")
		(net 15)
	)
	(segment
		(start 119.330532 76.65)
		(end 119.065532 76.915)
		(width 0.19)
		(layer "F.Cu")
		(net 15)
	)
	(segment
		(start 108.98 129.185)
		(end 108.22337 129.185)
		(width 0.19)
		(layer "F.Cu")
		(net 15)
	)
	(segment
		(start 103.515 122.92337)
		(end 106.315 120.12337)
		(width 0.19)
		(layer "F.Cu")
		(net 15)
	)
	(segment
		(start 119.065532 76.915)
		(end 119.065532 77.385)
		(width 0.19)
		(layer "F.Cu")
		(net 15)
	)
	(segment
		(start 109.295 129.5)
		(end 108.98 129.185)
		(width 0.19)
		(layer "F.Cu")
		(net 15)
	)
	(segment
		(start 109.32 129.5)
		(end 109.295 129.5)
		(width 0.19)
		(layer "F.Cu")
		(net 15)
	)
	(segment
		(start 103.515 124.47663)
		(end 103.515 122.92337)
		(width 0.19)
		(layer "F.Cu")
		(net 15)
	)
	(segment
		(start 103.515 106.915)
		(end 103.4 106.8)
		(width 0.19)
		(layer "F.Cu")
		(net 15)
	)
	(via
		(at 119.180532 77.5)
		(size 0.45)
		(drill 0.1)
		(layers "F.Cu" "B.Cu")
		(net 15)
	)
	(via
		(at 103.4 106.8)
		(size 0.45)
		(drill 0.1)
		(layers "F.Cu" "B.Cu")
		(net 15)
	)
	(segment
		(start 107.8375 86.043044)
		(end 108.4375 86.643044)
		(width 0.15)
		(layer "In7.Cu")
		(net 15)
	)
	(segment
		(start 102.445364 107.050909)
		(end 102.756956 107.3625)
		(width 0.15)
		(layer "In7.Cu")
		(net 15)
	)
	(segment
		(start 108.4375 86.643044)
		(end 108.4375 87.456956)
		(width 0.15)
		(layer "In7.Cu")
		(net 15)
	)
	(segment
		(start 101.6375 91.756956)
		(end 101.6375 106.243044)
		(width 0.15)
		(layer "In7.Cu")
		(net 15)
	)
	(segment
		(start 103.5625 106.9625)
		(end 103.4 106.8)
		(width 0.15)
		(layer "In7.Cu")
		(net 15)
	)
	(segment
		(start 119.018032 77.6625)
		(end 119.018032 78.476424)
		(width 0.15)
		(layer "In7.Cu")
		(net 15)
	)
	(segment
		(start 119.180532 77.5)
		(end 119.018032 77.6625)
		(width 0.15)
		(layer "In7.Cu")
		(net 15)
	)
	(segment
		(start 111.956956 81.9375)
		(end 111.456956 81.9375)
		(width 0.15)
		(layer "In7.Cu")
		(net 15)
	)
	(segment
		(start 109.656956 83.3375)
		(end 107.8375 85.156956)
		(width 0.15)
		(layer "In7.Cu")
		(net 15)
	)
	(segment
		(start 119.018032 78.476424)
		(end 118.556956 78.9375)
		(width 0.15)
		(layer "In7.Cu")
		(net 15)
	)
	(segment
		(start 108.4375 87.456956)
		(end 107.656956 88.2375)
		(width 0.15)
		(layer "In7.Cu")
		(net 15)
	)
	(segment
		(start 105.156956 88.2375)
		(end 101.6375 91.756956)
		(width 0.15)
		(layer "In7.Cu")
		(net 15)
	)
	(segment
		(start 107.8375 85.156956)
		(end 107.8375 86.043044)
		(width 0.15)
		(layer "In7.Cu")
		(net 15)
	)
	(segment
		(start 117.643044 78.9375)
		(end 117.343044 78.6375)
		(width 0.15)
		(layer "In7.Cu")
		(net 15)
	)
	(segment
		(start 103.5625 107.143044)
		(end 103.5625 106.9625)
		(width 0.15)
		(layer "In7.Cu")
		(net 15)
	)
	(segment
		(start 103.343044 107.3625)
		(end 103.5625 107.143044)
		(width 0.15)
		(layer "In7.Cu")
		(net 15)
	)
	(segment
		(start 102.756956 107.3625)
		(end 103.343044 107.3625)
		(width 0.15)
		(layer "In7.Cu")
		(net 15)
	)
	(segment
		(start 117.343044 78.6375)
		(end 116.456956 78.6375)
		(width 0.15)
		(layer "In7.Cu")
		(net 15)
	)
	(segment
		(start 102.382621 106.618677)
		(end 102.445363 106.681419)
		(width 0.15)
		(layer "In7.Cu")
		(net 15)
	)
	(segment
		(start 116.456956 78.6375)
		(end 114.656956 80.4375)
		(width 0.15)
		(layer "In7.Cu")
		(net 15)
	)
	(segment
		(start 107.656956 88.2375)
		(end 105.156956 88.2375)
		(width 0.15)
		(layer "In7.Cu")
		(net 15)
	)
	(segment
		(start 111.456956 81.9375)
		(end 110.056956 83.3375)
		(width 0.15)
		(layer "In7.Cu")
		(net 15)
	)
	(segment
		(start 114.656956 80.4375)
		(end 113.456956 80.4375)
		(width 0.15)
		(layer "In7.Cu")
		(net 15)
	)
	(segment
		(start 110.056956 83.3375)
		(end 109.656956 83.3375)
		(width 0.15)
		(layer "In7.Cu")
		(net 15)
	)
	(segment
		(start 101.6375 106.243044)
		(end 102.013133 106.618677)
		(width 0.15)
		(layer "In7.Cu")
		(net 15)
	)
	(segment
		(start 118.556956 78.9375)
		(end 117.643044 78.9375)
		(width 0.15)
		(layer "In7.Cu")
		(net 15)
	)
	(segment
		(start 113.456956 80.4375)
		(end 111.956956 81.9375)
		(width 0.15)
		(layer "In7.Cu")
		(net 15)
	)
	(arc
		(start 102.013133 106.618677)
		(mid 102.105505 106.656939)
		(end 102.197877 106.618677)
		(width 0.15)
		(layer "In7.Cu")
		(net 15)
	)
	(arc
		(start 102.445364 106.866165)
		(mid 102.407102 106.958537)
		(end 102.445364 107.050909)
		(width 0.15)
		(layer "In7.Cu")
		(net 15)
	)
	(arc
		(start 102.445363 106.681419)
		(mid 102.483624 106.773792)
		(end 102.445364 106.866165)
		(width 0.15)
		(layer "In7.Cu")
		(net 15)
	)
	(arc
		(start 102.197877 106.618677)
		(mid 102.290249 106.580415)
		(end 102.382621 106.618677)
		(width 0.15)
		(layer "In7.Cu")
		(net 15)
	)
	(segment
		(start 118.695532 76.915)
		(end 118.695532 77.385)
		(width 0.19)
		(layer "F.Cu")
		(net 16)
	)
	(segment
		(start 109.295 128.5)
		(end 108.98 128.815)
		(width 0.19)
		(layer "F.Cu")
		(net 16)
	)
	(segment
		(start 108.98 128.815)
		(end 108.37663 128.815)
		(width 0.19)
		(layer "F.Cu")
		(net 16)
	)
	(segment
		(start 118.430532 76.65)
		(end 118.695532 76.915)
		(width 0.19)
		(layer "F.Cu")
		(net 16)
	)
	(segment
		(start 109.32 128.5)
		(end 109.295 128.5)
		(width 0.19)
		(layer "F.Cu")
		(net 16)
	)
	(segment
		(start 108.37663 128.815)
		(end 103.885 124.32337)
		(width 0.19)
		(layer "F.Cu")
		(net 16)
	)
	(segment
		(start 106.685 116.02337)
		(end 103.885 113.22337)
		(width 0.19)
		(layer "F.Cu")
		(net 16)
	)
	(segment
		(start 106.685 120.27663)
		(end 106.685 116.02337)
		(width 0.19)
		(layer "F.Cu")
		(net 16)
	)
	(segment
		(start 118.695532 77.385)
		(end 118.580532 77.5)
		(width 0.19)
		(layer "F.Cu")
		(net 16)
	)
	(segment
		(start 103.885 106.915)
		(end 104 106.8)
		(width 0.19)
		(layer "F.Cu")
		(net 16)
	)
	(segment
		(start 103.885 113.22337)
		(end 103.885 106.915)
		(width 0.19)
		(layer "F.Cu")
		(net 16)
	)
	(segment
		(start 103.885 123.07663)
		(end 106.685 120.27663)
		(width 0.19)
		(layer "F.Cu")
		(net 16)
	)
	(segment
		(start 103.885 124.32337)
		(end 103.885 123.07663)
		(width 0.19)
		(layer "F.Cu")
		(net 16)
	)
	(via
		(at 118.580532 77.5)
		(size 0.45)
		(drill 0.1)
		(layers "F.Cu" "B.Cu")
		(net 16)
	)
	(via
		(at 104 106.8)
		(size 0.45)
		(drill 0.1)
		(layers "F.Cu" "B.Cu")
		(net 16)
	)
	(segment
		(start 101.3625 91.643044)
		(end 105.043044 87.9625)
		(width 0.15)
		(layer "In7.Cu")
		(net 16)
	)
	(segment
		(start 117.756956 78.6625)
		(end 118.443044 78.6625)
		(width 0.15)
		(layer "In7.Cu")
		(net 16)
	)
	(segment
		(start 104 106.8)
		(end 103.8375 106.9625)
		(width 0.15)
		(layer "In7.Cu")
		(net 16)
	)
	(segment
		(start 102.643044 107.6375)
		(end 101.3625 106.356956)
		(width 0.15)
		(layer "In7.Cu")
		(net 16)
	)
	(segment
		(start 103.8375 106.9625)
		(end 103.8375 107.256956)
		(width 0.15)
		(layer "In7.Cu")
		(net 16)
	)
	(segment
		(start 103.8375 107.256956)
		(end 103.456956 107.6375)
		(width 0.15)
		(layer "In7.Cu")
		(net 16)
	)
	(segment
		(start 101.3625 106.356956)
		(end 101.3625 91.643044)
		(width 0.15)
		(layer "In7.Cu")
		(net 16)
	)
	(segment
		(start 107.5625 86.156956)
		(end 107.5625 85.043044)
		(width 0.15)
		(layer "In7.Cu")
		(net 16)
	)
	(segment
		(start 116.343044 78.3625)
		(end 117.456956 78.3625)
		(width 0.15)
		(layer "In7.Cu")
		(net 16)
	)
	(segment
		(start 111.843044 81.6625)
		(end 113.343044 80.1625)
		(width 0.15)
		(layer "In7.Cu")
		(net 16)
	)
	(segment
		(start 114.543044 80.1625)
		(end 116.343044 78.3625)
		(width 0.15)
		(layer "In7.Cu")
		(net 16)
	)
	(segment
		(start 118.743032 78.362512)
		(end 118.743032 77.6625)
		(width 0.15)
		(layer "In7.Cu")
		(net 16)
	)
	(segment
		(start 113.343044 80.1625)
		(end 114.543044 80.1625)
		(width 0.15)
		(layer "In7.Cu")
		(net 16)
	)
	(segment
		(start 109.543044 83.0625)
		(end 109.943044 83.0625)
		(width 0.15)
		(layer "In7.Cu")
		(net 16)
	)
	(segment
		(start 107.5625 85.043044)
		(end 109.543044 83.0625)
		(width 0.15)
		(layer "In7.Cu")
		(net 16)
	)
	(segment
		(start 111.343044 81.6625)
		(end 111.843044 81.6625)
		(width 0.15)
		(layer "In7.Cu")
		(net 16)
	)
	(segment
		(start 108.1625 87.343044)
		(end 108.1625 86.756956)
		(width 0.15)
		(layer "In7.Cu")
		(net 16)
	)
	(segment
		(start 117.456956 78.3625)
		(end 117.756956 78.6625)
		(width 0.15)
		(layer "In7.Cu")
		(net 16)
	)
	(segment
		(start 118.443044 78.6625)
		(end 118.743032 78.362512)
		(width 0.15)
		(layer "In7.Cu")
		(net 16)
	)
	(segment
		(start 109.943044 83.0625)
		(end 111.343044 81.6625)
		(width 0.15)
		(layer "In7.Cu")
		(net 16)
	)
	(segment
		(start 107.543044 87.9625)
		(end 108.1625 87.343044)
		(width 0.15)
		(layer "In7.Cu")
		(net 16)
	)
	(segment
		(start 118.743032 77.6625)
		(end 118.580532 77.5)
		(width 0.15)
		(layer "In7.Cu")
		(net 16)
	)
	(segment
		(start 105.043044 87.9625)
		(end 107.543044 87.9625)
		(width 0.15)
		(layer "In7.Cu")
		(net 16)
	)
	(segment
		(start 103.456956 107.6375)
		(end 102.643044 107.6375)
		(width 0.15)
		(layer "In7.Cu")
		(net 16)
	)
	(segment
		(start 108.1625 86.756956)
		(end 107.5625 86.156956)
		(width 0.15)
		(layer "In7.Cu")
		(net 16)
	)
	(segment
		(start 148.654391 125.6)
		(end 148.654391 124.84)
		(width 0.5)
		(layer "F.Cu")
		(net 17)
	)
	(segment
		(start 148.114391 129.03)
		(end 148.1 129.015609)
		(width 0.5)
		(layer "F.Cu")
		(net 17)
	)
	(segment
		(start 148.114391 129.03)
		(end 148.114391 131.695)
		(width 0.5)
		(layer "F.Cu")
		(net 17)
	)
	(segment
		(start 148.654391 128.045609)
		(end 148.654391 127.84)
		(width 0.5)
		(layer "F.Cu")
		(net 17)
	)
	(segment
		(start 148.654391 124.84)
		(end 148.644391 124.83)
		(width 0.5)
		(layer "F.Cu")
		(net 17)
	)
	(segment
		(start 148.654391 127.84)
		(end 148.654391 126.46)
		(width 0.5)
		(layer "F.Cu")
		(net 17)
	)
	(segment
		(start 148.654391 126.46)
		(end 148.654391 125.6)
		(width 0.5)
		(layer "F.Cu")
		(net 17)
	)
	(segment
		(start 145.424391 125.43)
		(end 146.08 125.43)
		(width 0.2)
		(layer "F.Cu")
		(net 17)
	)
	(segment
		(start 146.25 125.6)
		(end 148.654391 125.6)
		(width 0.2)
		(layer "F.Cu")
		(net 17)
	)
	(segment
		(start 146.08 125.43)
		(end 146.25 125.6)
		(width 0.2)
		(layer "F.Cu")
		(net 17)
	)
	(segment
		(start 148.114391 131.695)
		(end 147.999391 131.81)
		(width 0.5)
		(layer "F.Cu")
		(net 17)
	)
	(segment
		(start 148.1 128.6)
		(end 148.654391 128.045609)
		(width 0.5)
		(layer "F.Cu")
		(net 17)
	)
	(segment
		(start 148.1 129.015609)
		(end 148.1 128.6)
		(width 0.5)
		(layer "F.Cu")
		(net 17)
	)
	(segment
		(start 179.696 106.174)
		(end 178.92 106.95)
		(width 0.2)
		(layer "F.Cu")
		(net 18)
	)
	(segment
		(start 184.05 110.63)
		(end 184.571 110.109)
		(width 0.2)
		(layer "F.Cu")
		(net 18)
	)
	(segment
		(start 183.670942 106.174)
		(end 179.696 106.174)
		(width 0.2)
		(layer "F.Cu")
		(net 18)
	)
	(segment
		(start 182.94 110.625)
		(end 184.045 110.625)
		(width 0.2)
		(layer "F.Cu")
		(net 18)
	)
	(segment
		(start 184.045 110.625)
		(end 184.05 110.63)
		(width 0.2)
		(layer "F.Cu")
		(net 18)
	)
	(segment
		(start 184.571 107.074058)
		(end 183.670942 106.174)
		(width 0.2)
		(layer "F.Cu")
		(net 18)
	)
	(segment
		(start 184.571 110.109)
		(end 184.571 107.074058)
		(width 0.2)
		(layer "F.Cu")
		(net 18)
	)
	(segment
		(start 183.93 123.681908)
		(end 183.698092 123.45)
		(width 0.15)
		(layer "F.Cu")
		(net 19)
	)
	(segment
		(start 181.824057 123.246356)
		(end 179.257569 123.246356)
		(width 0.15)
		(layer "F.Cu")
		(net 19)
	)
	(segment
		(start 182.94 127.625)
		(end 183.979468 127.625)
		(width 0.15)
		(layer "F.Cu")
		(net 19)
	)
	(segment
		(start 182.027701 123.45)
		(end 181.824057 123.246356)
		(width 0.15)
		(layer "F.Cu")
		(net 19)
	)
	(segment
		(start 183.979468 127.625)
		(end 184.044468 127.69)
		(width 0.15)
		(layer "F.Cu")
		(net 19)
	)
	(segment
		(start 184.540468 127.194)
		(end 184.540468 126.390468)
		(width 0.15)
		(layer "F.Cu")
		(net 19)
	)
	(segment
		(start 184.540468 126.390468)
		(end 183.93 125.78)
		(width 0.15)
		(layer "F.Cu")
		(net 19)
	)
	(segment
		(start 179.257569 123.246356)
		(end 178.666569 123.837356)
		(width 0.15)
		(layer "F.Cu")
		(net 19)
	)
	(segment
		(start 183.93 125.78)
		(end 183.93 123.681908)
		(width 0.15)
		(layer "F.Cu")
		(net 19)
	)
	(segment
		(start 183.698092 123.45)
		(end 182.027701 123.45)
		(width 0.15)
		(layer "F.Cu")
		(net 19)
	)
	(segment
		(start 184.044468 127.69)
		(end 184.540468 127.194)
		(width 0.15)
		(layer "F.Cu")
		(net 19)
	)
	(segment
		(start 179.566 138.354)
		(end 182.763545 138.354)
		(width 0.2)
		(layer "F.Cu")
		(net 20)
	)
	(segment
		(start 182.94 142.625)
		(end 184.019468 142.625)
		(width 0.2)
		(layer "F.Cu")
		(net 20)
	)
	(segment
		(start 182.763545 138.354)
		(end 183.053545 138.064)
		(width 0.2)
		(layer "F.Cu")
		(net 20)
	)
	(segment
		(start 183.610942 138.064)
		(end 184.540468 138.993526)
		(width 0.2)
		(layer "F.Cu")
		(net 20)
	)
	(segment
		(start 178.97 138.95)
		(end 179.566 138.354)
		(width 0.2)
		(layer "F.Cu")
		(net 20)
	)
	(segment
		(start 184.540468 138.993526)
		(end 184.540468 142.149)
		(width 0.2)
		(layer "F.Cu")
		(net 20)
	)
	(segment
		(start 183.053545 138.064)
		(end 183.610942 138.064)
		(width 0.2)
		(layer "F.Cu")
		(net 20)
	)
	(segment
		(start 184.540468 142.149)
		(end 184.019468 142.67)
		(width 0.2)
		(layer "F.Cu")
		(net 20)
	)
	(segment
		(start 196.641532 147.395)
		(end 196.856532 147.18)
		(width 0.19)
		(layer "F.Cu")
		(net 21)
	)
	(segment
		(start 193.946 147.415)
		(end 196.264408 147.415)
		(width 0.19)
		(layer "F.Cu")
		(net 21)
	)
	(segment
		(start 196.264408 147.415)
		(end 196.284408 147.395)
		(width 0.19)
		(layer "F.Cu")
		(net 21)
	)
	(segment
		(start 193.631 147.1)
		(end 193.946 147.415)
		(width 0.19)
		(layer "F.Cu")
		(net 21)
	)
	(segment
		(start 196.856532 147.18)
		(end 197.606532 147.18)
		(width 0.19)
		(layer "F.Cu")
		(net 21)
	)
	(segment
		(start 196.284408 147.395)
		(end 196.641532 147.395)
		(width 0.19)
		(layer "F.Cu")
		(net 21)
	)
	(segment
		(start 193.606 147.1)
		(end 193.631 147.1)
		(width 0.19)
		(layer "F.Cu")
		(net 21)
	)
	(segment
		(start 193.946 147.785)
		(end 196.406 147.785)
		(width 0.19)
		(layer "F.Cu")
		(net 22)
	)
	(segment
		(start 196.426 147.765)
		(end 196.641532 147.765)
		(width 0.19)
		(layer "F.Cu")
		(net 22)
	)
	(segment
		(start 193.631 148.1)
		(end 193.946 147.785)
		(width 0.19)
		(layer "F.Cu")
		(net 22)
	)
	(segment
		(start 193.606 148.1)
		(end 193.631 148.1)
		(width 0.19)
		(layer "F.Cu")
		(net 22)
	)
	(segment
		(start 196.406 147.785)
		(end 196.426 147.765)
		(width 0.19)
		(layer "F.Cu")
		(net 22)
	)
	(segment
		(start 196.641532 147.765)
		(end 196.856532 147.98)
		(width 0.19)
		(layer "F.Cu")
		(net 22)
	)
	(segment
		(start 196.856532 147.98)
		(end 197.606532 147.98)
		(width 0.19)
		(layer "F.Cu")
		(net 22)
	)
	(segment
		(start 183.495 111.975)
		(end 182.94 111.975)
		(width 0.2)
		(layer "F.Cu")
		(net 23)
	)
	(segment
		(start 184.05 112.53)
		(end 183.495 111.975)
		(width 0.2)
		(layer "F.Cu")
		(net 23)
	)
	(segment
		(start 183.485 128.975)
		(end 182.93 128.975)
		(width 0.2)
		(layer "F.Cu")
		(net 24)
	)
	(segment
		(start 184.04 129.53)
		(end 183.485 128.975)
		(width 0.2)
		(layer "F.Cu")
		(net 24)
	)
	(segment
		(start 179.975 108.5)
		(end 179.975 109.06)
		(width 0.2)
		(layer "F.Cu")
		(net 25)
	)
	(segment
		(start 179.855 108.38)
		(end 179.975 108.5)
		(width 0.2)
		(layer "F.Cu")
		(net 25)
	)
	(segment
		(start 179.855 107.916)
		(end 179.855 108.38)
		(width 0.2)
		(layer "F.Cu")
		(net 25)
	)
	(segment
		(start 179.525 108.546)
		(end 178.895 107.916)
		(width 0.2)
		(layer "F.Cu")
		(net 26)
	)
	(segment
		(start 179.525 109.06)
		(end 179.525 108.546)
		(width 0.2)
		(layer "F.Cu")
		(net 26)
	)
	(segment
		(start 194.084408 142.965)
		(end 194.079408 142.96)
		(width 0.19)
		(layer "F.Cu")
		(net 27)
	)
	(segment
		(start 197.606532 143.18)
		(end 196.856532 143.18)
		(width 0.19)
		(layer "F.Cu")
		(net 27)
	)
	(segment
		(start 196.856532 143.18)
		(end 196.641532 142.965)
		(width 0.19)
		(layer "F.Cu")
		(net 27)
	)
	(segment
		(start 196.641532 142.965)
		(end 194.084408 142.965)
		(width 0.19)
		(layer "F.Cu")
		(net 27)
	)
	(segment
		(start 193.946 142.96)
		(end 193.631 143.275)
		(width 0.19)
		(layer "F.Cu")
		(net 27)
	)
	(segment
		(start 194.079408 142.96)
		(end 193.946 142.96)
		(width 0.19)
		(layer "F.Cu")
		(net 27)
	)
	(segment
		(start 179.965 125.5)
		(end 179.965 126.06)
		(width 0.2)
		(layer "F.Cu")
		(net 28)
	)
	(segment
		(start 179.845 125.38)
		(end 179.965 125.5)
		(width 0.2)
		(layer "F.Cu")
		(net 28)
	)
	(segment
		(start 179.845 124.916)
		(end 179.845 125.38)
		(width 0.2)
		(layer "F.Cu")
		(net 28)
	)
	(segment
		(start 179.515 126.06)
		(end 179.515 125.546)
		(width 0.2)
		(layer "F.Cu")
		(net 29)
	)
	(segment
		(start 179.515 125.546)
		(end 178.885 124.916)
		(width 0.2)
		(layer "F.Cu")
		(net 29)
	)
	(segment
		(start 194.226 142.595)
		(end 194.221 142.59)
		(width 0.19)
		(layer "F.Cu")
		(net 30)
	)
	(segment
		(start 197.606532 142.38)
		(end 196.856532 142.38)
		(width 0.19)
		(layer "F.Cu")
		(net 30)
	)
	(segment
		(start 193.946 142.59)
		(end 193.631 142.275)
		(width 0.19)
		(layer "F.Cu")
		(net 30)
	)
	(segment
		(start 194.221 142.59)
		(end 193.946 142.59)
		(width 0.19)
		(layer "F.Cu")
		(net 30)
	)
	(segment
		(start 196.856532 142.38)
		(end 196.641532 142.595)
		(width 0.19)
		(layer "F.Cu")
		(net 30)
	)
	(segment
		(start 196.641532 142.595)
		(end 194.226 142.595)
		(width 0.19)
		(layer "F.Cu")
		(net 30)
	)
	(segment
		(start 140.049 58.4)
		(end 140.049 58.8)
		(width 0.5)
		(layer "F.Cu")
		(net 31)
	)
	(segment
		(start 140.049 58.8)
		(end 140.049 59.431)
		(width 0.5)
		(layer "F.Cu")
		(net 31)
	)
	(segment
		(start 140.83 59.5)
		(end 141.06 59.27)
		(width 0.2)
		(layer "F.Cu")
		(net 31)
	)
	(segment
		(start 139.98 59.5)
		(end 139.98 58.869)
		(width 0.3)
		(layer "F.Cu")
		(net 31)
	)
	(segment
		(start 139.98 59.5)
		(end 140.83 59.5)
		(width 0.2)
		(layer "F.Cu")
		(net 31)
	)
	(segment
		(start 138.5 60.4)
		(end 137.8 59.7)
		(width 0.5)
		(layer "F.Cu")
		(net 31)
	)
	(segment
		(start 137.8 59.7)
		(end 136.4 59.7)
		(width 0.5)
		(layer "F.Cu")
		(net 31)
	)
	(segment
		(start 139.7 60.4)
		(end 138.5 60.4)
		(width 0.5)
		(layer "F.Cu")
		(net 31)
	)
	(segment
		(start 139.98 58.869)
		(end 140.049 58.8)
		(width 0.3)
		(layer "F.Cu")
		(net 31)
	)
	(segment
		(start 141.06 59.27)
		(end 141 59.27)
		(width 0.2)
		(layer "F.Cu")
		(net 31)
	)
	(segment
		(start 139.98 59.5)
		(end 139.98 60.12)
		(width 0.5)
		(layer "F.Cu")
		(net 31)
	)
	(segment
		(start 139.98 60.12)
		(end 139.7 60.4)
		(width 0.5)
		(layer "F.Cu")
		(net 31)
	)
	(segment
		(start 140.049 59.431)
		(end 139.98 59.5)
		(width 0.5)
		(layer "F.Cu")
		(net 31)
	)
	(segment
		(start 145.4 108.1)
		(end 145.4 112.9)
		(width 0.2)
		(layer "F.Cu")
		(net 32)
	)
	(segment
		(start 133.4 90.2)
		(end 145.475 102.275)
		(width 0.2)
		(layer "F.Cu")
		(net 32)
	)
	(segment
		(start 143.1 113.5)
		(end 142.6 114)
		(width 0.2)
		(layer "F.Cu")
		(net 32)
	)
	(segment
		(start 145 137.8)
		(end 145 138.8)
		(width 0.2)
		(layer "F.Cu")
		(net 32)
	)
	(segment
		(start 122 86.2)
		(end 122 85.2)
		(width 0.1)
		(layer "F.Cu")
		(net 32)
	)
	(segment
		(start 148.4 121.7)
		(end 150.6 123.9)
		(width 0.2)
		(layer "F.Cu")
		(net 32)
	)
	(segment
		(start 150.6 123.9)
		(end 150.6 132.6)
		(width 0.2)
		(layer "F.Cu")
		(net 32)
	)
	(segment
		(start 145.475 102.275)
		(end 148.825 102.275)
		(width 0.2)
		(layer "F.Cu")
		(net 32)
	)
	(segment
		(start 145 138.8)
		(end 145.6 139.4)
		(width 0.2)
		(layer "F.Cu")
		(net 32)
	)
	(segment
		(start 148 134.8)
		(end 145 137.8)
		(width 0.2)
		(layer "F.Cu")
		(net 32)
	)
	(segment
		(start 148.6 106.9)
		(end 148.1 107.4)
		(width 0.2)
		(layer "F.Cu")
		(net 32)
	)
	(segment
		(start 122 85.2)
		(end 122.630532 84.569468)
		(width 0.1)
		(layer "F.Cu")
		(net 32)
	)
	(segment
		(start 123.8 90.2)
		(end 133.4 90.2)
		(width 0.2)
		(layer "F.Cu")
		(net 32)
	)
	(segment
		(start 148.6 104.65)
		(end 148.6 106.9)
		(width 0.2)
		(layer "F.Cu")
		(net 32)
	)
	(segment
		(start 122.630532 84.569468)
		(end 122.630532 83.730532)
		(width 0.1)
		(layer "F.Cu")
		(net 32)
	)
	(segment
		(start 122 83.1)
		(end 122 81.819468)
		(width 0.1)
		(layer "F.Cu")
		(net 32)
	)
	(segment
		(start 150.6 132.6)
		(end 148.4 134.8)
		(width 0.2)
		(layer "F.Cu")
		(net 32)
	)
	(segment
		(start 149.4 103.85)
		(end 148.6 104.65)
		(width 0.2)
		(layer "F.Cu")
		(net 32)
	)
	(segment
		(start 148.4 134.8)
		(end 148 134.8)
		(width 0.2)
		(layer "F.Cu")
		(net 32)
	)
	(segment
		(start 148.825 102.275)
		(end 149.4 102.85)
		(width 0.2)
		(layer "F.Cu")
		(net 32)
	)
	(segment
		(start 145.8 121.7)
		(end 148.4 121.7)
		(width 0.2)
		(layer "F.Cu")
		(net 32)
	)
	(segment
		(start 144.8 113.5)
		(end 143.1 113.5)
		(width 0.2)
		(layer "F.Cu")
		(net 32)
	)
	(segment
		(start 122 81.819468)
		(end 121.330532 81.15)
		(width 0.1)
		(layer "F.Cu")
		(net 32)
	)
	(segment
		(start 146.1 107.4)
		(end 145.4 108.1)
		(width 0.2)
		(layer "F.Cu")
		(net 32)
	)
	(segment
		(start 142.6 114)
		(end 142.6 118.5)
		(width 0.2)
		(layer "F.Cu")
		(net 32)
	)
	(segment
		(start 122.630532 83.730532)
		(end 122 83.1)
		(width 0.1)
		(layer "F.Cu")
		(net 32)
	)
	(segment
		(start 122 88.4)
		(end 123.8 90.2)
		(width 0.2)
		(layer "F.Cu")
		(net 32)
	)
	(segment
		(start 122 86.2)
		(end 122 88.4)
		(width 0.2)
		(layer "F.Cu")
		(net 32)
	)
	(segment
		(start 145.6 139.4)
		(end 146.6 139.4)
		(width 0.2)
		(layer "F.Cu")
		(net 32)
	)
	(segment
		(start 142.6 118.5)
		(end 145.8 121.7)
		(width 0.2)
		(layer "F.Cu")
		(net 32)
	)
	(segment
		(start 149.4 102.85)
		(end 149.4 103.85)
		(width 0.2)
		(layer "F.Cu")
		(net 32)
	)
	(segment
		(start 148.1 107.4)
		(end 146.1 107.4)
		(width 0.2)
		(layer "F.Cu")
		(net 32)
	)
	(segment
		(start 145.4 112.9)
		(end 144.8 113.5)
		(width 0.2)
		(layer "F.Cu")
		(net 32)
	)
	(via
		(at 146.6 139.4)
		(size 0.45)
		(drill 0.1)
		(layers "F.Cu" "B.Cu")
		(net 32)
	)
	(segment
		(start 149.6 147.4)
		(end 149.6 145.8)
		(width 0.2)
		(layer "B.Cu")
		(net 32)
	)
	(segment
		(start 148.7 147.701)
		(end 149.299 147.701)
		(width 0.2)
		(layer "B.Cu")
		(net 32)
	)
	(segment
		(start 148.723313 148.635)
		(end 148.723313 147.724313)
		(width 0.2)
		(layer "B.Cu")
		(net 32)
	)
	(segment
		(start 149.2 145.4)
		(end 149.6 145.8)
		(width 0.2)
		(layer "B.Cu")
		(net 32)
	)
	(segment
		(start 149.299 147.701)
		(end 149.6 147.4)
		(width 0.2)
		(layer "B.Cu")
		(net 32)
	)
	(segment
		(start 147.8 146.4)
		(end 148.7 147.3)
		(width 0.2)
		(layer "B.Cu")
		(net 32)
	)
	(segment
		(start 149.2 145.4)
		(end 149.2 142)
		(width 0.2)
		(layer "B.Cu")
		(net 32)
	)
	(segment
		(start 148.7 147.701)
		(end 148.7 147.3)
		(width 0.2)
		(layer "B.Cu")
		(net 32)
	)
	(segment
		(start 147.8 146.4)
		(end 147.8 144.7)
		(width 0.2)
		(layer "B.Cu")
		(net 32)
	)
	(segment
		(start 148.723313 147.724313)
		(end 148.7 147.701)
		(width 0.2)
		(layer "B.Cu")
		(net 32)
	)
	(segment
		(start 149.2 142)
		(end 146.6 139.4)
		(width 0.2)
		(layer "B.Cu")
		(net 32)
	)
	(segment
		(start 112.77 115.93)
		(end 112.9 115.8)
		(width 0.1)
		(layer "B.Cu")
		(net 33)
	)
	(segment
		(start 118.201 97.499)
		(end 121.233 97.499)
		(width 0.1)
		(layer "B.Cu")
		(net 33)
	)
	(segment
		(start 117.7 98)
		(end 118.201 97.499)
		(width 0.1)
		(layer "B.Cu")
		(net 33)
	)
	(segment
		(start 116.6 115.8)
		(end 117.7 114.7)
		(width 0.1)
		(layer "B.Cu")
		(net 33)
	)
	(segment
		(start 117.7 114.7)
		(end 117.7 98)
		(width 0.1)
		(layer "B.Cu")
		(net 33)
	)
	(segment
		(start 112.9 115.8)
		(end 116.6 115.8)
		(width 0.1)
		(layer "B.Cu")
		(net 33)
	)
	(segment
		(start 112.77 116.59)
		(end 112.77 115.93)
		(width 0.1)
		(layer "B.Cu")
		(net 33)
	)
	(segment
		(start 117.4 140.4)
		(end 117.4 133)
		(width 0.1)
		(layer "B.Cu")
		(net 34)
	)
	(segment
		(start 117.4 133)
		(end 118.2 132.2)
		(width 0.1)
		(layer "B.Cu")
		(net 34)
	)
	(segment
		(start 118.2 132.2)
		(end 118.2 122.2)
		(width 0.1)
		(layer "B.Cu")
		(net 34)
	)
	(segment
		(start 118.2 122.2)
		(end 118.89 121.51)
		(width 0.1)
		(layer "B.Cu")
		(net 34)
	)
	(segment
		(start 116.34 141.46)
		(end 117.4 140.4)
		(width 0.1)
		(layer "B.Cu")
		(net 34)
	)
	(segment
		(start 110.015 141.46)
		(end 116.34 141.46)
		(width 0.1)
		(layer "B.Cu")
		(net 34)
	)
	(segment
		(start 118.89 121.51)
		(end 121.209 121.51)
		(width 0.1)
		(layer "B.Cu")
		(net 34)
	)
	(segment
		(start 119.59 124.01)
		(end 121.209 124.01)
		(width 0.1)
		(layer "B.Cu")
		(net 35)
	)
	(segment
		(start 117.8 133.6)
		(end 118.8 132.6)
		(width 0.1)
		(layer "B.Cu")
		(net 35)
	)
	(segment
		(start 118.8 124.8)
		(end 119.59 124.01)
		(width 0.1)
		(layer "B.Cu")
		(net 35)
	)
	(segment
		(start 116.4 142.2)
		(end 117.8 140.8)
		(width 0.1)
		(layer "B.Cu")
		(net 35)
	)
	(segment
		(start 108.555 141.47)
		(end 109.285 142.2)
		(width 0.1)
		(layer "B.Cu")
		(net 35)
	)
	(segment
		(start 109.285 142.2)
		(end 116.4 142.2)
		(width 0.1)
		(layer "B.Cu")
		(net 35)
	)
	(segment
		(start 117.8 140.8)
		(end 117.8 133.6)
		(width 0.1)
		(layer "B.Cu")
		(net 35)
	)
	(segment
		(start 118.8 132.6)
		(end 118.8 124.8)
		(width 0.1)
		(layer "B.Cu")
		(net 35)
	)
	(segment
		(start 168.81 63.97)
		(end 169.91 63.97)
		(width 0.1)
		(layer "F.Cu")
		(net 36)
	)
	(segment
		(start 169.91 63.97)
		(end 169.98 63.9)
		(width 0.1)
		(layer "F.Cu")
		(net 36)
	)
	(via
		(at 170.3 62.5)
		(size 0.45)
		(drill 0.1)
		(layers "F.Cu" "B.Cu")
		(net 37)
	)
	(segment
		(start 172.25 61.75)
		(end 172.25 60.75)
		(width 0.1)
		(layer "B.Cu")
		(net 37)
	)
	(segment
		(start 170.3 62.5)
		(end 171.5 62.5)
		(width 0.1)
		(layer "B.Cu")
		(net 37)
	)
	(segment
		(start 172.25 60.75)
		(end 172.921996 60.078004)
		(width 0.1)
		(layer "B.Cu")
		(net 37)
	)
	(segment
		(start 171.5 62.5)
		(end 172.25 61.75)
		(width 0.1)
		(layer "B.Cu")
		(net 37)
	)
	(segment
		(start 172.921996 60.078004)
		(end 173.248 60.078004)
		(width 0.1)
		(layer "B.Cu")
		(net 37)
	)
	(segment
		(start 173.17 63.9)
		(end 173.24 63.97)
		(width 0.1)
		(layer "F.Cu")
		(net 38)
	)
	(segment
		(start 172.1 63.9)
		(end 173.17 63.9)
		(width 0.1)
		(layer "F.Cu")
		(net 38)
	)
	(via
		(at 172.25 62.5)
		(size 0.45)
		(drill 0.1)
		(layers "F.Cu" "B.Cu")
		(net 39)
	)
	(segment
		(start 173.248 62.385002)
		(end 172.364998 62.385002)
		(width 0.1)
		(layer "B.Cu")
		(net 39)
	)
	(segment
		(start 172.364998 62.385002)
		(end 172.25 62.5)
		(width 0.1)
		(layer "B.Cu")
		(net 39)
	)
	(segment
		(start 217.23587 132.4975)
		(end 217.9675 132.4975)
		(width 0.19)
		(layer "F.Cu")
		(net 40)
	)
	(segment
		(start 211.142 128.099)
		(end 211.900401 128.099)
		(width 0.19)
		(layer "F.Cu")
		(net 40)
	)
	(segment
		(start 218.295 132.825)
		(end 218.32 132.825)
		(width 0.19)
		(layer "F.Cu")
		(net 40)
	)
	(segment
		(start 216.415 131.67663)
		(end 217.23587 132.4975)
		(width 0.19)
		(layer "F.Cu")
		(net 40)
	)
	(segment
		(start 216.415 130.47663)
		(end 216.415 131.67663)
		(width 0.19)
		(layer "F.Cu")
		(net 40)
	)
	(segment
		(start 212.02287 128.0845)
		(end 212.32337 128.385)
		(width 0.19)
		(layer "F.Cu")
		(net 40)
	)
	(segment
		(start 217.9675 132.4975)
		(end 218.295 132.825)
		(width 0.19)
		(layer "F.Cu")
		(net 40)
	)
	(segment
		(start 214.32337 128.385)
		(end 216.415 130.47663)
		(width 0.19)
		(layer "F.Cu")
		(net 40)
	)
	(segment
		(start 211.914901 128.0845)
		(end 212.02287 128.0845)
		(width 0.19)
		(layer "F.Cu")
		(net 40)
	)
	(segment
		(start 212.32337 128.385)
		(end 214.32337 128.385)
		(width 0.19)
		(layer "F.Cu")
		(net 40)
	)
	(segment
		(start 211.900401 128.099)
		(end 211.914901 128.0845)
		(width 0.19)
		(layer "F.Cu")
		(net 40)
	)
	(segment
		(start 216.50837 126.37)
		(end 214.72337 124.585)
		(width 0.19)
		(layer "F.Cu")
		(net 41)
	)
	(segment
		(start 217.89 126.37)
		(end 216.50837 126.37)
		(width 0.19)
		(layer "F.Cu")
		(net 41)
	)
	(segment
		(start 212.43837 124.5)
		(end 212.52337 124.585)
		(width 0.19)
		(layer "F.Cu")
		(net 41)
	)
	(segment
		(start 214.72337 124.585)
		(end 212.52337 124.585)
		(width 0.19)
		(layer "F.Cu")
		(net 41)
	)
	(segment
		(start 211.142 124.5)
		(end 212.43837 124.5)
		(width 0.19)
		(layer "F.Cu")
		(net 41)
	)
	(segment
		(start 218.22 126.7)
		(end 217.89 126.37)
		(width 0.19)
		(layer "F.Cu")
		(net 41)
	)
	(segment
		(start 153.728999 112.25)
		(end 154.35 112.25)
		(width 0.1)
		(layer "F.Cu")
		(net 42)
	)
	(segment
		(start 155.5 112.9)
		(end 155.8 113.2)
		(width 0.1)
		(layer "F.Cu")
		(net 42)
	)
	(segment
		(start 155.5 112.5)
		(end 155.5 112.9)
		(width 0.1)
		(layer "F.Cu")
		(net 42)
	)
	(segment
		(start 155.2 112.2)
		(end 155.5 112.5)
		(width 0.1)
		(layer "F.Cu")
		(net 42)
	)
	(segment
		(start 154.35 112.25)
		(end 154.4 112.2)
		(width 0.1)
		(layer "F.Cu")
		(net 42)
	)
	(segment
		(start 155.8 113.2)
		(end 156.24 113.2)
		(width 0.1)
		(layer "F.Cu")
		(net 42)
	)
	(segment
		(start 154.4 112.2)
		(end 155.2 112.2)
		(width 0.1)
		(layer "F.Cu")
		(net 42)
	)
	(via
		(at 141.2 115.2)
		(size 0.45)
		(drill 0.1)
		(layers "F.Cu" "B.Cu")
		(net 42)
	)
	(via
		(at 154.4 112.2)
		(size 0.45)
		(drill 0.1)
		(layers "F.Cu" "B.Cu")
		(net 42)
	)
	(via
		(at 140.3 62.5)
		(size 0.45)
		(drill 0.1)
		(layers "F.Cu" "B.Cu")
		(net 42)
	)
	(via
		(at 148.1 63.3)
		(size 0.45)
		(drill 0.1)
		(layers "F.Cu" "B.Cu")
		(net 42)
	)
	(via
		(at 150.4 70.8)
		(size 0.45)
		(drill 0.1)
		(layers "F.Cu" "B.Cu")
		(net 42)
	)
	(segment
		(start 140.2 61.277)
		(end 140.2 61.7)
		(width 0.1)
		(layer "B.Cu")
		(net 42)
	)
	(segment
		(start 140.3 61.8)
		(end 140.3 62.5)
		(width 0.1)
		(layer "B.Cu")
		(net 42)
	)
	(segment
		(start 148.1 63.3)
		(end 148.1 68)
		(width 0.1)
		(layer "B.Cu")
		(net 42)
	)
	(segment
		(start 148.1 68)
		(end 150.4 70.3)
		(width 0.1)
		(layer "B.Cu")
		(net 42)
	)
	(segment
		(start 150.4 70.3)
		(end 150.4 70.8)
		(width 0.1)
		(layer "B.Cu")
		(net 42)
	)
	(segment
		(start 148.13 59.97)
		(end 148.13 60.525)
		(width 0.1)
		(layer "B.Cu")
		(net 42)
	)
	(segment
		(start 140.2 61.277)
		(end 140.2 60.505)
		(width 0.1)
		(layer "B.Cu")
		(net 42)
	)
	(segment
		(start 148.13 63.27)
		(end 148.1 63.3)
		(width 0.1)
		(layer "B.Cu")
		(net 42)
	)
	(segment
		(start 148.63 59.47)
		(end 148.13 59.97)
		(width 0.1)
		(layer "B.Cu")
		(net 42)
	)
	(segment
		(start 148.63 58.98)
		(end 148.63 59.47)
		(width 0.1)
		(layer "B.Cu")
		(net 42)
	)
	(segment
		(start 148.13 61.297)
		(end 148.13 60.525)
		(width 0.1)
		(layer "B.Cu")
		(net 42)
	)
	(segment
		(start 140.63 59.47)
		(end 140.63 58.98)
		(width 0.1)
		(layer "B.Cu")
		(net 42)
	)
	(segment
		(start 140.2 61.7)
		(end 140.3 61.8)
		(width 0.1)
		(layer "B.Cu")
		(net 42)
	)
	(segment
		(start 148.13 61.297)
		(end 148.13 63.27)
		(width 0.1)
		(layer "B.Cu")
		(net 42)
	)
	(segment
		(start 140.2 60.505)
		(end 140.2 59.9)
		(width 0.1)
		(layer "B.Cu")
		(net 42)
	)
	(segment
		(start 140.2 59.9)
		(end 140.63 59.47)
		(width 0.1)
		(layer "B.Cu")
		(net 42)
	)
	(segment
		(start 150.4 70.8)
		(end 150.4 82.965686)
		(width 0.1)
		(layer "In5.Cu")
		(net 42)
	)
	(segment
		(start 141.5 100.475)
		(end 141 100.975)
		(width 0.1)
		(layer "In5.Cu")
		(net 42)
	)
	(segment
		(start 141 115)
		(end 141.2 115.2)
		(width 0.1)
		(layer "In5.Cu")
		(net 42)
	)
	(segment
		(start 144.844255 88.224)
		(end 144.624 88.444255)
		(width 0.1)
		(layer "In5.Cu")
		(net 42)
	)
	(segment
		(start 141.275 93.640685)
		(end 141 93.915685)
		(width 0.1)
		(layer "In5.Cu")
		(net 42)
	)
	(segment
		(start 150.4 82.965686)
		(end 145.141685 88.224)
		(width 0.1)
		(layer "In5.Cu")
		(net 42)
	)
	(segment
		(start 147.3 63.3)
		(end 148.1 63.3)
		(width 0.1)
		(layer "In5.Cu")
		(net 42)
	)
	(segment
		(start 145.9 61.9)
		(end 147.3 63.3)
		(width 0.1)
		(layer "In5.Cu")
		(net 42)
	)
	(segment
		(start 140.3 62.5)
		(end 140.9 61.9)
		(width 0.1)
		(layer "In5.Cu")
		(net 42)
	)
	(segment
		(start 141.5 98.976471)
		(end 141.5 100.475)
		(width 0.1)
		(layer "In5.Cu")
		(net 42)
	)
	(segment
		(start 141.275 93.075)
		(end 141.275 93.640685)
		(width 0.1)
		(layer "In5.Cu")
		(net 42)
	)
	(segment
		(start 140.9 61.9)
		(end 145.9 61.9)
		(width 0.1)
		(layer "In5.Cu")
		(net 42)
	)
	(segment
		(start 141 100.975)
		(end 141 115)
		(width 0.1)
		(layer "In5.Cu")
		(net 42)
	)
	(segment
		(start 144.624 89.726)
		(end 141.275 93.075)
		(width 0.1)
		(layer "In5.Cu")
		(net 42)
	)
	(segment
		(start 144.624 88.444255)
		(end 144.624 89.726)
		(width 0.1)
		(layer "In5.Cu")
		(net 42)
	)
	(segment
		(start 141 98.476471)
		(end 141.5 98.976471)
		(width 0.1)
		(layer "In5.Cu")
		(net 42)
	)
	(segment
		(start 145.141685 88.224)
		(end 144.844255 88.224)
		(width 0.1)
		(layer "In5.Cu")
		(net 42)
	)
	(segment
		(start 141 93.915685)
		(end 141 98.476471)
		(width 0.1)
		(layer "In5.Cu")
		(net 42)
	)
	(segment
		(start 149.2 115.2)
		(end 152.2 112.2)
		(width 0.1)
		(layer "In7.Cu")
		(net 42)
	)
	(segment
		(start 152.2 112.2)
		(end 154.4 112.2)
		(width 0.1)
		(layer "In7.Cu")
		(net 42)
	)
	(segment
		(start 141.2 115.2)
		(end 149.2 115.2)
		(width 0.1)
		(layer "In7.Cu")
		(net 42)
	)
	(segment
		(start 155.1 113.5)
		(end 155.8 114.2)
		(width 0.1)
		(layer "F.Cu")
		(net 43)
	)
	(segment
		(start 154.256 112.744)
		(end 154.4 112.6)
		(width 0.1)
		(layer "F.Cu")
		(net 43)
	)
	(segment
		(start 155.8 114.2)
		(end 156.24 114.2)
		(width 0.1)
		(layer "F.Cu")
		(net 43)
	)
	(segment
		(start 154.8 112.6)
		(end 155.1 112.9)
		(width 0.1)
		(layer "F.Cu")
		(net 43)
	)
	(segment
		(start 155.1 112.9)
		(end 155.1 113.5)
		(width 0.1)
		(layer "F.Cu")
		(net 43)
	)
	(segment
		(start 153.729 112.744)
		(end 154.256 112.744)
		(width 0.1)
		(layer "F.Cu")
		(net 43)
	)
	(segment
		(start 154.4 112.6)
		(end 154.8 112.6)
		(width 0.1)
		(layer "F.Cu")
		(net 43)
	)
	(via
		(at 154.8 112.6)
		(size 0.45)
		(drill 0.1)
		(layers "F.Cu" "B.Cu")
		(net 43)
	)
	(via
		(at 140.4 115.2)
		(size 0.45)
		(drill 0.1)
		(layers "F.Cu" "B.Cu")
		(net 43)
	)
	(via
		(at 149.9 70.4)
		(size 0.45)
		(drill 0.1)
		(layers "F.Cu" "B.Cu")
		(net 43)
	)
	(via
		(at 147.6 62.8)
		(size 0.45)
		(drill 0.1)
		(layers "F.Cu" "B.Cu")
		(net 43)
	)
	(via
		(at 139.8 62.2)
		(size 0.45)
		(drill 0.1)
		(layers "F.Cu" "B.Cu")
		(net 43)
	)
	(segment
		(start 149.4 70.4)
		(end 147.6 68.6)
		(width 0.1)
		(layer "B.Cu")
		(net 43)
	)
	(segment
		(start 139.7 61.277)
		(end 139.7 62.1)
		(width 0.1)
		(layer "B.Cu")
		(net 43)
	)
	(segment
		(start 147.6 68.6)
		(end 147.6 62.8)
		(width 0.1)
		(layer "B.Cu")
		(net 43)
	)
	(segment
		(start 147.63 61.297)
		(end 147.63 60.525)
		(width 0.1)
		(layer "B.Cu")
		(net 43)
	)
	(segment
		(start 149.9 70.4)
		(end 149.4 70.4)
		(width 0.1)
		(layer "B.Cu")
		(net 43)
	)
	(segment
		(start 147.63 60.525)
		(end 147.63 58.98)
		(width 0.1)
		(layer "B.Cu")
		(net 43)
	)
	(segment
		(start 139.7 60.505)
		(end 139.7 59.05)
		(width 0.1)
		(layer "B.Cu")
		(net 43)
	)
	(segment
		(start 139.7 59.05)
		(end 139.63 58.98)
		(width 0.1)
		(layer "B.Cu")
		(net 43)
	)
	(segment
		(start 147.63 61.297)
		(end 147.6 61.327)
		(width 0.1)
		(layer "B.Cu")
		(net 43)
	)
	(segment
		(start 139.7 62.1)
		(end 139.8 62.2)
		(width 0.1)
		(layer "B.Cu")
		(net 43)
	)
	(segment
		(start 147.6 61.327)
		(end 147.6 62.8)
		(width 0.1)
		(layer "B.Cu")
		(net 43)
	)
	(segment
		(start 139.7 61.277)
		(end 139.7 60.505)
		(width 0.1)
		(layer "B.Cu")
		(net 43)
	)
	(segment
		(start 141.257843 99.967157)
		(end 140.5 100.725)
		(width 0.1)
		(layer "In5.Cu")
		(net 43)
	)
	(segment
		(start 140.775 93.2)
		(end 140.775 98.534314)
		(width 0.1)
		(layer "In5.Cu")
		(net 43)
	)
	(segment
		(start 140.5 100.725)
		(end 140.5 115.1)
		(width 0.1)
		(layer "In5.Cu")
		(net 43)
	)
	(segment
		(start 147.6 61.6)
		(end 147.6 62.8)
		(width 0.1)
		(layer "In5.Cu")
		(net 43)
	)
	(segment
		(start 149.9 70.4)
		(end 149.5 70.8)
		(width 0.1)
		(layer "In5.Cu")
		(net 43)
	)
	(segment
		(start 144.424 88.361412)
		(end 144.424 88.433843)
		(width 0.1)
		(layer "In5.Cu")
		(net 43)
	)
	(segment
		(start 149.5 83.15)
		(end 145.85 86.8)
		(width 0.1)
		(layer "In5.Cu")
		(net 43)
	)
	(segment
		(start 144.761412 88.024)
		(end 144.424 88.361412)
		(width 0.1)
		(layer "In5.Cu")
		(net 43)
	)
	(segment
		(start 139.8 62.2)
		(end 140.55 61.45)
		(width 0.1)
		(layer "In5.Cu")
		(net 43)
	)
	(segment
		(start 140.55 61.45)
		(end 147.45 61.45)
		(width 0.1)
		(layer "In5.Cu")
		(net 43)
	)
	(segment
		(start 141.3 99.365686)
		(end 141.257843 99.407843)
		(width 0.1)
		(layer "In5.Cu")
		(net 43)
	)
	(segment
		(start 144.424 88.433843)
		(end 144.4 88.457843)
		(width 0.1)
		(layer "In5.Cu")
		(net 43)
	)
	(segment
		(start 144.4 89.575)
		(end 140.775 93.2)
		(width 0.1)
		(layer "In5.Cu")
		(net 43)
	)
	(segment
		(start 141.3 99.059314)
		(end 141.3 99.365686)
		(width 0.1)
		(layer "In5.Cu")
		(net 43)
	)
	(segment
		(start 145.85 86.8)
		(end 145.85 87.232842)
		(width 0.1)
		(layer "In5.Cu")
		(net 43)
	)
	(segment
		(start 141.257843 99.407843)
		(end 141.257843 99.967157)
		(width 0.1)
		(layer "In5.Cu")
		(net 43)
	)
	(segment
		(start 147.45 61.45)
		(end 147.6 61.6)
		(width 0.1)
		(layer "In5.Cu")
		(net 43)
	)
	(segment
		(start 144.4 88.457843)
		(end 144.4 89.575)
		(width 0.1)
		(layer "In5.Cu")
		(net 43)
	)
	(segment
		(start 145.85 87.232842)
		(end 145.058842 88.024)
		(width 0.1)
		(layer "In5.Cu")
		(net 43)
	)
	(segment
		(start 145.058842 88.024)
		(end 144.761412 88.024)
		(width 0.1)
		(layer "In5.Cu")
		(net 43)
	)
	(segment
		(start 140.5 115.1)
		(end 140.4 115.2)
		(width 0.1)
		(layer "In5.Cu")
		(net 43)
	)
	(segment
		(start 149.5 70.8)
		(end 149.5 83.15)
		(width 0.1)
		(layer "In5.Cu")
		(net 43)
	)
	(segment
		(start 140.775 98.534314)
		(end 141.3 99.059314)
		(width 0.1)
		(layer "In5.Cu")
		(net 43)
	)
	(segment
		(start 140.8 115.6)
		(end 149.4 115.6)
		(width 0.1)
		(layer "In7.Cu")
		(net 43)
	)
	(segment
		(start 152.4 112.6)
		(end 154.8 112.6)
		(width 0.1)
		(layer "In7.Cu")
		(net 43)
	)
	(segment
		(start 140.4 115.2)
		(end 140.8 115.6)
		(width 0.1)
		(layer "In7.Cu")
		(net 43)
	)
	(segment
		(start 149.4 115.6)
		(end 152.4 112.6)
		(width 0.1)
		(layer "In7.Cu")
		(net 43)
	)
	(segment
		(start 217.9675 132.1275)
		(end 218.295 131.8)
		(width 0.19)
		(layer "F.Cu")
		(net 44)
	)
	(segment
		(start 212.47663 128.015)
		(end 214.47663 128.015)
		(width 0.19)
		(layer "F.Cu")
		(net 44)
	)
	(segment
		(start 211.142 127.7)
		(end 211.900401 127.7)
		(width 0.19)
		(layer "F.Cu")
		(net 44)
	)
	(segment
		(start 212.17613 127.7145)
		(end 212.47663 128.015)
		(width 0.19)
		(layer "F.Cu")
		(net 44)
	)
	(segment
		(start 211.900401 127.7)
		(end 211.914901 127.7145)
		(width 0.19)
		(layer "F.Cu")
		(net 44)
	)
	(segment
		(start 218.295 131.8)
		(end 218.32 131.8)
		(width 0.19)
		(layer "F.Cu")
		(net 44)
	)
	(segment
		(start 217.38913 132.1275)
		(end 217.9675 132.1275)
		(width 0.19)
		(layer "F.Cu")
		(net 44)
	)
	(segment
		(start 211.914901 127.7145)
		(end 212.17613 127.7145)
		(width 0.19)
		(layer "F.Cu")
		(net 44)
	)
	(segment
		(start 216.785 130.32337)
		(end 216.785 131.52337)
		(width 0.19)
		(layer "F.Cu")
		(net 44)
	)
	(segment
		(start 216.785 131.52337)
		(end 217.38913 132.1275)
		(width 0.19)
		(layer "F.Cu")
		(net 44)
	)
	(segment
		(start 214.47663 128.015)
		(end 216.785 130.32337)
		(width 0.19)
		(layer "F.Cu")
		(net 44)
	)
	(segment
		(start 208.638553 116.523076)
		(end 208.97663 116.185)
		(width 0.19)
		(layer "F.Cu")
		(net 45)
	)
	(segment
		(start 208.465 117.983257)
		(end 208.56965 117.983257)
		(width 0.19)
		(layer "F.Cu")
		(net 45)
	)
	(segment
		(start 218.0025 118.5875)
		(end 218.315 118.9)
		(width 0.19)
		(layer "F.Cu")
		(net 45)
	)
	(segment
		(start 208.285 117.353257)
		(end 208.285 116.87663)
		(width 0.19)
		(layer "F.Cu")
		(net 45)
	)
	(segment
		(start 208.285 116.87663)
		(end 208.638553 116.523076)
		(width 0.19)
		(layer "F.Cu")
		(net 45)
	)
	(segment
		(start 208.1385 119.137099)
		(end 208.1385 118.8)
		(width 0.19)
		(layer "F.Cu")
		(net 45)
	)
	(segment
		(start 208.97663 116.185)
		(end 211.22337 116.185)
		(width 0.19)
		(layer "F.Cu")
		(net 45)
	)
	(segment
		(start 208.56965 117.533257)
		(end 208.465 117.533257)
		(width 0.19)
		(layer "F.Cu")
		(net 45)
	)
	(segment
		(start 208.154 119.152599)
		(end 208.1385 119.137099)
		(width 0.19)
		(layer "F.Cu")
		(net 45)
	)
	(segment
		(start 208.74965 117.803257)
		(end 208.74965 117.713257)
		(width 0.19)
		(layer "F.Cu")
		(net 45)
	)
	(segment
		(start 208.1385 118.8)
		(end 208.285 118.6535)
		(width 0.19)
		(layer "F.Cu")
		(net 45)
	)
	(segment
		(start 213.62587 118.5875)
		(end 218.0025 118.5875)
		(width 0.19)
		(layer "F.Cu")
		(net 45)
	)
	(segment
		(start 211.22337 116.185)
		(end 213.62587 118.5875)
		(width 0.19)
		(layer "F.Cu")
		(net 45)
	)
	(segment
		(start 208.154 119.911)
		(end 208.154 119.152599)
		(width 0.19)
		(layer "F.Cu")
		(net 45)
	)
	(segment
		(start 208.285 118.6535)
		(end 208.285 118.163257)
		(width 0.19)
		(layer "F.Cu")
		(net 45)
	)
	(arc
		(start 208.465 117.533257)
		(mid 208.337721 117.480536)
		(end 208.285 117.353257)
		(width 0.19)
		(layer "F.Cu")
		(net 45)
	)
	(arc
		(start 208.285 118.163257)
		(mid 208.337721 118.035978)
		(end 208.465 117.983257)
		(width 0.19)
		(layer "F.Cu")
		(net 45)
	)
	(arc
		(start 208.56965 117.983257)
		(mid 208.696929 117.930536)
		(end 208.74965 117.803257)
		(width 0.19)
		(layer "F.Cu")
		(net 45)
	)
	(arc
		(start 208.74965 117.713257)
		(mid 208.696929 117.585978)
		(end 208.56965 117.533257)
		(width 0.19)
		(layer "F.Cu")
		(net 45)
	)
	(via
		(at 177.5 56.05)
		(size 0.45)
		(drill 0.1)
		(layers "F.Cu" "B.Cu")
		(net 46)
	)
	(segment
		(start 177.5 56)
		(end 177.5 57.02)
		(width 0.1)
		(layer "B.Cu")
		(net 46)
	)
	(segment
		(start 89.15 83.15)
		(end 89.3 83)
		(width 0.1)
		(layer "F.Cu")
		(net 47)
	)
	(segment
		(start 89.3 83)
		(end 89.3 82.95)
		(width 0.1)
		(layer "F.Cu")
		(net 47)
	)
	(segment
		(start 89.7 84.05)
		(end 89.15 83.5)
		(width 0.1)
		(layer "F.Cu")
		(net 47)
	)
	(segment
		(start 108.75 66.442157)
		(end 108.75 67.15)
		(width 0.1)
		(layer "F.Cu")
		(net 47)
	)
	(segment
		(start 108.75 67.15)
		(end 107.05 68.85)
		(width 0.1)
		(layer "F.Cu")
		(net 47)
	)
	(segment
		(start 89.45 82.5)
		(end 90.130532 81.819468)
		(width 0.1)
		(layer "F.Cu")
		(net 47)
	)
	(segment
		(start 89.3 82.95)
		(end 89.45 82.8)
		(width 0.1)
		(layer "F.Cu")
		(net 47)
	)
	(segment
		(start 102 68.85)
		(end 100.8 70.05)
		(width 0.1)
		(layer "F.Cu")
		(net 47)
	)
	(segment
		(start 89.15 83.5)
		(end 89.15 83.15)
		(width 0.1)
		(layer "F.Cu")
		(net 47)
	)
	(segment
		(start 107.05 68.85)
		(end 102 68.85)
		(width 0.1)
		(layer "F.Cu")
		(net 47)
	)
	(segment
		(start 89.45 82.8)
		(end 89.45 82.5)
		(width 0.1)
		(layer "F.Cu")
		(net 47)
	)
	(segment
		(start 99 69.45)
		(end 96.95 69.45)
		(width 0.1)
		(layer "F.Cu")
		(net 47)
	)
	(segment
		(start 89.5 86.05)
		(end 89.5 85.25)
		(width 0.1)
		(layer "F.Cu")
		(net 47)
	)
	(segment
		(start 90.130532 81.819468)
		(end 90.130532 81.15)
		(width 0.1)
		(layer "F.Cu")
		(net 47)
	)
	(segment
		(start 89.7 85.05)
		(end 89.7 84.05)
		(width 0.1)
		(layer "F.Cu")
		(net 47)
	)
	(segment
		(start 99.6 70.05)
		(end 99 69.45)
		(width 0.1)
		(layer "F.Cu")
		(net 47)
	)
	(segment
		(start 100.8 70.05)
		(end 99.6 70.05)
		(width 0.1)
		(layer "F.Cu")
		(net 47)
	)
	(segment
		(start 89.5 85.25)
		(end 89.7 85.05)
		(width 0.1)
		(layer "F.Cu")
		(net 47)
	)
	(via
		(at 122.55 65.2)
		(size 0.45)
		(drill 0.1)
		(layers "F.Cu" "B.Cu")
		(net 47)
	)
	(via
		(at 108.75 66.442157)
		(size 0.45)
		(drill 0.1)
		(layers "F.Cu" "B.Cu")
		(net 47)
	)
	(via
		(at 198 67.5)
		(size 0.45)
		(drill 0.1)
		(layers "F.Cu" "B.Cu")
		(net 47)
	)
	(via
		(at 89.5 86.05)
		(size 0.45)
		(drill 0.1)
		(layers "F.Cu" "B.Cu")
		(net 47)
	)
	(via
		(at 96.95 69.45)
		(size 0.45)
		(drill 0.1)
		(layers "F.Cu" "B.Cu")
		(net 47)
	)
	(segment
		(start 89.5 86.05)
		(end 89.35 86.2)
		(width 0.1)
		(layer "B.Cu")
		(net 47)
	)
	(segment
		(start 95.05 71.5)
		(end 94.55 71)
		(width 0.1)
		(layer "B.Cu")
		(net 47)
	)
	(segment
		(start 94.55 71)
		(end 94.55 70.2)
		(width 0.1)
		(layer "B.Cu")
		(net 47)
	)
	(segment
		(start 87.5 84.7)
		(end 87.5 82.3)
		(width 0.1)
		(layer "B.Cu")
		(net 47)
	)
	(segment
		(start 90.55 75.75)
		(end 92.15 74.15)
		(width 0.1)
		(layer "B.Cu")
		(net 47)
	)
	(segment
		(start 110.33 66.05)
		(end 109.142157 66.05)
		(width 0.1)
		(layer "B.Cu")
		(net 47)
	)
	(segment
		(start 89 86.2)
		(end 87.5 84.7)
		(width 0.1)
		(layer "B.Cu")
		(net 47)
	)
	(segment
		(start 198.5 67.5)
		(end 198.65 67.35)
		(width 0.1)
		(layer "B.Cu")
		(net 47)
	)
	(segment
		(start 95.05 72.85)
		(end 95.05 71.5)
		(width 0.1)
		(layer "B.Cu")
		(net 47)
	)
	(segment
		(start 90.9 80.2)
		(end 90.9 79.05)
		(width 0.1)
		(layer "B.Cu")
		(net 47)
	)
	(segment
		(start 109.142157 66.05)
		(end 108.75 66.442157)
		(width 0.1)
		(layer "B.Cu")
		(net 47)
	)
	(segment
		(start 121.79 64.44)
		(end 111.94 64.44)
		(width 0.1)
		(layer "B.Cu")
		(net 47)
	)
	(segment
		(start 93.75 74.15)
		(end 95.05 72.85)
		(width 0.1)
		(layer "B.Cu")
		(net 47)
	)
	(segment
		(start 89.1 80.7)
		(end 90.4 80.7)
		(width 0.1)
		(layer "B.Cu")
		(net 47)
	)
	(segment
		(start 90.55 78.7)
		(end 90.55 75.75)
		(width 0.1)
		(layer "B.Cu")
		(net 47)
	)
	(segment
		(start 95.3 69.45)
		(end 96.95 69.45)
		(width 0.1)
		(layer "B.Cu")
		(net 47)
	)
	(segment
		(start 198 67.5)
		(end 198.5 67.5)
		(width 0.1)
		(layer "B.Cu")
		(net 47)
	)
	(segment
		(start 111.94 64.44)
		(end 110.33 66.05)
		(width 0.1)
		(layer "B.Cu")
		(net 47)
	)
	(segment
		(start 90.9 79.05)
		(end 90.55 78.7)
		(width 0.1)
		(layer "B.Cu")
		(net 47)
	)
	(segment
		(start 89.35 86.2)
		(end 89 86.2)
		(width 0.1)
		(layer "B.Cu")
		(net 47)
	)
	(segment
		(start 122.55 65.2)
		(end 121.79 64.44)
		(width 0.1)
		(layer "B.Cu")
		(net 47)
	)
	(segment
		(start 92.15 74.15)
		(end 93.75 74.15)
		(width 0.1)
		(layer "B.Cu")
		(net 47)
	)
	(segment
		(start 198.65 67.35)
		(end 198.65 66.85)
		(width 0.1)
		(layer "B.Cu")
		(net 47)
	)
	(segment
		(start 90.4 80.7)
		(end 90.9 80.2)
		(width 0.1)
		(layer "B.Cu")
		(net 47)
	)
	(segment
		(start 94.55 70.2)
		(end 95.3 69.45)
		(width 0.1)
		(layer "B.Cu")
		(net 47)
	)
	(segment
		(start 87.5 82.3)
		(end 89.1 80.7)
		(width 0.1)
		(layer "B.Cu")
		(net 47)
	)
	(segment
		(start 203.72 62)
		(end 205.05 60.67)
		(width 0.1)
		(layer "In5.Cu")
		(net 47)
	)
	(segment
		(start 217.57 55.56)
		(end 216.74 54.73)
		(width 0.1)
		(layer "In5.Cu")
		(net 47)
	)
	(segment
		(start 198.7 65.7)
		(end 198.7 63)
		(width 0.1)
		(layer "In5.Cu")
		(net 47)
	)
	(segment
		(start 212.03 54.73)
		(end 211.33 55.43)
		(width 0.1)
		(layer "In5.Cu")
		(net 47)
	)
	(segment
		(start 159.2 62.75)
		(end 154.65 67.3)
		(width 0.1)
		(layer "In5.Cu")
		(net 47)
	)
	(segment
		(start 217.57 57.01)
		(end 217.57 55.56)
		(width 0.1)
		(layer "In5.Cu")
		(net 47)
	)
	(segment
		(start 208.35 60.67)
		(end 209.69 59.33)
		(width 0.1)
		(layer "In5.Cu")
		(net 47)
	)
	(segment
		(start 209.69 59.33)
		(end 215.25 59.33)
		(width 0.1)
		(layer "In5.Cu")
		(net 47)
	)
	(segment
		(start 198 67.5)
		(end 198 66.4)
		(width 0.1)
		(layer "In5.Cu")
		(net 47)
	)
	(segment
		(start 215.25 59.33)
		(end 217.57 57.01)
		(width 0.1)
		(layer "In5.Cu")
		(net 47)
	)
	(segment
		(start 122.95 65.6)
		(end 122.55 65.2)
		(width 0.1)
		(layer "In5.Cu")
		(net 47)
	)
	(segment
		(start 198.7 63)
		(end 199.7 62)
		(width 0.1)
		(layer "In5.Cu")
		(net 47)
	)
	(segment
		(start 154.65 67.3)
		(end 149.65 67.3)
		(width 0.1)
		(layer "In5.Cu")
		(net 47)
	)
	(segment
		(start 199.7 62)
		(end 203.72 62)
		(width 0.1)
		(layer "In5.Cu")
		(net 47)
	)
	(segment
		(start 145.85 63.5)
		(end 126.050002 63.5)
		(width 0.1)
		(layer "In5.Cu")
		(net 47)
	)
	(segment
		(start 205.05 60.67)
		(end 208.35 60.67)
		(width 0.1)
		(layer "In5.Cu")
		(net 47)
	)
	(segment
		(start 198.56 57)
		(end 193.985788 57)
		(width 0.1)
		(layer "In5.Cu")
		(net 47)
	)
	(segment
		(start 190.185788 60.8)
		(end 171 60.8)
		(width 0.1)
		(layer "In5.Cu")
		(net 47)
	)
	(segment
		(start 198 66.4)
		(end 198.7 65.7)
		(width 0.1)
		(layer "In5.Cu")
		(net 47)
	)
	(segment
		(start 123.950002 65.6)
		(end 122.95 65.6)
		(width 0.1)
		(layer "In5.Cu")
		(net 47)
	)
	(segment
		(start 216.74 54.73)
		(end 212.03 54.73)
		(width 0.1)
		(layer "In5.Cu")
		(net 47)
	)
	(segment
		(start 200.13 55.43)
		(end 198.56 57)
		(width 0.1)
		(layer "In5.Cu")
		(net 47)
	)
	(segment
		(start 171 60.8)
		(end 169.05 62.75)
		(width 0.1)
		(layer "In5.Cu")
		(net 47)
	)
	(segment
		(start 193.985788 57)
		(end 190.185788 60.8)
		(width 0.1)
		(layer "In5.Cu")
		(net 47)
	)
	(segment
		(start 211.33 55.43)
		(end 200.13 55.43)
		(width 0.1)
		(layer "In5.Cu")
		(net 47)
	)
	(segment
		(start 126.050002 63.5)
		(end 123.950002 65.6)
		(width 0.1)
		(layer "In5.Cu")
		(net 47)
	)
	(segment
		(start 149.65 67.3)
		(end 145.85 63.5)
		(width 0.1)
		(layer "In5.Cu")
		(net 47)
	)
	(segment
		(start 169.05 62.75)
		(end 159.2 62.75)
		(width 0.1)
		(layer "In5.Cu")
		(net 47)
	)
	(segment
		(start 87.6 71)
		(end 88 71.4)
		(width 0.1)
		(layer "F.Cu")
		(net 48)
	)
	(segment
		(start 87.6 70.4)
		(end 87.6 71)
		(width 0.1)
		(layer "F.Cu")
		(net 48)
	)
	(segment
		(start 88 71.4)
		(end 89.380532 71.4)
		(width 0.1)
		(layer "F.Cu")
		(net 48)
	)
	(segment
		(start 88 70)
		(end 87.6 70.4)
		(width 0.1)
		(layer "F.Cu")
		(net 48)
	)
	(segment
		(start 89.380532 71.4)
		(end 90.130532 72.15)
		(width 0.1)
		(layer "F.Cu")
		(net 48)
	)
	(via
		(at 88 70)
		(size 0.45)
		(drill 0.1)
		(layers "F.Cu" "B.Cu")
		(net 48)
	)
	(segment
		(start 88.4 66.3)
		(end 88 65.9)
		(width 0.1)
		(layer "B.Cu")
		(net 48)
	)
	(segment
		(start 88.4 69.6)
		(end 88.4 66.3)
		(width 0.1)
		(layer "B.Cu")
		(net 48)
	)
	(segment
		(start 88 70)
		(end 88.4 69.6)
		(width 0.1)
		(layer "B.Cu")
		(net 48)
	)
	(segment
		(start 84.165686 132.4)
		(end 86.2 132.4)
		(width 0.1)
		(layer "F.Cu")
		(net 49)
	)
	(segment
		(start 73.8 116)
		(end 74.2 116.4)
		(width 0.1)
		(layer "F.Cu")
		(net 49)
	)
	(segment
		(start 76.4 116.7)
		(end 76.4 117.4)
		(width 0.1)
		(layer "F.Cu")
		(net 49)
	)
	(segment
		(start 76.4 117.4)
		(end 80.4 121.4)
		(width 0.1)
		(layer "F.Cu")
		(net 49)
	)
	(segment
		(start 76.1 116.4)
		(end 76.4 116.7)
		(width 0.1)
		(layer "F.Cu")
		(net 49)
	)
	(segment
		(start 80.4 128.634314)
		(end 84.165686 132.4)
		(width 0.1)
		(layer "F.Cu")
		(net 49)
	)
	(segment
		(start 86.2 132.4)
		(end 87 133.2)
		(width 0.1)
		(layer "F.Cu")
		(net 49)
	)
	(segment
		(start 87 133.2)
		(end 87 135.9)
		(width 0.1)
		(layer "F.Cu")
		(net 49)
	)
	(segment
		(start 74.505532 113.235)
		(end 73.8 113.940532)
		(width 0.1)
		(layer "F.Cu")
		(net 49)
	)
	(segment
		(start 80.4 121.4)
		(end 80.4 128.634314)
		(width 0.1)
		(layer "F.Cu")
		(net 49)
	)
	(segment
		(start 87 135.9)
		(end 87.4 136.3)
		(width 0.1)
		(layer "F.Cu")
		(net 49)
	)
	(segment
		(start 73.8 113.940532)
		(end 73.8 116)
		(width 0.1)
		(layer "F.Cu")
		(net 49)
	)
	(segment
		(start 74.2 116.4)
		(end 76.1 116.4)
		(width 0.1)
		(layer "F.Cu")
		(net 49)
	)
	(via
		(at 74.505532 113.235)
		(size 0.45)
		(drill 0.1)
		(layers "F.Cu" "B.Cu")
		(net 49)
	)
	(via
		(at 145.4 92.6)
		(size 0.45)
		(drill 0.1)
		(layers "F.Cu" "B.Cu")
		(net 49)
	)
	(via
		(at 87.4 136.3)
		(size 0.45)
		(drill 0.1)
		(layers "F.Cu" "B.Cu")
		(net 49)
	)
	(via
		(at 138.630532 76.65)
		(size 0.45)
		(drill 0.1)
		(layers "F.Cu" "B.Cu")
		(net 49)
	)
	(segment
		(start 145.4 91.9)
		(end 145.4 92.6)
		(width 0.1)
		(layer "B.Cu")
		(net 49)
	)
	(segment
		(start 144.65 77.8)
		(end 144.65 84.6)
		(width 0.1)
		(layer "B.Cu")
		(net 49)
	)
	(segment
		(start 144.15 85.1)
		(end 144.15 90.65)
		(width 0.1)
		(layer "B.Cu")
		(net 49)
	)
	(segment
		(start 138.630532 76.65)
		(end 139.480532 77.5)
		(width 0.1)
		(layer "B.Cu")
		(net 49)
	)
	(segment
		(start 139.480532 77.5)
		(end 144.35 77.5)
		(width 0.1)
		(layer "B.Cu")
		(net 49)
	)
	(segment
		(start 144.35 77.5)
		(end 144.65 77.8)
		(width 0.1)
		(layer "B.Cu")
		(net 49)
	)
	(segment
		(start 144.65 84.6)
		(end 144.15 85.1)
		(width 0.1)
		(layer "B.Cu")
		(net 49)
	)
	(segment
		(start 144.15 90.65)
		(end 145.4 91.9)
		(width 0.1)
		(layer "B.Cu")
		(net 49)
	)
	(segment
		(start 100.6 131.4)
		(end 99.675 132.325)
		(width 0.1)
		(layer "In5.Cu")
		(net 49)
	)
	(segment
		(start 144.8 107)
		(end 145.4 107.6)
		(width 0.1)
		(layer "In5.Cu")
		(net 49)
	)
	(segment
		(start 106.028428 131.4)
		(end 100.6 131.4)
		(width 0.1)
		(layer "In5.Cu")
		(net 49)
	)
	(segment
		(start 145.4 107.6)
		(end 145.4 117.628428)
		(width 0.1)
		(layer "In5.Cu")
		(net 49)
	)
	(segment
		(start 90.15 136.3)
		(end 87.4 136.3)
		(width 0.1)
		(layer "In5.Cu")
		(net 49)
	)
	(segment
		(start 99.675 132.325)
		(end 94.125 132.325)
		(width 0.1)
		(layer "In5.Cu")
		(net 49)
	)
	(segment
		(start 145.4 103)
		(end 144.8 103.6)
		(width 0.1)
		(layer "In5.Cu")
		(net 49)
	)
	(segment
		(start 138.528428 124.5)
		(end 112.928428 124.5)
		(width 0.1)
		(layer "In5.Cu")
		(net 49)
	)
	(segment
		(start 145.4 117.628428)
		(end 138.528428 124.5)
		(width 0.1)
		(layer "In5.Cu")
		(net 49)
	)
	(segment
		(start 145.4 92.6)
		(end 145.4 103)
		(width 0.1)
		(layer "In5.Cu")
		(net 49)
	)
	(segment
		(start 112.928428 124.5)
		(end 106.028428 131.4)
		(width 0.1)
		(layer "In5.Cu")
		(net 49)
	)
	(segment
		(start 144.8 103.6)
		(end 144.8 107)
		(width 0.1)
		(layer "In5.Cu")
		(net 49)
	)
	(segment
		(start 94.125 132.325)
		(end 90.15 136.3)
		(width 0.1)
		(layer "In5.Cu")
		(net 49)
	)
	(segment
		(start 120.780532 75.5)
		(end 120.430532 75.15)
		(width 0.1)
		(layer "F.Cu")
		(net 50)
	)
	(segment
		(start 120.85 75.5)
		(end 120.780532 75.5)
		(width 0.1)
		(layer "F.Cu")
		(net 50)
	)
	(via
		(at 120.85 75.5)
		(size 0.45)
		(drill 0.1)
		(layers "F.Cu" "B.Cu")
		(net 50)
	)
	(via
		(at 87.3 109.15)
		(size 0.45)
		(drill 0.1)
		(layers "F.Cu" "B.Cu")
		(net 50)
	)
	(segment
		(start 79.1 108.35)
		(end 79.1 100.15)
		(width 0.1)
		(layer "B.Cu")
		(net 50)
	)
	(segment
		(start 87.05 108.6)
		(end 86.45 108.6)
		(width 0.1)
		(layer "B.Cu")
		(net 50)
	)
	(segment
		(start 87.3 108.85)
		(end 87.05 108.6)
		(width 0.1)
		(layer "B.Cu")
		(net 50)
	)
	(segment
		(start 79.6 108.85)
		(end 79.1 108.35)
		(width 0.1)
		(layer "B.Cu")
		(net 50)
	)
	(segment
		(start 75.25 91.119468)
		(end 74.505532 90.375)
		(width 0.1)
		(layer "B.Cu")
		(net 50)
	)
	(segment
		(start 75.25 99.5)
		(end 75.25 91.119468)
		(width 0.1)
		(layer "B.Cu")
		(net 50)
	)
	(segment
		(start 86.45 108.6)
		(end 86.2 108.85)
		(width 0.1)
		(layer "B.Cu")
		(net 50)
	)
	(segment
		(start 86.2 108.85)
		(end 79.6 108.85)
		(width 0.1)
		(layer "B.Cu")
		(net 50)
	)
	(segment
		(start 87.3 109.15)
		(end 87.3 108.85)
		(width 0.1)
		(layer "B.Cu")
		(net 50)
	)
	(segment
		(start 79.1 100.15)
		(end 78.739627 99.789627)
		(width 0.1)
		(layer "B.Cu")
		(net 50)
	)
	(segment
		(start 78.739627 99.789627)
		(end 75.539627 99.789627)
		(width 0.1)
		(layer "B.Cu")
		(net 50)
	)
	(segment
		(start 75.539627 99.789627)
		(end 75.25 99.5)
		(width 0.1)
		(layer "B.Cu")
		(net 50)
	)
	(segment
		(start 124.25 75.9)
		(end 121.25 75.9)
		(width 0.1)
		(layer "In5.Cu")
		(net 50)
	)
	(segment
		(start 123.535961 76.771129)
		(end 123.535961 77.26)
		(width 0.1)
		(layer "In5.Cu")
		(net 50)
	)
	(segment
		(start 123.745961 77.4)
		(end 124.025 77.4)
		(width 0.1)
		(layer "In5.Cu")
		(net 50)
	)
	(segment
		(start 118.6 80.75)
		(end 118.75 80.6)
		(width 0.1)
		(layer "In5.Cu")
		(net 50)
	)
	(segment
		(start 124.307842 77.117157)
		(end 124.317811 77.107189)
		(width 0.1)
		(layer "In5.Cu")
		(net 50)
	)
	(segment
		(start 124.025 77.4)
		(end 124.307842 77.117157)
		(width 0.1)
		(layer "In5.Cu")
		(net 50)
	)
	(segment
		(start 85.45 111.45)
		(end 85.45 113.45)
		(width 0.1)
		(layer "In5.Cu")
		(net 50)
	)
	(segment
		(start 87.3 109.6)
		(end 85.45 111.45)
		(width 0.1)
		(layer "In5.Cu")
		(net 50)
	)
	(segment
		(start 96.3 109.8)
		(end 96.600002 109.499998)
		(width 0.1)
		(layer "In5.Cu")
		(net 50)
	)
	(segment
		(start 121.25 75.9)
		(end 120.85 75.5)
		(width 0.1)
		(layer "In5.Cu")
		(net 50)
	)
	(segment
		(start 122.625961 76.631104)
		(end 122.695961 76.631104)
		(width 0.1)
		(layer "In5.Cu")
		(net 50)
	)
	(segment
		(start 122.835961 76.771104)
		(end 122.835961 77.26)
		(width 0.1)
		(layer "In5.Cu")
		(net 50)
	)
	(segment
		(start 99 100.575738)
		(end 99 94.925738)
		(width 0.1)
		(layer "In5.Cu")
		(net 50)
	)
	(segment
		(start 116.374631 81.349631)
		(end 117.400369 81.349631)
		(width 0.1)
		(layer "In5.Cu")
		(net 50)
	)
	(segment
		(start 124.317811 77.107189)
		(end 124.65 76.775)
		(width 0.1)
		(layer "In5.Cu")
		(net 50)
	)
	(segment
		(start 123.325961 76.631129)
		(end 123.395961 76.631129)
		(width 0.1)
		(layer "In5.Cu")
		(net 50)
	)
	(segment
		(start 113.974263 83.749999)
		(end 116.374631 81.349631)
		(width 0.1)
		(layer "In5.Cu")
		(net 50)
	)
	(segment
		(start 124.65 76.775)
		(end 124.65 76.3)
		(width 0.1)
		(layer "In5.Cu")
		(net 50)
	)
	(segment
		(start 121.674262 77.4)
		(end 122.345961 77.4)
		(width 0.1)
		(layer "In5.Cu")
		(net 50)
	)
	(segment
		(start 113.375739 83.749999)
		(end 113.974263 83.749999)
		(width 0.1)
		(layer "In5.Cu")
		(net 50)
	)
	(segment
		(start 93.05 114.6)
		(end 96.3 111.35)
		(width 0.1)
		(layer "In5.Cu")
		(net 50)
	)
	(segment
		(start 122.975961 77.4)
		(end 123.045961 77.4)
		(width 0.1)
		(layer "In5.Cu")
		(net 50)
	)
	(segment
		(start 117.400369 81.349631)
		(end 118 80.75)
		(width 0.1)
		(layer "In5.Cu")
		(net 50)
	)
	(segment
		(start 124.65 76.3)
		(end 124.25 75.9)
		(width 0.1)
		(layer "In5.Cu")
		(net 50)
	)
	(segment
		(start 87.3 109.15)
		(end 87.3 109.6)
		(width 0.1)
		(layer "In5.Cu")
		(net 50)
	)
	(segment
		(start 123.185961 77.26)
		(end 123.185961 76.771129)
		(width 0.1)
		(layer "In5.Cu")
		(net 50)
	)
	(segment
		(start 99 94.925738)
		(end 99.723103 94.202635)
		(width 0.1)
		(layer "In5.Cu")
		(net 50)
	)
	(segment
		(start 85.8 113.8)
		(end 90.824264 113.8)
		(width 0.1)
		(layer "In5.Cu")
		(net 50)
	)
	(segment
		(start 123.675961 77.4)
		(end 123.745961 77.4)
		(width 0.1)
		(layer "In5.Cu")
		(net 50)
	)
	(segment
		(start 118 80.75)
		(end 118.6 80.75)
		(width 0.1)
		(layer "In5.Cu")
		(net 50)
	)
	(segment
		(start 99.723103 94.202635)
		(end 102.923103 94.202635)
		(width 0.1)
		(layer "In5.Cu")
		(net 50)
	)
	(segment
		(start 90.824264 113.8)
		(end 91.624264 114.6)
		(width 0.1)
		(layer "In5.Cu")
		(net 50)
	)
	(segment
		(start 96.600002 109.499998)
		(end 96.600002 102.975736)
		(width 0.1)
		(layer "In5.Cu")
		(net 50)
	)
	(segment
		(start 91.624264 114.6)
		(end 93.05 114.6)
		(width 0.1)
		(layer "In5.Cu")
		(net 50)
	)
	(segment
		(start 118.75 80.6)
		(end 118.75 80.324262)
		(width 0.1)
		(layer "In5.Cu")
		(net 50)
	)
	(segment
		(start 122.485961 77.26)
		(end 122.485961 76.771104)
		(width 0.1)
		(layer "In5.Cu")
		(net 50)
	)
	(segment
		(start 102.923103 94.202635)
		(end 113.375739 83.749999)
		(width 0.1)
		(layer "In5.Cu")
		(net 50)
	)
	(segment
		(start 85.45 113.45)
		(end 85.8 113.8)
		(width 0.1)
		(layer "In5.Cu")
		(net 50)
	)
	(segment
		(start 118.75 80.324262)
		(end 121.674262 77.4)
		(width 0.1)
		(layer "In5.Cu")
		(net 50)
	)
	(segment
		(start 96.600002 102.975736)
		(end 99 100.575738)
		(width 0.1)
		(layer "In5.Cu")
		(net 50)
	)
	(segment
		(start 96.3 111.35)
		(end 96.3 109.8)
		(width 0.1)
		(layer "In5.Cu")
		(net 50)
	)
	(arc
		(start 123.395961 76.631129)
		(mid 123.494956 76.672134)
		(end 123.535961 76.771129)
		(width 0.1)
		(layer "In5.Cu")
		(net 50)
	)
	(arc
		(start 123.535961 77.26)
		(mid 123.576966 77.358995)
		(end 123.675961 77.4)
		(width 0.1)
		(layer "In5.Cu")
		(net 50)
	)
	(arc
		(start 122.485961 76.771104)
		(mid 122.526966 76.672109)
		(end 122.625961 76.631104)
		(width 0.1)
		(layer "In5.Cu")
		(net 50)
	)
	(arc
		(start 122.345961 77.4)
		(mid 122.444956 77.358995)
		(end 122.485961 77.26)
		(width 0.1)
		(layer "In5.Cu")
		(net 50)
	)
	(arc
		(start 122.695961 76.631104)
		(mid 122.794956 76.672109)
		(end 122.835961 76.771104)
		(width 0.1)
		(layer "In5.Cu")
		(net 50)
	)
	(arc
		(start 123.045961 77.4)
		(mid 123.144956 77.358995)
		(end 123.185961 77.26)
		(width 0.1)
		(layer "In5.Cu")
		(net 50)
	)
	(arc
		(start 123.185961 76.771129)
		(mid 123.226966 76.672134)
		(end 123.325961 76.631129)
		(width 0.1)
		(layer "In5.Cu")
		(net 50)
	)
	(arc
		(start 122.835961 77.26)
		(mid 122.876966 77.358995)
		(end 122.975961 77.4)
		(width 0.1)
		(layer "In5.Cu")
		(net 50)
	)
	(segment
		(start 130.525 99)
		(end 132.25 99)
		(width 0.1)
		(layer "F.Cu")
		(net 51)
	)
	(segment
		(start 128.3 98.6)
		(end 130.125 98.6)
		(width 0.1)
		(layer "F.Cu")
		(net 51)
	)
	(segment
		(start 128.09 98.32)
		(end 128.09 98.39)
		(width 0.1)
		(layer "F.Cu")
		(net 51)
	)
	(segment
		(start 128.09 98.39)
		(end 128.3 98.6)
		(width 0.1)
		(layer "F.Cu")
		(net 51)
	)
	(segment
		(start 130.125 98.6)
		(end 130.525 99)
		(width 0.1)
		(layer "F.Cu")
		(net 51)
	)
	(via
		(at 128.09 98.32)
		(size 0.45)
		(drill 0.1)
		(layers "F.Cu" "B.Cu")
		(net 51)
	)
	(via
		(at 138.630532 82.65)
		(size 0.45)
		(drill 0.1)
		(layers "F.Cu" "B.Cu")
		(net 51)
	)
	(via
		(at 132.25 99)
		(size 0.45)
		(drill 0.1)
		(layers "F.Cu" "B.Cu")
		(net 51)
	)
	(via
		(at 79.585532 92.915)
		(size 0.45)
		(drill 0.1)
		(layers "F.Cu" "B.Cu")
		(net 51)
	)
	(segment
		(start 133.5 94.05)
		(end 133.5 97.75)
		(width 0.1)
		(layer "In5.Cu")
		(net 51)
	)
	(segment
		(start 140.15 83.85)
		(end 140.15 84.5)
		(width 0.1)
		(layer "In5.Cu")
		(net 51)
	)
	(segment
		(start 82.2 100)
		(end 81 98.8)
		(width 0.1)
		(layer "In5.Cu")
		(net 51)
	)
	(segment
		(start 100.20295 101.3)
		(end 98.100004 103.402946)
		(width 0.1)
		(layer "In5.Cu")
		(net 51)
	)
	(segment
		(start 128.09 98.32)
		(end 127.68 98.32)
		(width 0.1)
		(layer "In5.Cu")
		(net 51)
	)
	(segment
		(start 123.234316 98.534316)
		(end 120.468632 101.3)
		(width 0.1)
		(layer "In5.Cu")
		(net 51)
	)
	(segment
		(start 139.3 83.319468)
		(end 139.619468 83.319468)
		(width 0.1)
		(layer "In5.Cu")
		(net 51)
	)
	(segment
		(start 127.465684 98.534316)
		(end 123.234316 98.534316)
		(width 0.1)
		(layer "In5.Cu")
		(net 51)
	)
	(segment
		(start 139.900001 87.649999)
		(end 133.5 94.05)
		(width 0.1)
		(layer "In5.Cu")
		(net 51)
	)
	(segment
		(start 84.275 115.2)
		(end 84.025 114.95)
		(width 0.1)
		(layer "In5.Cu")
		(net 51)
	)
	(segment
		(start 84.025 100.525)
		(end 83.5 100)
		(width 0.1)
		(layer "In5.Cu")
		(net 51)
	)
	(segment
		(start 139.900001 84.749999)
		(end 139.900001 87.649999)
		(width 0.1)
		(layer "In5.Cu")
		(net 51)
	)
	(segment
		(start 138.630532 82.65)
		(end 139.3 83.319468)
		(width 0.1)
		(layer "In5.Cu")
		(net 51)
	)
	(segment
		(start 133.5 97.75)
		(end 132.25 99)
		(width 0.1)
		(layer "In5.Cu")
		(net 51)
	)
	(segment
		(start 84.025 114.95)
		(end 84.025 100.525)
		(width 0.1)
		(layer "In5.Cu")
		(net 51)
	)
	(segment
		(start 80.25 98.8)
		(end 80 98.55)
		(width 0.1)
		(layer "In5.Cu")
		(net 51)
	)
	(segment
		(start 140.15 84.5)
		(end 139.900001 84.749999)
		(width 0.1)
		(layer "In5.Cu")
		(net 51)
	)
	(segment
		(start 80 93.329468)
		(end 79.585532 92.915)
		(width 0.1)
		(layer "In5.Cu")
		(net 51)
	)
	(segment
		(start 98.100004 103.402946)
		(end 98.100004 110.571574)
		(width 0.1)
		(layer "In5.Cu")
		(net 51)
	)
	(segment
		(start 81 98.8)
		(end 80.25 98.8)
		(width 0.1)
		(layer "In5.Cu")
		(net 51)
	)
	(segment
		(start 127.68 98.32)
		(end 127.465684 98.534316)
		(width 0.1)
		(layer "In5.Cu")
		(net 51)
	)
	(segment
		(start 83.5 100)
		(end 82.2 100)
		(width 0.1)
		(layer "In5.Cu")
		(net 51)
	)
	(segment
		(start 98.100004 110.571574)
		(end 93.471578 115.2)
		(width 0.1)
		(layer "In5.Cu")
		(net 51)
	)
	(segment
		(start 80 98.55)
		(end 80 93.329468)
		(width 0.1)
		(layer "In5.Cu")
		(net 51)
	)
	(segment
		(start 139.619468 83.319468)
		(end 140.15 83.85)
		(width 0.1)
		(layer "In5.Cu")
		(net 51)
	)
	(segment
		(start 93.471578 115.2)
		(end 84.275 115.2)
		(width 0.1)
		(layer "In5.Cu")
		(net 51)
	)
	(segment
		(start 120.468632 101.3)
		(end 100.20295 101.3)
		(width 0.1)
		(layer "In5.Cu")
		(net 51)
	)
	(segment
		(start 128.455532 79.025)
		(end 128.580532 78.9)
		(width 0.17)
		(layer "F.Cu")
		(net 52)
	)
	(segment
		(start 128.730532 79.65)
		(end 128.455532 79.375)
		(width 0.17)
		(layer "F.Cu")
		(net 52)
	)
	(segment
		(start 128.455532 79.375)
		(end 128.455532 79.025)
		(width 0.17)
		(layer "F.Cu")
		(net 52)
	)
	(via
		(at 66.4 108.7)
		(size 0.45)
		(drill 0.1)
		(layers "F.Cu" "B.Cu")
		(net 52)
	)
	(via
		(at 128.580532 78.9)
		(size 0.45)
		(drill 0.1)
		(layers "F.Cu" "B.Cu")
		(net 52)
	)
	(segment
		(start 65.490001 114.46)
		(end 65.565001 114.535)
		(width 0.17)
		(layer "B.Cu")
		(net 52)
	)
	(segment
		(start 65.917512 114.535)
		(end 66.525 113.927512)
		(width 0.17)
		(layer "B.Cu")
		(net 52)
	)
	(segment
		(start 66.525 108.825)
		(end 66.4 108.7)
		(width 0.17)
		(layer "B.Cu")
		(net 52)
	)
	(segment
		(start 64.59 114.46)
		(end 65.490001 114.46)
		(width 0.17)
		(layer "B.Cu")
		(net 52)
	)
	(segment
		(start 66.525 113.927512)
		(end 66.525 108.825)
		(width 0.17)
		(layer "B.Cu")
		(net 52)
	)
	(segment
		(start 65.565001 114.535)
		(end 65.917512 114.535)
		(width 0.17)
		(layer "B.Cu")
		(net 52)
	)
	(segment
		(start 125.3466 82.5125)
		(end 124.5466 83.3125)
		(width 0.125)
		(layer "In2.Cu")
		(net 52)
	)
	(segment
		(start 85.8268 85.3075)
		(end 85.8268 86.4925)
		(width 0.125)
		(layer "In2.Cu")
		(net 52)
	)
	(segment
		(start 103.9534 83.5125)
		(end 102.4534 82.0125)
		(width 0.125)
		(layer "In2.Cu")
		(net 52)
	)
	(segment
		(start 100.0966 82.0125)
		(end 99.7966 82.3125)
		(width 0.125)
		(layer "In2.Cu")
		(net 52)
	)
	(segment
		(start 89.4466 82.0125)
		(end 88.8125 82.6466)
		(width 0.125)
		(layer "In2.Cu")
		(net 52)
	)
	(segment
		(start 88.7466 84.545428)
		(end 88.868576 84.667404)
		(width 0.125)
		(layer "In2.Cu")
		(net 52)
	)
	(segment
		(start 87.1275 86.0125)
		(end 87.657653 85.482343)
		(width 0.125)
		(layer "In2.Cu")
		(net 52)
	)
	(segment
		(start 110.1466 83.0125)
		(end 109.6466 83.5125)
		(width 0.125)
		(layer "In2.Cu")
		(net 52)
	)
	(segment
		(start 86.5943 86.825)
		(end 86.4843 86.825)
		(width 0.125)
		(layer "In2.Cu")
		(net 52)
	)
	(segment
		(start 87.730132 84.624977)
		(end 88.320568 85.215413)
		(width 0.125)
		(layer "In2.Cu")
		(net 52)
	)
	(segment
		(start 92.594687 83.025)
		(end 92.484687 83.025)
		(width 0.125)
		(layer "In2.Cu")
		(net 52)
	)
	(segment
		(start 116.0534 83.9125)
		(end 115.6534 83.5125)
		(width 0.125)
		(layer "In2.Cu")
		(net 52)
	)
	(segment
		(start 86.1518 86.4925)
		(end 86.1518 85.3075)
		(width 0.125)
		(layer "In2.Cu")
		(net 52)
	)
	(segment
		(start 88.8125 83.5591)
		(end 88.8125 84.3275)
		(width 0.125)
		(layer "In2.Cu")
		(net 52)
	)
	(segment
		(start 66.587499 108.887499)
		(end 66.4 108.7)
		(width 0.125)
		(layer "In2.Cu")
		(net 52)
	)
	(segment
		(start 92.152187 82.6925)
		(end 92.152187 82.12)
		(width 0.125)
		(layer "In2.Cu")
		(net 52)
	)
	(segment
		(start 118.4466 82.9125)
		(end 117.4466 83.9125)
		(width 0.125)
		(layer "In2.Cu")
		(net 52)
	)
	(segment
		(start 124.5466 83.3125)
		(end 119.6534 83.3125)
		(width 0.125)
		(layer "In2.Cu")
		(net 52)
	)
	(segment
		(start 102.4534 82.0125)
		(end 100.0966 82.0125)
		(width 0.125)
		(layer "In2.Cu")
		(net 52)
	)
	(segment
		(start 69.3466 86.0125)
		(end 84.9443 86.0125)
		(width 0.125)
		(layer "In2.Cu")
		(net 52)
	)
	(segment
		(start 66.9534 109.5125)
		(end 66.587499 109.146599)
		(width 0.125)
		(layer "In2.Cu")
		(net 52)
	)
	(segment
		(start 86.0443 85.2)
		(end 85.9343 85.2)
		(width 0.125)
		(layer "In2.Cu")
		(net 52)
	)
	(segment
		(start 109.6466 83.5125)
		(end 103.9534 83.5125)
		(width 0.125)
		(layer "In2.Cu")
		(net 52)
	)
	(segment
		(start 119.2534 82.9125)
		(end 118.4466 82.9125)
		(width 0.125)
		(layer "In2.Cu")
		(net 52)
	)
	(segment
		(start 89.4466 82.0125)
		(end 92.044687 82.0125)
		(width 0.125)
		(layer "In2.Cu")
		(net 52)
	)
	(segment
		(start 95.4466 82.7125)
		(end 94.2534 82.7125)
		(width 0.125)
		(layer "In2.Cu")
		(net 52)
	)
	(segment
		(start 98.2534 82.3125)
		(end 97.2534 81.3125)
		(width 0.125)
		(layer "In2.Cu")
		(net 52)
	)
	(segment
		(start 115.6534 83.5125)
		(end 111.8534 83.5125)
		(width 0.125)
		(layer "In2.Cu")
		(net 52)
	)
	(segment
		(start 88.8125 84.3275)
		(end 88.7466 84.3934)
		(width 0.125)
		(layer "In2.Cu")
		(net 52)
	)
	(segment
		(start 119.6534 83.3125)
		(end 119.2534 82.9125)
		(width 0.125)
		(layer "In2.Cu")
		(net 52)
	)
	(segment
		(start 128.393033 80.066067)
		(end 125.9466 82.5125)
		(width 0.125)
		(layer "In2.Cu")
		(net 52)
	)
	(segment
		(start 87.1275 86.0125)
		(end 87.0343 86.0125)
		(width 0.125)
		(layer "In2.Cu")
		(net 52)
	)
	(segment
		(start 88.868576 85.13763)
		(end 88.790794 85.215413)
		(width 0.125)
		(layer "In2.Cu")
		(net 52)
	)
	(segment
		(start 95.9125 81.7466)
		(end 95.9125 82.2466)
		(width 0.125)
		(layer "In2.Cu")
		(net 52)
	)
	(segment
		(start 66.587499 109.146599)
		(end 66.587499 108.887499)
		(width 0.125)
		(layer "In2.Cu")
		(net 52)
	)
	(segment
		(start 99.7966 82.3125)
		(end 98.2534 82.3125)
		(width 0.125)
		(layer "In2.Cu")
		(net 52)
	)
	(segment
		(start 68.4125 86.9466)
		(end 68.4125 108.8466)
		(width 0.125)
		(layer "In2.Cu")
		(net 52)
	)
	(segment
		(start 97.2534 81.3125)
		(end 96.3466 81.3125)
		(width 0.125)
		(layer "In2.Cu")
		(net 52)
	)
	(segment
		(start 69.3466 86.0125)
		(end 68.4125 86.9466)
		(width 0.125)
		(layer "In2.Cu")
		(net 52)
	)
	(segment
		(start 89.175 83.0091)
		(end 89.175 83.1966)
		(width 0.125)
		(layer "In2.Cu")
		(net 52)
	)
	(segment
		(start 128.393033 79.087499)
		(end 128.393033 80.066067)
		(width 0.125)
		(layer "In2.Cu")
		(net 52)
	)
	(segment
		(start 93.5534 82.0125)
		(end 93.034687 82.0125)
		(width 0.125)
		(layer "In2.Cu")
		(net 52)
	)
	(segment
		(start 95.9125 82.2466)
		(end 95.4466 82.7125)
		(width 0.125)
		(layer "In2.Cu")
		(net 52)
	)
	(segment
		(start 85.0518 86.4925)
		(end 85.0518 86.12)
		(width 0.125)
		(layer "In2.Cu")
		(net 52)
	)
	(segment
		(start 94.2534 82.7125)
		(end 93.5534 82.0125)
		(width 0.125)
		(layer "In2.Cu")
		(net 52)
	)
	(segment
		(start 87.500322 84.854786)
		(end 87.657653 85.012117)
		(width 0.125)
		(layer "In2.Cu")
		(net 52)
	)
	(segment
		(start 117.4466 83.9125)
		(end 116.0534 83.9125)
		(width 0.125)
		(layer "In2.Cu")
		(net 52)
	)
	(segment
		(start 96.3466 81.3125)
		(end 95.9125 81.7466)
		(width 0.125)
		(layer "In2.Cu")
		(net 52)
	)
	(segment
		(start 86.9268 86.12)
		(end 86.9268 86.4925)
		(width 0.125)
		(layer "In2.Cu")
		(net 52)
	)
	(segment
		(start 92.927187 82.12)
		(end 92.927187 82.6925)
		(width 0.125)
		(layer "In2.Cu")
		(net 52)
	)
	(segment
		(start 87.578104 84.624977)
		(end 87.500322 84.702758)
		(width 0.125)
		(layer "In2.Cu")
		(net 52)
	)
	(segment
		(start 128.580532 78.9)
		(end 128.393033 79.087499)
		(width 0.125)
		(layer "In2.Cu")
		(net 52)
	)
	(segment
		(start 67.7466 109.5125)
		(end 66.9534 109.5125)
		(width 0.125)
		(layer "In2.Cu")
		(net 52)
	)
	(segment
		(start 125.9466 82.5125)
		(end 125.3466 82.5125)
		(width 0.125)
		(layer "In2.Cu")
		(net 52)
	)
	(segment
		(start 111.8534 83.5125)
		(end 111.3534 83.0125)
		(width 0.125)
		(layer "In2.Cu")
		(net 52)
	)
	(segment
		(start 68.4125 108.8466)
		(end 67.7466 109.5125)
		(width 0.125)
		(layer "In2.Cu")
		(net 52)
	)
	(segment
		(start 111.3534 83.0125)
		(end 110.1466 83.0125)
		(width 0.125)
		(layer "In2.Cu")
		(net 52)
	)
	(segment
		(start 85.4943 86.825)
		(end 85.3843 86.825)
		(width 0.125)
		(layer "In2.Cu")
		(net 52)
	)
	(arc
		(start 88.7466 84.3934)
		(mid 88.715114 84.469414)
		(end 88.7466 84.545428)
		(width 0.125)
		(layer "In2.Cu")
		(net 52)
	)
	(arc
		(start 92.152187 82.12)
		(mid 92.120701 82.043986)
		(end 92.044687 82.0125)
		(width 0.125)
		(layer "In2.Cu")
		(net 52)
	)
	(arc
		(start 85.9343 85.2)
		(mid 85.858286 85.231486)
		(end 85.8268 85.3075)
		(width 0.125)
		(layer "In2.Cu")
		(net 52)
	)
	(arc
		(start 85.3843 86.825)
		(mid 85.149187 86.727613)
		(end 85.0518 86.4925)
		(width 0.125)
		(layer "In2.Cu")
		(net 52)
	)
	(arc
		(start 87.500322 84.702758)
		(mid 87.468836 84.778772)
		(end 87.500322 84.854786)
		(width 0.125)
		(layer "In2.Cu")
		(net 52)
	)
	(arc
		(start 85.0518 86.12)
		(mid 85.020314 86.043986)
		(end 84.9443 86.0125)
		(width 0.125)
		(layer "In2.Cu")
		(net 52)
	)
	(arc
		(start 89.175 83.1966)
		(mid 89.088963 83.404313)
		(end 88.88125 83.49035)
		(width 0.125)
		(layer "In2.Cu")
		(net 52)
	)
	(arc
		(start 87.657653 85.012117)
		(mid 87.75504 85.24723)
		(end 87.657653 85.482343)
		(width 0.125)
		(layer "In2.Cu")
		(net 52)
	)
	(arc
		(start 86.9268 86.4925)
		(mid 86.829413 86.727613)
		(end 86.5943 86.825)
		(width 0.125)
		(layer "In2.Cu")
		(net 52)
	)
	(arc
		(start 92.927187 82.6925)
		(mid 92.8298 82.927613)
		(end 92.594687 83.025)
		(width 0.125)
		(layer "In2.Cu")
		(net 52)
	)
	(arc
		(start 88.88125 82.71535)
		(mid 89.088963 82.801387)
		(end 89.175 83.0091)
		(width 0.125)
		(layer "In2.Cu")
		(net 52)
	)
	(arc
		(start 88.790794 85.215413)
		(mid 88.555681 85.3128)
		(end 88.320568 85.215413)
		(width 0.125)
		(layer "In2.Cu")
		(net 52)
	)
	(arc
		(start 85.8268 86.4925)
		(mid 85.729413 86.727613)
		(end 85.4943 86.825)
		(width 0.125)
		(layer "In2.Cu")
		(net 52)
	)
	(arc
		(start 92.484687 83.025)
		(mid 92.249574 82.927613)
		(end 92.152187 82.6925)
		(width 0.125)
		(layer "In2.Cu")
		(net 52)
	)
	(arc
		(start 86.1518 85.3075)
		(mid 86.120314 85.231486)
		(end 86.0443 85.2)
		(width 0.125)
		(layer "In2.Cu")
		(net 52)
	)
	(arc
		(start 88.868576 84.667404)
		(mid 88.965963 84.902517)
		(end 88.868576 85.13763)
		(width 0.125)
		(layer "In2.Cu")
		(net 52)
	)
	(arc
		(start 88.88125 83.49035)
		(mid 88.832636 83.510486)
		(end 88.8125 83.5591)
		(width 0.125)
		(layer "In2.Cu")
		(net 52)
	)
	(arc
		(start 87.730132 84.624977)
		(mid 87.654118 84.593491)
		(end 87.578104 84.624977)
		(width 0.125)
		(layer "In2.Cu")
		(net 52)
	)
	(arc
		(start 93.034687 82.0125)
		(mid 92.958673 82.043986)
		(end 92.927187 82.12)
		(width 0.125)
		(layer "In2.Cu")
		(net 52)
	)
	(arc
		(start 87.0343 86.0125)
		(mid 86.958286 86.043986)
		(end 86.9268 86.12)
		(width 0.125)
		(layer "In2.Cu")
		(net 52)
	)
	(arc
		(start 88.8125 82.6466)
		(mid 88.832636 82.695214)
		(end 88.88125 82.71535)
		(width 0.125)
		(layer "In2.Cu")
		(net 52)
	)
	(arc
		(start 86.4843 86.825)
		(mid 86.249187 86.727613)
		(end 86.1518 86.4925)
		(width 0.125)
		(layer "In2.Cu")
		(net 52)
	)
	(via
		(at 127.830532 73.65)
		(size 0.45)
		(drill 0.1)
		(layers "F.Cu" "B.Cu")
		(net 53)
	)
	(via
		(at 207.707 59.8)
		(size 0.45)
		(drill 0.1)
		(layers "F.Cu" "B.Cu")
		(net 53)
	)
	(segment
		(start 207.582 59.365001)
		(end 207.582 59.675)
		(width 0.17)
		(layer "B.Cu")
		(net 53)
	)
	(segment
		(start 207.582 59.675)
		(end 207.707 59.8)
		(width 0.17)
		(layer "B.Cu")
		(net 53)
	)
	(segment
		(start 207.657 58.39)
		(end 207.657 59.290001)
		(width 0.17)
		(layer "B.Cu")
		(net 53)
	)
	(segment
		(start 207.657 59.290001)
		(end 207.582 59.365001)
		(width 0.17)
		(layer "B.Cu")
		(net 53)
	)
	(segment
		(start 167.110876 73.058605)
		(end 167.222598 72.946882)
		(width 0.125)
		(layer "In2.Cu")
		(net 53)
	)
	(segment
		(start 166.711302 71.829595)
		(end 166.711306 71.829597)
		(width 0.125)
		(layer "In2.Cu")
		(net 53)
	)
	(segment
		(start 168.22805 70.312851)
		(end 168.379342 70.464143)
		(width 0.125)
		(layer "In2.Cu")
		(net 53)
	)
	(segment
		(start 165.993617 74.175803)
		(end 166.105339 74.06408)
		(width 0.125)
		(layer "In2.Cu")
		(net 53)
	)
	(segment
		(start 166.217036 72.770756)
		(end 166.504885 73.058605)
		(width 0.125)
		(layer "In2.Cu")
		(net 53)
	)
	(segment
		(start 167.828533 70.712365)
		(end 167.828536 70.712367)
		(width 0.125)
		(layer "In2.Cu")
		(net 53)
	)
	(segment
		(start 128.168031 74.202131)
		(end 128.4784 74.5125)
		(width 0.125)
		(layer "In2.Cu")
		(net 53)
	)
	(segment
		(start 127.830532 73.65)
		(end 128.168031 73.987499)
		(width 0.125)
		(layer "In2.Cu")
		(net 53)
	)
	(segment
		(start 164.876362 73.664539)
		(end 165.387626 74.175803)
		(width 0.125)
		(layer "In2.Cu")
		(net 53)
	)
	(segment
		(start 177.9375 60.7625)
		(end 206.0284 60.7625)
		(width 0.125)
		(layer "In2.Cu")
		(net 53)
	)
	(segment
		(start 168.841025 70.464143)
		(end 169.097055 70.208112)
		(width 0.125)
		(layer "In2.Cu")
		(net 53)
	)
	(segment
		(start 167.999657 70.084457)
		(end 168.228053 70.312853)
		(width 0.125)
		(layer "In2.Cu")
		(net 53)
	)
	(segment
		(start 207.0966 60.9625)
		(end 207.519501 60.539599)
		(width 0.125)
		(layer "In2.Cu")
		(net 53)
	)
	(segment
		(start 207.519501 59.987499)
		(end 207.707 59.8)
		(width 0.125)
		(layer "In2.Cu")
		(net 53)
	)
	(segment
		(start 166.975545 71.294805)
		(end 167.110823 71.430083)
		(width 0.125)
		(layer "In2.Cu")
		(net 53)
	)
	(segment
		(start 166.576029 71.69432)
		(end 166.711306 71.829597)
		(width 0.125)
		(layer "In2.Cu")
		(net 53)
	)
	(segment
		(start 166.576029 71.582864)
		(end 166.864089 71.294805)
		(width 0.125)
		(layer "In2.Cu")
		(net 53)
	)
	(segment
		(start 167.828533 70.712365)
		(end 168.339798 71.22363)
		(width 0.125)
		(layer "In2.Cu")
		(net 53)
	)
	(segment
		(start 168.228075 71.941345)
		(end 168.339798 71.829621)
		(width 0.125)
		(layer "In2.Cu")
		(net 53)
	)
	(segment
		(start 164.400458 73.188633)
		(end 164.876366 73.664541)
		(width 0.125)
		(layer "In2.Cu")
		(net 53)
	)
	(segment
		(start 167.11082 71.430081)
		(end 167.622084 71.941345)
		(width 0.125)
		(layer "In2.Cu")
		(net 53)
	)
	(segment
		(start 128.4784 74.5125)
		(end 164.1875 74.5125)
		(width 0.125)
		(layer "In2.Cu")
		(net 53)
	)
	(segment
		(start 167.110823 71.430083)
		(end 167.11082 71.430081)
		(width 0.125)
		(layer "In2.Cu")
		(net 53)
	)
	(segment
		(start 166.105339 73.458089)
		(end 165.81752 73.17027)
		(width 0.125)
		(layer "In2.Cu")
		(net 53)
	)
	(segment
		(start 206.2284 60.9625)
		(end 207.0966 60.9625)
		(width 0.125)
		(layer "In2.Cu")
		(net 53)
	)
	(segment
		(start 166.711302 71.829595)
		(end 167.222598 72.340891)
		(width 0.125)
		(layer "In2.Cu")
		(net 53)
	)
	(segment
		(start 128.168031 73.987499)
		(end 128.168031 74.202131)
		(width 0.125)
		(layer "In2.Cu")
		(net 53)
	)
	(segment
		(start 168.228053 70.312853)
		(end 168.22805 70.312851)
		(width 0.125)
		(layer "In2.Cu")
		(net 53)
	)
	(segment
		(start 167.60014 70.483972)
		(end 167.828536 70.712367)
		(width 0.125)
		(layer "In2.Cu")
		(net 53)
	)
	(segment
		(start 165.81752 72.882477)
		(end 165.929244 72.770756)
		(width 0.125)
		(layer "In2.Cu")
		(net 53)
	)
	(segment
		(start 164.000942 73.300355)
		(end 164.112664 73.188634)
		(width 0.125)
		(layer "In2.Cu")
		(net 53)
	)
	(segment
		(start 207.519501 60.539599)
		(end 207.519501 59.987499)
		(width 0.125)
		(layer "In2.Cu")
		(net 53)
	)
	(segment
		(start 164.253402 73.84061)
		(end 164.000941 73.588149)
		(width 0.125)
		(layer "In2.Cu")
		(net 53)
	)
	(segment
		(start 167.60014 70.19618)
		(end 167.711865 70.084456)
		(width 0.125)
		(layer "In2.Cu")
		(net 53)
	)
	(segment
		(start 164.876366 73.664541)
		(end 164.876362 73.664539)
		(width 0.125)
		(layer "In2.Cu")
		(net 53)
	)
	(segment
		(start 169.097055 69.602944)
		(end 177.9375 60.7625)
		(width 0.125)
		(layer "In2.Cu")
		(net 53)
	)
	(segment
		(start 206.0284 60.7625)
		(end 206.2284 60.9625)
		(width 0.125)
		(layer "In2.Cu")
		(net 53)
	)
	(segment
		(start 164.1875 74.5125)
		(end 164.253402 74.4466)
		(width 0.125)
		(layer "In2.Cu")
		(net 53)
	)
	(arc
		(start 165.387626 74.175803)
		(mid 165.690622 74.301307)
		(end 165.993617 74.175803)
		(width 0.125)
		(layer "In2.Cu")
		(net 53)
	)
	(arc
		(start 164.000941 73.588149)
		(mid 163.941338 73.444252)
		(end 164.000942 73.300355)
		(width 0.125)
		(layer "In2.Cu")
		(net 53)
	)
	(arc
		(start 167.711865 70.084456)
		(mid 167.855761 70.024853)
		(end 167.999657 70.084457)
		(width 0.125)
		(layer "In2.Cu")
		(net 53)
	)
	(arc
		(start 166.864089 71.294805)
		(mid 166.919818 71.271721)
		(end 166.975545 71.294805)
		(width 0.125)
		(layer "In2.Cu")
		(net 53)
	)
	(arc
		(start 168.339798 71.829621)
		(mid 168.465303 71.526625)
		(end 168.339798 71.22363)
		(width 0.125)
		(layer "In2.Cu")
		(net 53)
	)
	(arc
		(start 169.097055 70.208112)
		(mid 169.192673 69.97727)
		(end 169.097055 69.746429)
		(width 0.125)
		(layer "In2.Cu")
		(net 53)
	)
	(arc
		(start 164.253402 74.4466)
		(mid 164.378907 74.143605)
		(end 164.253402 73.84061)
		(width 0.125)
		(layer "In2.Cu")
		(net 53)
	)
	(arc
		(start 166.576029 71.69432)
		(mid 166.552945 71.638593)
		(end 166.576029 71.582864)
		(width 0.125)
		(layer "In2.Cu")
		(net 53)
	)
	(arc
		(start 168.379342 70.464143)
		(mid 168.610184 70.55976)
		(end 168.841025 70.464143)
		(width 0.125)
		(layer "In2.Cu")
		(net 53)
	)
	(arc
		(start 166.105339 74.06408)
		(mid 166.230844 73.761084)
		(end 166.105339 73.458089)
		(width 0.125)
		(layer "In2.Cu")
		(net 53)
	)
	(arc
		(start 165.81752 73.17027)
		(mid 165.757916 73.026374)
		(end 165.81752 72.882477)
		(width 0.125)
		(layer "In2.Cu")
		(net 53)
	)
	(arc
		(start 165.929244 72.770756)
		(mid 166.07314 72.711152)
		(end 166.217036 72.770756)
		(width 0.125)
		(layer "In2.Cu")
		(net 53)
	)
	(arc
		(start 167.60014 70.483972)
		(mid 167.540536 70.340076)
		(end 167.60014 70.19618)
		(width 0.125)
		(layer "In2.Cu")
		(net 53)
	)
	(arc
		(start 164.112664 73.188634)
		(mid 164.256562 73.129029)
		(end 164.400458 73.188633)
		(width 0.125)
		(layer "In2.Cu")
		(net 53)
	)
	(arc
		(start 166.504885 73.058605)
		(mid 166.807881 73.184109)
		(end 167.110876 73.058605)
		(width 0.125)
		(layer "In2.Cu")
		(net 53)
	)
	(arc
		(start 167.622084 71.941345)
		(mid 167.92508 72.066849)
		(end 168.228075 71.941345)
		(width 0.125)
		(layer "In2.Cu")
		(net 53)
	)
	(arc
		(start 169.097055 69.746429)
		(mid 169.067338 69.674687)
		(end 169.097055 69.602944)
		(width 0.125)
		(layer "In2.Cu")
		(net 53)
	)
	(arc
		(start 167.222598 72.946882)
		(mid 167.348103 72.643886)
		(end 167.222598 72.340891)
		(width 0.125)
		(layer "In2.Cu")
		(net 53)
	)
	(segment
		(start 123.330532 79.65)
		(end 123.055532 79.925)
		(width 0.17)
		(layer "F.Cu")
		(net 54)
	)
	(segment
		(start 123.055532 80.275)
		(end 123.180532 80.4)
		(width 0.17)
		(layer "F.Cu")
		(net 54)
	)
	(segment
		(start 123.055532 79.925)
		(end 123.055532 80.275)
		(width 0.17)
		(layer "F.Cu")
		(net 54)
	)
	(via
		(at 65.796706 103.996706)
		(size 0.45)
		(drill 0.1)
		(layers "F.Cu" "B.Cu")
		(net 54)
	)
	(via
		(at 123.180532 80.4)
		(size 0.45)
		(drill 0.1)
		(layers "F.Cu" "B.Cu")
		(net 54)
	)
	(segment
		(start 65.115 104.535)
		(end 65.417512 104.535)
		(width 0.17)
		(layer "B.Cu")
		(net 54)
	)
	(segment
		(start 65.04 104.46)
		(end 65.115 104.535)
		(width 0.17)
		(layer "B.Cu")
		(net 54)
	)
	(segment
		(start 64.59 104.46)
		(end 65.04 104.46)
		(width 0.17)
		(layer "B.Cu")
		(net 54)
	)
	(segment
		(start 65.796706 104.155806)
		(end 65.796706 103.996706)
		(width 0.17)
		(layer "B.Cu")
		(net 54)
	)
	(segment
		(start 65.417512 104.535)
		(end 65.796706 104.155806)
		(width 0.17)
		(layer "B.Cu")
		(net 54)
	)
	(segment
		(start 95.2625 78.594097)
		(end 95.2625 79.605893)
		(width 0.125)
		(layer "In2.Cu")
		(net 54)
	)
	(segment
		(start 86.1534 83.2875)
		(end 86.3625 83.0784)
		(width 0.125)
		(layer "In2.Cu")
		(net 54)
	)
	(segment
		(start 119.1466 79.6625)
		(end 119.5591 80.075)
		(width 0.125)
		(layer "In2.Cu")
		(net 54)
	)
	(segment
		(start 95.5875 79.605893)
		(end 95.5875 78.75)
		(width 0.125)
		(layer "In2.Cu")
		(net 54)
	)
	(segment
		(start 106.40785 79.137939)
		(end 106.51785 79.137939)
		(width 0.125)
		(layer "In2.Cu")
		(net 54)
	)
	(segment
		(start 90.8625 78.694092)
		(end 90.8625 79.605893)
		(width 0.125)
		(layer "In2.Cu")
		(net 54)
	)
	(segment
		(start 65.3875 87.0534)
		(end 69.1534 83.2875)
		(width 0.125)
		(layer "In2.Cu")
		(net 54)
	)
	(segment
		(start 121.2534 78.9875)
		(end 122.0466 78.9875)
		(width 0.125)
		(layer "In2.Cu")
		(net 54)
	)
	(segment
		(start 65.796706 103.996706)
		(end 66.044194 103.996706)
		(width 0.125)
		(layer "In2.Cu")
		(net 54)
	)
	(segment
		(start 105.0625 79.7934)
		(end 105.4566 80.1875)
		(width 0.125)
		(layer "In2.Cu")
		(net 54)
	)
	(segment
		(start 90.0875 79.605893)
		(end 90.0875 78.694092)
		(width 0.125)
		(layer "In2.Cu")
		(net 54)
	)
	(segment
		(start 91.1875 79.605893)
		(end 91.1875 79.145)
		(width 0.125)
		(layer "In2.Cu")
		(net 54)
	)
	(segment
		(start 119.5591 80.075)
		(end 120.5659 80.075)
		(width 0.125)
		(layer "In2.Cu")
		(net 54)
	)
	(segment
		(start 92.2875 79.605893)
		(end 92.2875 78.394108)
		(width 0.125)
		(layer "In2.Cu")
		(net 54)
	)
	(segment
		(start 116.3866 80.1375)
		(end 117.6534 80.1375)
		(width 0.125)
		(layer "In2.Cu")
		(net 54)
	)
	(segment
		(start 94.4875 79.605893)
		(end 94.4875 78.594097)
		(width 0.125)
		(layer "In2.Cu")
		(net 54)
	)
	(segment
		(start 111.35785 80.1875)
		(end 111.8534 80.1875)
		(width 0.125)
		(layer "In2.Cu")
		(net 54)
	)
	(segment
		(start 120.7875 79.4534)
		(end 121.2534 78.9875)
		(width 0.125)
		(layer "In2.Cu")
		(net 54)
	)
	(segment
		(start 109.05035 80.52)
		(end 109.05035 81.07956)
		(width 0.125)
		(layer "In2.Cu")
		(net 54)
	)
	(segment
		(start 110.80785 80.787084)
		(end 110.91785 80.787084)
		(width 0.125)
		(layer "In2.Cu")
		(net 54)
	)
	(segment
		(start 94.1625 78.04409)
		(end 94.1625 79.605893)
		(width 0.125)
		(layer "In2.Cu")
		(net 54)
	)
	(segment
		(start 122.993033 80.212501)
		(end 123.180532 80.4)
		(width 0.125)
		(layer "In2.Cu")
		(net 54)
	)
	(segment
		(start 94.27 79.713393)
		(end 94.38 79.713393)
		(width 0.125)
		(layer "In2.Cu")
		(net 54)
	)
	(segment
		(start 66.1875 103.8534)
		(end 66.1875 101.0466)
		(width 0.125)
		(layer "In2.Cu")
		(net 54)
	)
	(segment
		(start 110.70035 79.42044)
		(end 110.70035 80.679584)
		(width 0.125)
		(layer "In2.Cu")
		(net 54)
	)
	(segment
		(start 120.5659 80.075)
		(end 120.7875 79.8534)
		(width 0.125)
		(layer "In2.Cu")
		(net 54)
	)
	(segment
		(start 106.85035 79.470439)
		(end 106.85035 80.579565)
		(width 0.125)
		(layer "In2.Cu")
		(net 54)
	)
	(segment
		(start 106.07535 80.475)
		(end 106.07535 79.470439)
		(width 0.125)
		(layer "In2.Cu")
		(net 54)
	)
	(segment
		(start 113.1534 78.8875)
		(end 113.6966 78.8875)
		(width 0.125)
		(layer "In2.Cu")
		(net 54)
	)
	(segment
		(start 108.60785 80.1875)
		(end 108.71785 80.1875)
		(width 0.125)
		(layer "In2.Cu")
		(net 54)
	)
	(segment
		(start 107.17535 80.579565)
		(end 107.17535 80.070439)
		(width 0.125)
		(layer "In2.Cu")
		(net 54)
	)
	(segment
		(start 109.15785 81.18706)
		(end 109.26785 81.18706)
		(width 0.125)
		(layer "In2.Cu")
		(net 54)
	)
	(segment
		(start 97.51875 78.8125)
		(end 104.7216 78.8125)
		(width 0.125)
		(layer "In2.Cu")
		(net 54)
	)
	(segment
		(start 94.82 78.261597)
		(end 94.93 78.261597)
		(width 0.125)
		(layer "In2.Cu")
		(net 54)
	)
	(segment
		(start 117.6534 80.1375)
		(end 118.1284 79.6625)
		(width 0.125)
		(layer "In2.Cu")
		(net 54)
	)
	(segment
		(start 66.044194 103.996706)
		(end 66.1875 103.8534)
		(width 0.125)
		(layer "In2.Cu")
		(net 54)
	)
	(segment
		(start 104.7216 78.8125)
		(end 105.0625 79.1534)
		(width 0.125)
		(layer "In2.Cu")
		(net 54)
	)
	(segment
		(start 108.05785 80.737081)
		(end 108.16785 80.737081)
		(width 0.125)
		(layer "In2.Cu")
		(net 54)
	)
	(segment
		(start 111.02535 80.679584)
		(end 111.02535 80.52)
		(width 0.125)
		(layer "In2.Cu")
		(net 54)
	)
	(segment
		(start 89.87 79.713393)
		(end 89.98 79.713393)
		(width 0.125)
		(layer "In2.Cu")
		(net 54)
	)
	(segment
		(start 90.97 79.713393)
		(end 91.08 79.713393)
		(width 0.125)
		(layer "In2.Cu")
		(net 54)
	)
	(segment
		(start 110.25785 79.08794)
		(end 110.36785 79.08794)
		(width 0.125)
		(layer "In2.Cu")
		(net 54)
	)
	(segment
		(start 93.0625 78.394108)
		(end 93.0625 78.705)
		(width 0.125)
		(layer "In2.Cu")
		(net 54)
	)
	(segment
		(start 109.92535 80.08)
		(end 109.92535 79.42044)
		(width 0.125)
		(layer "In2.Cu")
		(net 54)
	)
	(segment
		(start 93.72 77.71159)
		(end 93.83 77.71159)
		(width 0.125)
		(layer "In2.Cu")
		(net 54)
	)
	(segment
		(start 114.9466 79.6875)
		(end 115.3966 80.1375)
		(width 0.125)
		(layer "In2.Cu")
		(net 54)
	)
	(segment
		(start 105.8066 80.5375)
		(end 106.01285 80.5375)
		(width 0.125)
		(layer "In2.Cu")
		(net 54)
	)
	(segment
		(start 118.1284 79.6625)
		(end 119.1466 79.6625)
		(width 0.125)
		(layer "In2.Cu")
		(net 54)
	)
	(segment
		(start 86.8784 78.8125)
		(end 89.43 78.8125)
		(width 0.125)
		(layer "In2.Cu")
		(net 54)
	)
	(segment
		(start 115.8366 80.587061)
		(end 115.9466 80.587061)
		(width 0.125)
		(layer "In2.Cu")
		(net 54)
	)
	(segment
		(start 89.7625 79.145)
		(end 89.7625 79.605893)
		(width 0.125)
		(layer "In2.Cu")
		(net 54)
	)
	(segment
		(start 96.425 78.8125)
		(end 96.61875 78.8125)
		(width 0.125)
		(layer "In2.Cu")
		(net 54)
	)
	(segment
		(start 93.3875 78.705)
		(end 93.3875 78.04409)
		(width 0.125)
		(layer "In2.Cu")
		(net 54)
	)
	(segment
		(start 107.95035 80.070439)
		(end 107.95035 80.629581)
		(width 0.125)
		(layer "In2.Cu")
		(net 54)
	)
	(segment
		(start 105.0625 79.1534)
		(end 105.0625 79.7934)
		(width 0.125)
		(layer "In2.Cu")
		(net 54)
	)
	(segment
		(start 65.3875 100.2466)
		(end 65.3875 87.0534)
		(width 0.125)
		(layer "In2.Cu")
		(net 54)
	)
	(segment
		(start 108.27535 80.629581)
		(end 108.27535 80.52)
		(width 0.125)
		(layer "In2.Cu")
		(net 54)
	)
	(segment
		(start 86.3625 83.0784)
		(end 86.3625 79.3284)
		(width 0.125)
		(layer "In2.Cu")
		(net 54)
	)
	(segment
		(start 66.1875 101.0466)
		(end 65.3875 100.2466)
		(width 0.125)
		(layer "In2.Cu")
		(net 54)
	)
	(segment
		(start 93.17 78.8125)
		(end 93.28 78.8125)
		(width 0.125)
		(layer "In2.Cu")
		(net 54)
	)
	(segment
		(start 120.7875 79.8534)
		(end 120.7875 79.4534)
		(width 0.125)
		(layer "In2.Cu")
		(net 54)
	)
	(segment
		(start 69.1534 83.2875)
		(end 86.1534 83.2875)
		(width 0.125)
		(layer "In2.Cu")
		(net 54)
	)
	(segment
		(start 106.95785 80.687065)
		(end 107.06785 80.687065)
		(width 0.125)
		(layer "In2.Cu")
		(net 54)
	)
	(segment
		(start 92.62 78.061608)
		(end 92.73 78.061608)
		(width 0.125)
		(layer "In2.Cu")
		(net 54)
	)
	(segment
		(start 90.42 78.361592)
		(end 90.53 78.361592)
		(width 0.125)
		(layer "In2.Cu")
		(net 54)
	)
	(segment
		(start 91.9625 79.145)
		(end 91.9625 79.605893)
		(width 0.125)
		(layer "In2.Cu")
		(net 54)
	)
	(segment
		(start 109.70785 80.1875)
		(end 109.81785 80.1875)
		(width 0.125)
		(layer "In2.Cu")
		(net 54)
	)
	(segment
		(start 109.37535 81.07956)
		(end 109.37535 80.52)
		(width 0.125)
		(layer "In2.Cu")
		(net 54)
	)
	(segment
		(start 114.4966 79.6875)
		(end 114.9466 79.6875)
		(width 0.125)
		(layer "In2.Cu")
		(net 54)
	)
	(segment
		(start 96.96875 78.4625)
		(end 97.16875 78.4625)
		(width 0.125)
		(layer "In2.Cu")
		(net 54)
	)
	(segment
		(start 91.52 78.8125)
		(end 91.63 78.8125)
		(width 0.125)
		(layer "In2.Cu")
		(net 54)
	)
	(segment
		(start 107.50785 79.737939)
		(end 107.61785 79.737939)
		(width 0.125)
		(layer "In2.Cu")
		(net 54)
	)
	(segment
		(start 115.7291 80.47)
		(end 115.7291 80.479561)
		(width 0.125)
		(layer "In2.Cu")
		(net 54)
	)
	(segment
		(start 116.0541 80.479561)
		(end 116.0541 80.47)
		(width 0.125)
		(layer "In2.Cu")
		(net 54)
	)
	(segment
		(start 92.07 79.713393)
		(end 92.18 79.713393)
		(width 0.125)
		(layer "In2.Cu")
		(net 54)
	)
	(segment
		(start 95.37 79.713393)
		(end 95.48 79.713393)
		(width 0.125)
		(layer "In2.Cu")
		(net 54)
	)
	(segment
		(start 95.875 78.4625)
		(end 96.075 78.4625)
		(width 0.125)
		(layer "In2.Cu")
		(net 54)
	)
	(segment
		(start 122.0466 78.9875)
		(end 122.993033 79.933933)
		(width 0.125)
		(layer "In2.Cu")
		(net 54)
	)
	(segment
		(start 86.3625 79.3284)
		(end 86.8784 78.8125)
		(width 0.125)
		(layer "In2.Cu")
		(net 54)
	)
	(segment
		(start 122.993033 79.933933)
		(end 122.993033 80.212501)
		(width 0.125)
		(layer "In2.Cu")
		(net 54)
	)
	(segment
		(start 111.8534 80.1875)
		(end 113.1534 78.8875)
		(width 0.125)
		(layer "In2.Cu")
		(net 54)
	)
	(segment
		(start 113.6966 78.8875)
		(end 114.4966 79.6875)
		(width 0.125)
		(layer "In2.Cu")
		(net 54)
	)
	(arc
		(start 97.16875 78.4625)
		(mid 97.372043 78.546707)
		(end 97.45625 78.75)
		(width 0.125)
		(layer "In2.Cu")
		(net 54)
	)
	(arc
		(start 91.63 78.8125)
		(mid 91.865113 78.909887)
		(end 91.9625 79.145)
		(width 0.125)
		(layer "In2.Cu")
		(net 54)
	)
	(arc
		(start 115.3966 80.1375)
		(mid 115.631713 80.234887)
		(end 115.7291 80.47)
		(width 0.125)
		(layer "In2.Cu")
		(net 54)
	)
	(arc
		(start 92.2875 78.394108)
		(mid 92.384887 78.158995)
		(end 92.62 78.061608)
		(width 0.125)
		(layer "In2.Cu")
		(net 54)
	)
	(arc
		(start 96.3625 78.75)
		(mid 96.380806 78.794194)
		(end 96.425 78.8125)
		(width 0.125)
		(layer "In2.Cu")
		(net 54)
	)
	(arc
		(start 95.48 79.713393)
		(mid 95.556014 79.681907)
		(end 95.5875 79.605893)
		(width 0.125)
		(layer "In2.Cu")
		(net 54)
	)
	(arc
		(start 107.61785 79.737939)
		(mid 107.852963 79.835326)
		(end 107.95035 80.070439)
		(width 0.125)
		(layer "In2.Cu")
		(net 54)
	)
	(arc
		(start 111.02535 80.52)
		(mid 111.122737 80.284887)
		(end 111.35785 80.1875)
		(width 0.125)
		(layer "In2.Cu")
		(net 54)
	)
	(arc
		(start 109.81785 80.1875)
		(mid 109.893864 80.156014)
		(end 109.92535 80.08)
		(width 0.125)
		(layer "In2.Cu")
		(net 54)
	)
	(arc
		(start 109.26785 81.18706)
		(mid 109.343864 81.155574)
		(end 109.37535 81.07956)
		(width 0.125)
		(layer "In2.Cu")
		(net 54)
	)
	(arc
		(start 106.51785 79.137939)
		(mid 106.752963 79.235326)
		(end 106.85035 79.470439)
		(width 0.125)
		(layer "In2.Cu")
		(net 54)
	)
	(arc
		(start 92.18 79.713393)
		(mid 92.256014 79.681907)
		(end 92.2875 79.605893)
		(width 0.125)
		(layer "In2.Cu")
		(net 54)
	)
	(arc
		(start 97.45625 78.75)
		(mid 97.474556 78.794194)
		(end 97.51875 78.8125)
		(width 0.125)
		(layer "In2.Cu")
		(net 54)
	)
	(arc
		(start 89.98 79.713393)
		(mid 90.056014 79.681907)
		(end 90.0875 79.605893)
		(width 0.125)
		(layer "In2.Cu")
		(net 54)
	)
	(arc
		(start 106.07535 79.470439)
		(mid 106.172737 79.235326)
		(end 106.40785 79.137939)
		(width 0.125)
		(layer "In2.Cu")
		(net 54)
	)
	(arc
		(start 96.68125 78.75)
		(mid 96.765457 78.546707)
		(end 96.96875 78.4625)
		(width 0.125)
		(layer "In2.Cu")
		(net 54)
	)
	(arc
		(start 91.08 79.713393)
		(mid 91.156014 79.681907)
		(end 91.1875 79.605893)
		(width 0.125)
		(layer "In2.Cu")
		(net 54)
	)
	(arc
		(start 109.37535 80.52)
		(mid 109.472737 80.284887)
		(end 109.70785 80.1875)
		(width 0.125)
		(layer "In2.Cu")
		(net 54)
	)
	(arc
		(start 106.01285 80.5375)
		(mid 106.057044 80.519194)
		(end 106.07535 80.475)
		(width 0.125)
		(layer "In2.Cu")
		(net 54)
	)
	(arc
		(start 116.0541 80.47)
		(mid 116.151487 80.234887)
		(end 116.3866 80.1375)
		(width 0.125)
		(layer "In2.Cu")
		(net 54)
	)
	(arc
		(start 107.95035 80.629581)
		(mid 107.981836 80.705595)
		(end 108.05785 80.737081)
		(width 0.125)
		(layer "In2.Cu")
		(net 54)
	)
	(arc
		(start 92.73 78.061608)
		(mid 92.965113 78.158995)
		(end 93.0625 78.394108)
		(width 0.125)
		(layer "In2.Cu")
		(net 54)
	)
	(arc
		(start 93.3875 78.04409)
		(mid 93.484887 77.808977)
		(end 93.72 77.71159)
		(width 0.125)
		(layer "In2.Cu")
		(net 54)
	)
	(arc
		(start 91.1875 79.145)
		(mid 91.284887 78.909887)
		(end 91.52 78.8125)
		(width 0.125)
		(layer "In2.Cu")
		(net 54)
	)
	(arc
		(start 96.61875 78.8125)
		(mid 96.662944 78.794194)
		(end 96.68125 78.75)
		(width 0.125)
		(layer "In2.Cu")
		(net 54)
	)
	(arc
		(start 109.05035 81.07956)
		(mid 109.081836 81.155574)
		(end 109.15785 81.18706)
		(width 0.125)
		(layer "In2.Cu")
		(net 54)
	)
	(arc
		(start 94.1625 79.605893)
		(mid 94.193986 79.681907)
		(end 94.27 79.713393)
		(width 0.125)
		(layer "In2.Cu")
		(net 54)
	)
	(arc
		(start 115.9466 80.587061)
		(mid 116.022614 80.555575)
		(end 116.0541 80.479561)
		(width 0.125)
		(layer "In2.Cu")
		(net 54)
	)
	(arc
		(start 90.53 78.361592)
		(mid 90.765113 78.458979)
		(end 90.8625 78.694092)
		(width 0.125)
		(layer "In2.Cu")
		(net 54)
	)
	(arc
		(start 95.2625 79.605893)
		(mid 95.293986 79.681907)
		(end 95.37 79.713393)
		(width 0.125)
		(layer "In2.Cu")
		(net 54)
	)
	(arc
		(start 108.71785 80.1875)
		(mid 108.952963 80.284887)
		(end 109.05035 80.52)
		(width 0.125)
		(layer "In2.Cu")
		(net 54)
	)
	(arc
		(start 110.70035 80.679584)
		(mid 110.731836 80.755598)
		(end 110.80785 80.787084)
		(width 0.125)
		(layer "In2.Cu")
		(net 54)
	)
	(arc
		(start 105.4566 80.1875)
		(mid 105.659893 80.271707)
		(end 105.7441 80.475)
		(width 0.125)
		(layer "In2.Cu")
		(net 54)
	)
	(arc
		(start 110.36785 79.08794)
		(mid 110.602963 79.185327)
		(end 110.70035 79.42044)
		(width 0.125)
		(layer "In2.Cu")
		(net 54)
	)
	(arc
		(start 89.43 78.8125)
		(mid 89.665113 78.909887)
		(end 89.7625 79.145)
		(width 0.125)
		(layer "In2.Cu")
		(net 54)
	)
	(arc
		(start 105.7441 80.475)
		(mid 105.762406 80.519194)
		(end 105.8066 80.5375)
		(width 0.125)
		(layer "In2.Cu")
		(net 54)
	)
	(arc
		(start 90.0875 78.694092)
		(mid 90.184887 78.458979)
		(end 90.42 78.361592)
		(width 0.125)
		(layer "In2.Cu")
		(net 54)
	)
	(arc
		(start 94.4875 78.594097)
		(mid 94.584887 78.358984)
		(end 94.82 78.261597)
		(width 0.125)
		(layer "In2.Cu")
		(net 54)
	)
	(arc
		(start 89.7625 79.605893)
		(mid 89.793986 79.681907)
		(end 89.87 79.713393)
		(width 0.125)
		(layer "In2.Cu")
		(net 54)
	)
	(arc
		(start 94.93 78.261597)
		(mid 95.165113 78.358984)
		(end 95.2625 78.594097)
		(width 0.125)
		(layer "In2.Cu")
		(net 54)
	)
	(arc
		(start 108.16785 80.737081)
		(mid 108.243864 80.705595)
		(end 108.27535 80.629581)
		(width 0.125)
		(layer "In2.Cu")
		(net 54)
	)
	(arc
		(start 108.27535 80.52)
		(mid 108.372737 80.284887)
		(end 108.60785 80.1875)
		(width 0.125)
		(layer "In2.Cu")
		(net 54)
	)
	(arc
		(start 93.0625 78.705)
		(mid 93.093986 78.781014)
		(end 93.17 78.8125)
		(width 0.125)
		(layer "In2.Cu")
		(net 54)
	)
	(arc
		(start 115.7291 80.479561)
		(mid 115.760586 80.555575)
		(end 115.8366 80.587061)
		(width 0.125)
		(layer "In2.Cu")
		(net 54)
	)
	(arc
		(start 93.83 77.71159)
		(mid 94.065113 77.808977)
		(end 94.1625 78.04409)
		(width 0.125)
		(layer "In2.Cu")
		(net 54)
	)
	(arc
		(start 94.38 79.713393)
		(mid 94.456014 79.681907)
		(end 94.4875 79.605893)
		(width 0.125)
		(layer "In2.Cu")
		(net 54)
	)
	(arc
		(start 106.85035 80.579565)
		(mid 106.881836 80.655579)
		(end 106.95785 80.687065)
		(width 0.125)
		(layer "In2.Cu")
		(net 54)
	)
	(arc
		(start 95.5875 78.75)
		(mid 95.671707 78.546707)
		(end 95.875 78.4625)
		(width 0.125)
		(layer "In2.Cu")
		(net 54)
	)
	(arc
		(start 93.28 78.8125)
		(mid 93.356014 78.781014)
		(end 93.3875 78.705)
		(width 0.125)
		(layer "In2.Cu")
		(net 54)
	)
	(arc
		(start 110.91785 80.787084)
		(mid 110.993864 80.755598)
		(end 111.02535 80.679584)
		(width 0.125)
		(layer "In2.Cu")
		(net 54)
	)
	(arc
		(start 91.9625 79.605893)
		(mid 91.993986 79.681907)
		(end 92.07 79.713393)
		(width 0.125)
		(layer "In2.Cu")
		(net 54)
	)
	(arc
		(start 96.075 78.4625)
		(mid 96.278293 78.546707)
		(end 96.3625 78.75)
		(width 0.125)
		(layer "In2.Cu")
		(net 54)
	)
	(arc
		(start 90.8625 79.605893)
		(mid 90.893986 79.681907)
		(end 90.97 79.713393)
		(width 0.125)
		(layer "In2.Cu")
		(net 54)
	)
	(arc
		(start 109.92535 79.42044)
		(mid 110.022737 79.185327)
		(end 110.25785 79.08794)
		(width 0.125)
		(layer "In2.Cu")
		(net 54)
	)
	(arc
		(start 107.06785 80.687065)
		(mid 107.143864 80.655579)
		(end 107.17535 80.579565)
		(width 0.125)
		(layer "In2.Cu")
		(net 54)
	)
	(arc
		(start 107.17535 80.070439)
		(mid 107.272737 79.835326)
		(end 107.50785 79.737939)
		(width 0.125)
		(layer "In2.Cu")
		(net 54)
	)
	(segment
		(start 224.182488 89.015)
		(end 222.726062 89.015)
		(width 0.17)
		(layer "F.Cu")
		(net 55)
	)
	(segment
		(start 224.712132 88.662132)
		(end 224.535356 88.662132)
		(width 0.17)
		(layer "F.Cu")
		(net 55)
	)
	(segment
		(start 222.201633 89.087)
		(end 221.789132 89.087)
		(width 0.17)
		(layer "F.Cu")
		(net 55)
	)
	(segment
		(start 232.930532 90.3475)
		(end 232.930532 91.539468)
		(width 0.17)
		(layer "F.Cu")
		(net 55)
	)
	(segment
		(start 222.276633 89.012)
		(end 222.201633 89.087)
		(width 0.17)
		(layer "F.Cu")
		(net 55)
	)
	(segment
		(start 95.055532 82.375)
		(end 95.055532 81.875)
		(width 0.17)
		(layer "F.Cu")
		(net 55)
	)
	(segment
		(start 224.535356 88.662132)
		(end 224.182488 89.015)
		(width 0.17)
		(layer "F.Cu")
		(net 55)
	)
	(segment
		(start 222.726062 89.015)
		(end 222.723062 89.012)
		(width 0.17)
		(layer "F.Cu")
		(net 55)
	)
	(segment
		(start 219.825 89.012)
		(end 219.7 89.137)
		(width 0.17)
		(layer "F.Cu")
		(net 55)
	)
	(segment
		(start 232.430532 86.860532)
		(end 232.42 86.85)
		(width 0.17)
		(layer "F.Cu")
		(net 55)
	)
	(segment
		(start 95.055532 81.875)
		(end 95.180532 81.75)
		(width 0.17)
		(layer "F.Cu")
		(net 55)
	)
	(segment
		(start 222.723062 89.012)
		(end 222.276633 89.012)
		(width 0.17)
		(layer "F.Cu")
		(net 55)
	)
	(segment
		(start 220.604631 89.087)
		(end 220.529631 89.012)
		(width 0.17)
		(layer "F.Cu")
		(net 55)
	)
	(segment
		(start 95.330532 82.65)
		(end 95.055532 82.375)
		(width 0.17)
		(layer "F.Cu")
		(net 55)
	)
	(segment
		(start 232.930532 91.539468)
		(end 232.92 91.55)
		(width 0.17)
		(layer "F.Cu")
		(net 55)
	)
	(segment
		(start 232.430532 88.0725)
		(end 232.430532 86.860532)
		(width 0.17)
		(layer "F.Cu")
		(net 55)
	)
	(segment
		(start 220.529631 89.012)
		(end 219.825 89.012)
		(width 0.17)
		(layer "F.Cu")
		(net 55)
	)
	(segment
		(start 221.789132 89.087)
		(end 221.017132 89.087)
		(width 0.17)
		(layer "F.Cu")
		(net 55)
	)
	(segment
		(start 221.017132 89.087)
		(end 220.604631 89.087)
		(width 0.17)
		(layer "F.Cu")
		(net 55)
	)
	(via
		(at 232.92 91.55)
		(size 0.45)
		(drill 0.1)
		(layers "F.Cu" "B.Cu")
		(net 55)
	)
	(via
		(at 219.7 89.137)
		(size 0.45)
		(drill 0.1)
		(layers "F.Cu" "B.Cu")
		(net 55)
	)
	(via
		(at 224.712132 88.662132)
		(size 0.45)
		(drill 0.1)
		(layers "F.Cu" "B.Cu")
		(net 55)
	)
	(via
		(at 95.180532 81.75)
		(size 0.45)
		(drill 0.1)
		(layers "F.Cu" "B.Cu")
		(net 55)
	)
	(via
		(at 232.42 86.85)
		(size 0.45)
		(drill 0.1)
		(layers "F.Cu" "B.Cu")
		(net 55)
	)
	(segment
		(start 232.495 86.775)
		(end 232.495 85.552488)
		(width 0.17)
		(layer "B.Cu")
		(net 55)
	)
	(segment
		(start 224.712132 88.485356)
		(end 224.712132 88.662132)
		(width 0.17)
		(layer "B.Cu")
		(net 55)
	)
	(segment
		(start 232.495 85.552488)
		(end 231.667512 84.725)
		(width 0.17)
		(layer "B.Cu")
		(net 55)
	)
	(segment
		(start 226.822488 84.725)
		(end 225.325 86.222488)
		(width 0.17)
		(layer "B.Cu")
		(net 55)
	)
	(segment
		(start 225.325 87.872488)
		(end 224.712132 88.485356)
		(width 0.17)
		(layer "B.Cu")
		(net 55)
	)
	(segment
		(start 232.42 86.85)
		(end 232.495 86.775)
		(width 0.17)
		(layer "B.Cu")
		(net 55)
	)
	(segment
		(start 231.667512 84.725)
		(end 226.822488 84.725)
		(width 0.17)
		(layer "B.Cu")
		(net 55)
	)
	(segment
		(start 225.325 86.222488)
		(end 225.325 87.872488)
		(width 0.17)
		(layer "B.Cu")
		(net 55)
	)
	(segment
		(start 232.42 88.85)
		(end 232.92 89.35)
		(width 0.125)
		(layer "In2.Cu")
		(net 55)
	)
	(segment
		(start 232.92 89.35)
		(end 232.92 91.55)
		(width 0.125)
		(layer "In2.Cu")
		(net 55)
	)
	(segment
		(start 232.42 86.85)
		(end 232.42 88.85)
		(width 0.125)
		(layer "In2.Cu")
		(net 55)
	)
	(segment
		(start 95.8875 81.8534)
		(end 95.8875 81.3534)
		(width 0.125)
		(layer "In7.Cu")
		(net 55)
	)
	(segment
		(start 162.8216 69.8625)
		(end 167.2534 69.8625)
		(width 0.125)
		(layer "In7.Cu")
		(net 55)
	)
	(segment
		(start 100.8875 74.9034)
		(end 100.8875 72.4034)
		(width 0.125)
		(layer "In7.Cu")
		(net 55)
	)
	(segment
		(start 105.5375 67.7534)
		(end 105.5375 64.7034)
		(width 0.125)
		(layer "In7.Cu")
		(net 55)
	)
	(segment
		(start 95.5534 82.1875)
		(end 95.8875 81.8534)
		(width 0.125)
		(layer "In7.Cu")
		(net 55)
	)
	(segment
		(start 105.5375 64.7034)
		(end 107.2134 63.0275)
		(width 0.125)
		(layer "In7.Cu")
		(net 55)
	)
	(segment
		(start 187.0716 69.7125)
		(end 189.8466 72.4875)
		(width 0.125)
		(layer "In7.Cu")
		(net 55)
	)
	(segment
		(start 176.2716 69.2125)
		(end 176.7716 69.7125)
		(width 0.125)
		(layer "In7.Cu")
		(net 55)
	)
	(segment
		(start 98.6875 79.1034)
		(end 98.6875 77.8534)
		(width 0.125)
		(layer "In7.Cu")
		(net 55)
	)
	(segment
		(start 167.2534 69.8625)
		(end 167.9034 69.2125)
		(width 0.125)
		(layer "In7.Cu")
		(net 55)
	)
	(segment
		(start 95.0966 82.1875)
		(end 95.5534 82.1875)
		(width 0.125)
		(layer "In7.Cu")
		(net 55)
	)
	(segment
		(start 107.2134 63.0275)
		(end 109.0725 63.0275)
		(width 0.125)
		(layer "In7.Cu")
		(net 55)
	)
	(segment
		(start 215.5125 78.7534)
		(end 215.5125 80.7534)
		(width 0.125)
		(layer "In7.Cu")
		(net 55)
	)
	(segment
		(start 162.6466 69.6875)
		(end 162.8216 69.8625)
		(width 0.125)
		(layer "In7.Cu")
		(net 55)
	)
	(segment
		(start 139.9466 57.8375)
		(end 147.5625 65.4534)
		(width 0.125)
		(layer "In7.Cu")
		(net 55)
	)
	(segment
		(start 194.8034 71.9375)
		(end 208.6966 71.9375)
		(width 0.125)
		(layer "In7.Cu")
		(net 55)
	)
	(segment
		(start 95.8875 81.3534)
		(end 96.9034 80.3375)
		(width 0.125)
		(layer "In7.Cu")
		(net 55)
	)
	(segment
		(start 194.2534 72.4875)
		(end 194.8034 71.9375)
		(width 0.125)
		(layer "In7.Cu")
		(net 55)
	)
	(segment
		(start 217.9466 81.9875)
		(end 220.5625 84.6034)
		(width 0.125)
		(layer "In7.Cu")
		(net 55)
	)
	(segment
		(start 215.5125 80.7534)
		(end 216.7466 81.9875)
		(width 0.125)
		(layer "In7.Cu")
		(net 55)
	)
	(segment
		(start 94.993033 81.937499)
		(end 94.993033 82.083933)
		(width 0.125)
		(layer "In7.Cu")
		(net 55)
	)
	(segment
		(start 208.6966 71.9375)
		(end 215.5125 78.7534)
		(width 0.125)
		(layer "In7.Cu")
		(net 55)
	)
	(segment
		(start 216.7466 81.9875)
		(end 217.9466 81.9875)
		(width 0.125)
		(layer "In7.Cu")
		(net 55)
	)
	(segment
		(start 95.180532 81.75)
		(end 94.993033 81.937499)
		(width 0.125)
		(layer "In7.Cu")
		(net 55)
	)
	(segment
		(start 96.9034 80.3375)
		(end 97.4534 80.3375)
		(width 0.125)
		(layer "In7.Cu")
		(net 55)
	)
	(segment
		(start 219.887499 88.949501)
		(end 219.7 89.137)
		(width 0.125)
		(layer "In7.Cu")
		(net 55)
	)
	(segment
		(start 114.2625 57.8375)
		(end 139.9466 57.8375)
		(width 0.125)
		(layer "In7.Cu")
		(net 55)
	)
	(segment
		(start 147.5625 65.4534)
		(end 147.5625 67.8034)
		(width 0.125)
		(layer "In7.Cu")
		(net 55)
	)
	(segment
		(start 94.993033 82.083933)
		(end 95.0966 82.1875)
		(width 0.125)
		(layer "In7.Cu")
		(net 55)
	)
	(segment
		(start 97.4534 80.3375)
		(end 98.6875 79.1034)
		(width 0.125)
		(layer "In7.Cu")
		(net 55)
	)
	(segment
		(start 147.5625 67.8034)
		(end 149.4466 69.6875)
		(width 0.125)
		(layer "In7.Cu")
		(net 55)
	)
	(segment
		(start 109.0725 63.0275)
		(end 114.2625 57.8375)
		(width 0.125)
		(layer "In7.Cu")
		(net 55)
	)
	(segment
		(start 220.5625 88.5966)
		(end 220.209599 88.949501)
		(width 0.125)
		(layer "In7.Cu")
		(net 55)
	)
	(segment
		(start 220.209599 88.949501)
		(end 219.887499 88.949501)
		(width 0.125)
		(layer "In7.Cu")
		(net 55)
	)
	(segment
		(start 167.9034 69.2125)
		(end 176.2716 69.2125)
		(width 0.125)
		(layer "In7.Cu")
		(net 55)
	)
	(segment
		(start 99.4375 76.3534)
		(end 100.8875 74.9034)
		(width 0.125)
		(layer "In7.Cu")
		(net 55)
	)
	(segment
		(start 220.5625 84.6034)
		(end 220.5625 88.5966)
		(width 0.125)
		(layer "In7.Cu")
		(net 55)
	)
	(segment
		(start 99.4375 77.1034)
		(end 99.4375 76.3534)
		(width 0.125)
		(layer "In7.Cu")
		(net 55)
	)
	(segment
		(start 100.8875 72.4034)
		(end 105.5375 67.7534)
		(width 0.125)
		(layer "In7.Cu")
		(net 55)
	)
	(segment
		(start 98.6875 77.8534)
		(end 99.4375 77.1034)
		(width 0.125)
		(layer "In7.Cu")
		(net 55)
	)
	(segment
		(start 176.7716 69.7125)
		(end 187.0716 69.7125)
		(width 0.125)
		(layer "In7.Cu")
		(net 55)
	)
	(segment
		(start 149.4466 69.6875)
		(end 162.6466 69.6875)
		(width 0.125)
		(layer "In7.Cu")
		(net 55)
	)
	(segment
		(start 189.8466 72.4875)
		(end 194.2534 72.4875)
		(width 0.125)
		(layer "In7.Cu")
		(net 55)
	)
	(segment
		(start 128.5 99.8)
		(end 129.975 99.8)
		(width 0.1)
		(layer "F.Cu")
		(net 56)
	)
	(segment
		(start 140.630532 72.15)
		(end 140.6 72.15)
		(width 0.1)
		(layer "F.Cu")
		(net 56)
	)
	(segment
		(start 129.975 99.8)
		(end 130.375 100.2)
		(width 0.1)
		(layer "F.Cu")
		(net 56)
	)
	(segment
		(start 130.375 100.2)
		(end 131.8 100.2)
		(width 0.1)
		(layer "F.Cu")
		(net 56)
	)
	(via
		(at 128.5 99.8)
		(size 0.45)
		(drill 0.1)
		(layers "F.Cu" "B.Cu")
		(net 56)
	)
	(via
		(at 140.6 72.15)
		(size 0.45)
		(drill 0.1)
		(layers "F.Cu" "B.Cu")
		(net 56)
	)
	(via
		(at 79.585532 95.455)
		(size 0.45)
		(drill 0.1)
		(layers "F.Cu" "B.Cu")
		(net 56)
	)
	(via
		(at 131.8 100.2)
		(size 0.45)
		(drill 0.1)
		(layers "F.Cu" "B.Cu")
		(net 56)
	)
	(segment
		(start 123.640682 99.825)
		(end 128.475 99.825)
		(width 0.1)
		(layer "In5.Cu")
		(net 56)
	)
	(segment
		(start 86.775 116)
		(end 94.36863 116)
		(width 0.1)
		(layer "In5.Cu")
		(net 56)
	)
	(segment
		(start 78.7 102.25)
		(end 79.15 102.7)
		(width 0.1)
		(layer "In5.Cu")
		(net 56)
	)
	(segment
		(start 134.7 94.402944)
		(end 141.100001 88.002943)
		(width 0.1)
		(layer "In5.Cu")
		(net 56)
	)
	(segment
		(start 140.9 73.8)
		(end 140.9 73.1)
		(width 0.1)
		(layer "In5.Cu")
		(net 56)
	)
	(segment
		(start 133.4 100.2)
		(end 134.7 98.9)
		(width 0.1)
		(layer "In5.Cu")
		(net 56)
	)
	(segment
		(start 140.9 73.1)
		(end 140.6 72.8)
		(width 0.1)
		(layer "In5.Cu")
		(net 56)
	)
	(segment
		(start 142 82.6)
		(end 142 81.725)
		(width 0.1)
		(layer "In5.Cu")
		(net 56)
	)
	(segment
		(start 100.4 102.8)
		(end 120.665682 102.8)
		(width 0.1)
		(layer "In5.Cu")
		(net 56)
	)
	(segment
		(start 120.665682 102.8)
		(end 123.640682 99.825)
		(width 0.1)
		(layer "In5.Cu")
		(net 56)
	)
	(segment
		(start 86.375 116.4)
		(end 86.775 116)
		(width 0.1)
		(layer "In5.Cu")
		(net 56)
	)
	(segment
		(start 141.100001 88.002943)
		(end 141.100001 83.499999)
		(width 0.1)
		(layer "In5.Cu")
		(net 56)
	)
	(segment
		(start 128.475 99.825)
		(end 128.5 99.8)
		(width 0.1)
		(layer "In5.Cu")
		(net 56)
	)
	(segment
		(start 141.100001 83.499999)
		(end 142 82.6)
		(width 0.1)
		(layer "In5.Cu")
		(net 56)
	)
	(segment
		(start 142 81.725)
		(end 141.55 81.275)
		(width 0.1)
		(layer "In5.Cu")
		(net 56)
	)
	(segment
		(start 142.65 77)
		(end 142.65 76.3)
		(width 0.1)
		(layer "In5.Cu")
		(net 56)
	)
	(segment
		(start 94.36863 116)
		(end 99.3 111.06863)
		(width 0.1)
		(layer "In5.Cu")
		(net 56)
	)
	(segment
		(start 141.55 80.25)
		(end 141.175 79.875)
		(width 0.1)
		(layer "In5.Cu")
		(net 56)
	)
	(segment
		(start 131.8 100.2)
		(end 133.4 100.2)
		(width 0.1)
		(layer "In5.Cu")
		(net 56)
	)
	(segment
		(start 82.15 103.7)
		(end 82.55 104.1)
		(width 0.1)
		(layer "In5.Cu")
		(net 56)
	)
	(segment
		(start 141.175 79.875)
		(end 141.175 78.475)
		(width 0.1)
		(layer "In5.Cu")
		(net 56)
	)
	(segment
		(start 99.3 103.9)
		(end 100.4 102.8)
		(width 0.1)
		(layer "In5.Cu")
		(net 56)
	)
	(segment
		(start 140.6 72.8)
		(end 140.6 72.15)
		(width 0.1)
		(layer "In5.Cu")
		(net 56)
	)
	(segment
		(start 142 75.65)
		(end 142 74.9)
		(width 0.1)
		(layer "In5.Cu")
		(net 56)
	)
	(segment
		(start 142.65 76.3)
		(end 142 75.65)
		(width 0.1)
		(layer "In5.Cu")
		(net 56)
	)
	(segment
		(start 82.55 104.1)
		(end 82.55 115.9)
		(width 0.1)
		(layer "In5.Cu")
		(net 56)
	)
	(segment
		(start 99.3 111.06863)
		(end 99.3 103.9)
		(width 0.1)
		(layer "In5.Cu")
		(net 56)
	)
	(segment
		(start 79.585532 95.455)
		(end 78.7 96.340532)
		(width 0.1)
		(layer "In5.Cu")
		(net 56)
	)
	(segment
		(start 78.7 96.340532)
		(end 78.7 102.25)
		(width 0.1)
		(layer "In5.Cu")
		(net 56)
	)
	(segment
		(start 134.7 98.9)
		(end 134.7 94.402944)
		(width 0.1)
		(layer "In5.Cu")
		(net 56)
	)
	(segment
		(start 79.15 102.7)
		(end 79.15 103.25)
		(width 0.1)
		(layer "In5.Cu")
		(net 56)
	)
	(segment
		(start 141.55 81.275)
		(end 141.55 80.25)
		(width 0.1)
		(layer "In5.Cu")
		(net 56)
	)
	(segment
		(start 141.175 78.475)
		(end 142.65 77)
		(width 0.1)
		(layer "In5.Cu")
		(net 56)
	)
	(segment
		(start 83.05 116.4)
		(end 86.375 116.4)
		(width 0.1)
		(layer "In5.Cu")
		(net 56)
	)
	(segment
		(start 82.55 115.9)
		(end 83.05 116.4)
		(width 0.1)
		(layer "In5.Cu")
		(net 56)
	)
	(segment
		(start 79.6 103.7)
		(end 82.15 103.7)
		(width 0.1)
		(layer "In5.Cu")
		(net 56)
	)
	(segment
		(start 142 74.9)
		(end 140.9 73.8)
		(width 0.1)
		(layer "In5.Cu")
		(net 56)
	)
	(segment
		(start 79.15 103.25)
		(end 79.6 103.7)
		(width 0.1)
		(layer "In5.Cu")
		(net 56)
	)
	(segment
		(start 86 77.3)
		(end 90.180532 77.3)
		(width 0.1)
		(layer "F.Cu")
		(net 57)
	)
	(segment
		(start 81.3 73.2)
		(end 80.9 73.6)
		(width 0.1)
		(layer "F.Cu")
		(net 57)
	)
	(segment
		(start 85.3 76.6)
		(end 85.3 74.7)
		(width 0.1)
		(layer "F.Cu")
		(net 57)
	)
	(segment
		(start 85.3 76.6)
		(end 86 77.3)
		(width 0.1)
		(layer "F.Cu")
		(net 57)
	)
	(segment
		(start 90.830532 76.65)
		(end 90.180532 77.3)
		(width 0.1)
		(layer "F.Cu")
		(net 57)
	)
	(segment
		(start 84.6 74)
		(end 85.3 74.7)
		(width 0.1)
		(layer "F.Cu")
		(net 57)
	)
	(segment
		(start 84.6 74)
		(end 84.6 73.4)
		(width 0.1)
		(layer "F.Cu")
		(net 57)
	)
	(segment
		(start 84.6 73.4)
		(end 84.4 73.2)
		(width 0.1)
		(layer "F.Cu")
		(net 57)
	)
	(segment
		(start 84.4 73.2)
		(end 81.3 73.2)
		(width 0.1)
		(layer "F.Cu")
		(net 57)
	)
	(via
		(at 202.126 143.1)
		(size 0.45)
		(drill 0.1)
		(layers "F.Cu" "B.Cu")
		(net 57)
	)
	(via
		(at 80.9 73.6)
		(size 0.45)
		(drill 0.1)
		(layers "F.Cu" "B.Cu")
		(net 57)
	)
	(segment
		(start 202.146 143.12)
		(end 202.126 143.1)
		(width 0.1)
		(layer "B.Cu")
		(net 57)
	)
	(segment
		(start 202.146 144.012)
		(end 202.146 143.12)
		(width 0.1)
		(layer "B.Cu")
		(net 57)
	)
	(segment
		(start 175.6 138)
		(end 180.8 143.2)
		(width 0.1)
		(layer "In7.Cu")
		(net 57)
	)
	(segment
		(start 79.8 83.4)
		(end 72 83.4)
		(width 0.1)
		(layer "In7.Cu")
		(net 57)
	)
	(segment
		(start 192 144.6)
		(end 193.5 143.1)
		(width 0.1)
		(layer "In7.Cu")
		(net 57)
	)
	(segment
		(start 67.8 91.6)
		(end 67.3 92.1)
		(width 0.1)
		(layer "In7.Cu")
		(net 57)
	)
	(segment
		(start 67.2 137.4)
		(end 69.65 139.85)
		(width 0.1)
		(layer "In7.Cu")
		(net 57)
	)
	(segment
		(start 153.7 134.2)
		(end 158.3 134.2)
		(width 0.1)
		(layer "In7.Cu")
		(net 57)
	)
	(segment
		(start 126 144.3)
		(end 138.3 144.3)
		(width 0.1)
		(layer "In7.Cu")
		(net 57)
	)
	(segment
		(start 83.675 140.725)
		(end 85.7 140.725)
		(width 0.1)
		(layer "In7.Cu")
		(net 57)
	)
	(segment
		(start 99.225 142.125)
		(end 100.1 143)
		(width 0.1)
		(layer "In7.Cu")
		(net 57)
	)
	(segment
		(start 64.4 108.1)
		(end 64.4 114.1)
		(width 0.1)
		(layer "In7.Cu")
		(net 57)
	)
	(segment
		(start 80.275 82.925)
		(end 79.8 83.4)
		(width 0.1)
		(layer "In7.Cu")
		(net 57)
	)
	(segment
		(start 187.9 144.6)
		(end 192 144.6)
		(width 0.1)
		(layer "In7.Cu")
		(net 57)
	)
	(segment
		(start 186.5 143.2)
		(end 187.9 144.6)
		(width 0.1)
		(layer "In7.Cu")
		(net 57)
	)
	(segment
		(start 87.1 142.125)
		(end 99.225 142.125)
		(width 0.1)
		(layer "In7.Cu")
		(net 57)
	)
	(segment
		(start 72 83.4)
		(end 69.2 86.2)
		(width 0.1)
		(layer "In7.Cu")
		(net 57)
	)
	(segment
		(start 82.8 139.85)
		(end 83.675 140.725)
		(width 0.1)
		(layer "In7.Cu")
		(net 57)
	)
	(segment
		(start 140.3 142.3)
		(end 145.6 142.3)
		(width 0.1)
		(layer "In7.Cu")
		(net 57)
	)
	(segment
		(start 80.275 77.075)
		(end 80.275 82.925)
		(width 0.1)
		(layer "In7.Cu")
		(net 57)
	)
	(segment
		(start 100.1 143)
		(end 100.1 143.5)
		(width 0.1)
		(layer "In7.Cu")
		(net 57)
	)
	(segment
		(start 69.2 86.2)
		(end 68.8 86.2)
		(width 0.1)
		(layer "In7.Cu")
		(net 57)
	)
	(segment
		(start 100.45 143.85)
		(end 125.55 143.85)
		(width 0.1)
		(layer "In7.Cu")
		(net 57)
	)
	(segment
		(start 67.2 116.9)
		(end 67.2 137.4)
		(width 0.1)
		(layer "In7.Cu")
		(net 57)
	)
	(segment
		(start 68.8 86.2)
		(end 67.8 87.2)
		(width 0.1)
		(layer "In7.Cu")
		(net 57)
	)
	(segment
		(start 64.4 114.1)
		(end 67.2 116.9)
		(width 0.1)
		(layer "In7.Cu")
		(net 57)
	)
	(segment
		(start 67.8 87.2)
		(end 67.8 91.6)
		(width 0.1)
		(layer "In7.Cu")
		(net 57)
	)
	(segment
		(start 193.5 143.1)
		(end 202.126 143.1)
		(width 0.1)
		(layer "In7.Cu")
		(net 57)
	)
	(segment
		(start 145.6 142.3)
		(end 153.7 134.2)
		(width 0.1)
		(layer "In7.Cu")
		(net 57)
	)
	(segment
		(start 67.3 92.1)
		(end 67.3 105.2)
		(width 0.1)
		(layer "In7.Cu")
		(net 57)
	)
	(segment
		(start 85.7 140.725)
		(end 87.1 142.125)
		(width 0.1)
		(layer "In7.Cu")
		(net 57)
	)
	(segment
		(start 67.3 105.2)
		(end 64.4 108.1)
		(width 0.1)
		(layer "In7.Cu")
		(net 57)
	)
	(segment
		(start 162.1 138)
		(end 175.6 138)
		(width 0.1)
		(layer "In7.Cu")
		(net 57)
	)
	(segment
		(start 138.3 144.3)
		(end 140.3 142.3)
		(width 0.1)
		(layer "In7.Cu")
		(net 57)
	)
	(segment
		(start 125.55 143.85)
		(end 126 144.3)
		(width 0.1)
		(layer "In7.Cu")
		(net 57)
	)
	(segment
		(start 180.8 143.2)
		(end 186.5 143.2)
		(width 0.1)
		(layer "In7.Cu")
		(net 57)
	)
	(segment
		(start 80.9 76.45)
		(end 80.275 77.075)
		(width 0.1)
		(layer "In7.Cu")
		(net 57)
	)
	(segment
		(start 100.1 143.5)
		(end 100.45 143.85)
		(width 0.1)
		(layer "In7.Cu")
		(net 57)
	)
	(segment
		(start 80.9 73.6)
		(end 80.9 76.45)
		(width 0.1)
		(layer "In7.Cu")
		(net 57)
	)
	(segment
		(start 158.3 134.2)
		(end 162.1 138)
		(width 0.1)
		(layer "In7.Cu")
		(net 57)
	)
	(segment
		(start 69.65 139.85)
		(end 82.8 139.85)
		(width 0.1)
		(layer "In7.Cu")
		(net 57)
	)
	(via
		(at 128.730532 85.65)
		(size 0.45)
		(drill 0.1)
		(layers "F.Cu" "B.Cu")
		(net 59)
	)
	(via
		(at 201.8125 62.9)
		(size 0.45)
		(drill 0.1)
		(layers "F.Cu" "B.Cu")
		(net 59)
	)
	(segment
		(start 201.925 62.7875)
		(end 201.8125 62.9)
		(width 0.17)
		(layer "B.Cu")
		(net 59)
	)
	(segment
		(start 203.733 59.365001)
		(end 203.733 59.919512)
		(width 0.17)
		(layer "B.Cu")
		(net 59)
	)
	(segment
		(start 203.733 59.919512)
		(end 201.925 61.727512)
		(width 0.17)
		(layer "B.Cu")
		(net 59)
	)
	(segment
		(start 203.658 58.39)
		(end 203.658 59.290001)
		(width 0.17)
		(layer "B.Cu")
		(net 59)
	)
	(segment
		(start 203.658 59.290001)
		(end 203.733 59.365001)
		(width 0.17)
		(layer "B.Cu")
		(net 59)
	)
	(segment
		(start 201.925 61.727512)
		(end 201.925 62.7875)
		(width 0.17)
		(layer "B.Cu")
		(net 59)
	)
	(segment
		(start 162.248909 87.34355)
		(end 162.248909 85.931456)
		(width 0.125)
		(layer "In2.Cu")
		(net 59)
	)
	(segment
		(start 130.091687 86.1475)
		(end 130.091687 86.0775)
		(width 0.125)
		(layer "In2.Cu")
		(net 59)
	)
	(segment
		(start 145.3466 86.6125)
		(end 155.4484 86.6125)
		(width 0.125)
		(layer "In2.Cu")
		(net 59)
	)
	(segment
		(start 197.1534 64.8875)
		(end 201.5534 64.8875)
		(width 0.125)
		(layer "In2.Cu")
		(net 59)
	)
	(segment
		(start 168.827364 86.525)
		(end 182.777365 72.574999)
		(width 0.125)
		(layer "In2.Cu")
		(net 59)
	)
	(segment
		(start 201.847499 63.752247)
		(end 201.820566 63.752247)
		(width 0.125)
		(layer "In2.Cu")
		(net 59)
	)
	(segment
		(start 158.0166 86.2375)
		(end 158.3041 86.525)
		(width 0.125)
		(layer "In2.Cu")
		(net 59)
	)
	(segment
		(start 201.680566 63.892247)
		(end 201.680566 63.962247)
		(width 0.125)
		(layer "In2.Cu")
		(net 59)
	)
	(segment
		(start 130.441687 86.0775)
		(end 130.441687 86.1475)
		(width 0.125)
		(layer "In2.Cu")
		(net 59)
	)
	(segment
		(start 155.8234 86.2375)
		(end 158.0166 86.2375)
		(width 0.125)
		(layer "In2.Cu")
		(net 59)
	)
	(segment
		(start 128.393033 86.133933)
		(end 128.5466 86.2875)
		(width 0.125)
		(layer "In2.Cu")
		(net 59)
	)
	(segment
		(start 162.581409 85.598956)
		(end 162.691409 85.598956)
		(width 0.125)
		(layer "In2.Cu")
		(net 59)
	)
	(segment
		(start 195.4875 66.5534)
		(end 197.1534 64.8875)
		(width 0.125)
		(layer "In2.Cu")
		(net 59)
	)
	(segment
		(start 162.031409 87.45105)
		(end 162.141409 87.45105)
		(width 0.125)
		(layer "In2.Cu")
		(net 59)
	)
	(segment
		(start 163.023909 85.931456)
		(end 163.023909 86.4175)
		(width 0.125)
		(layer "In2.Cu")
		(net 59)
	)
	(segment
		(start 130.581687 86.2875)
		(end 145.0216 86.2875)
		(width 0.125)
		(layer "In2.Cu")
		(net 59)
	)
	(segment
		(start 182.777365 72.574999)
		(end 193.865901 72.574999)
		(width 0.125)
		(layer "In2.Cu")
		(net 59)
	)
	(segment
		(start 195.4875 70.9534)
		(end 195.4875 66.5534)
		(width 0.125)
		(layer "In2.Cu")
		(net 59)
	)
	(segment
		(start 128.5466 86.2875)
		(end 129.951687 86.2875)
		(width 0.125)
		(layer "In2.Cu")
		(net 59)
	)
	(segment
		(start 201.5534 64.8875)
		(end 201.987499 64.453401)
		(width 0.125)
		(layer "In2.Cu")
		(net 59)
	)
	(segment
		(start 161.923909 86.8575)
		(end 161.923909 87.34355)
		(width 0.125)
		(layer "In2.Cu")
		(net 59)
	)
	(segment
		(start 145.0216 86.2875)
		(end 145.3466 86.6125)
		(width 0.125)
		(layer "In2.Cu")
		(net 59)
	)
	(segment
		(start 201.820566 64.102247)
		(end 201.847499 64.102247)
		(width 0.125)
		(layer "In2.Cu")
		(net 59)
	)
	(segment
		(start 201.987499 63.074999)
		(end 201.987499 63.612247)
		(width 0.125)
		(layer "In2.Cu")
		(net 59)
	)
	(segment
		(start 201.987499 64.242247)
		(end 201.987499 64.453401)
		(width 0.125)
		(layer "In2.Cu")
		(net 59)
	)
	(segment
		(start 163.131409 86.525)
		(end 168.827364 86.525)
		(width 0.125)
		(layer "In2.Cu")
		(net 59)
	)
	(segment
		(start 193.865901 72.574999)
		(end 195.4875 70.9534)
		(width 0.125)
		(layer "In2.Cu")
		(net 59)
	)
	(segment
		(start 130.231687 85.9375)
		(end 130.301687 85.9375)
		(width 0.125)
		(layer "In2.Cu")
		(net 59)
	)
	(segment
		(start 158.3041 86.525)
		(end 161.591409 86.525)
		(width 0.125)
		(layer "In2.Cu")
		(net 59)
	)
	(segment
		(start 128.393033 85.987499)
		(end 128.393033 86.133933)
		(width 0.125)
		(layer "In2.Cu")
		(net 59)
	)
	(segment
		(start 201.8125 62.9)
		(end 201.987499 63.074999)
		(width 0.125)
		(layer "In2.Cu")
		(net 59)
	)
	(segment
		(start 128.730532 85.65)
		(end 128.393033 85.987499)
		(width 0.125)
		(layer "In2.Cu")
		(net 59)
	)
	(segment
		(start 155.4484 86.6125)
		(end 155.8234 86.2375)
		(width 0.125)
		(layer "In2.Cu")
		(net 59)
	)
	(arc
		(start 163.023909 86.4175)
		(mid 163.055395 86.493514)
		(end 163.131409 86.525)
		(width 0.125)
		(layer "In2.Cu")
		(net 59)
	)
	(arc
		(start 161.591409 86.525)
		(mid 161.826522 86.622387)
		(end 161.923909 86.8575)
		(width 0.125)
		(layer "In2.Cu")
		(net 59)
	)
	(arc
		(start 130.301687 85.9375)
		(mid 130.400682 85.978505)
		(end 130.441687 86.0775)
		(width 0.125)
		(layer "In2.Cu")
		(net 59)
	)
	(arc
		(start 161.923909 87.34355)
		(mid 161.955395 87.419564)
		(end 162.031409 87.45105)
		(width 0.125)
		(layer "In2.Cu")
		(net 59)
	)
	(arc
		(start 201.820566 63.752247)
		(mid 201.721571 63.793252)
		(end 201.680566 63.892247)
		(width 0.125)
		(layer "In2.Cu")
		(net 59)
	)
	(arc
		(start 201.847499 64.102247)
		(mid 201.946494 64.143252)
		(end 201.987499 64.242247)
		(width 0.125)
		(layer "In2.Cu")
		(net 59)
	)
	(arc
		(start 129.951687 86.2875)
		(mid 130.050682 86.246495)
		(end 130.091687 86.1475)
		(width 0.125)
		(layer "In2.Cu")
		(net 59)
	)
	(arc
		(start 162.691409 85.598956)
		(mid 162.926522 85.696343)
		(end 163.023909 85.931456)
		(width 0.125)
		(layer "In2.Cu")
		(net 59)
	)
	(arc
		(start 130.441687 86.1475)
		(mid 130.482692 86.246495)
		(end 130.581687 86.2875)
		(width 0.125)
		(layer "In2.Cu")
		(net 59)
	)
	(arc
		(start 201.680566 63.962247)
		(mid 201.721571 64.061242)
		(end 201.820566 64.102247)
		(width 0.125)
		(layer "In2.Cu")
		(net 59)
	)
	(arc
		(start 201.987499 63.612247)
		(mid 201.946494 63.711242)
		(end 201.847499 63.752247)
		(width 0.125)
		(layer "In2.Cu")
		(net 59)
	)
	(arc
		(start 130.091687 86.0775)
		(mid 130.132692 85.978505)
		(end 130.231687 85.9375)
		(width 0.125)
		(layer "In2.Cu")
		(net 59)
	)
	(arc
		(start 162.141409 87.45105)
		(mid 162.217423 87.419564)
		(end 162.248909 87.34355)
		(width 0.125)
		(layer "In2.Cu")
		(net 59)
	)
	(arc
		(start 162.248909 85.931456)
		(mid 162.346296 85.696343)
		(end 162.581409 85.598956)
		(width 0.125)
		(layer "In2.Cu")
		(net 59)
	)
	(segment
		(start 131.9 86)
		(end 131.9 85.1)
		(width 0.1)
		(layer "F.Cu")
		(net 60)
	)
	(segment
		(start 158 117.8)
		(end 158.365686 117.8)
		(width 0.1)
		(layer "F.Cu")
		(net 60)
	)
	(segment
		(start 131.3 87.7)
		(end 131.1 87.5)
		(width 0.1)
		(layer "F.Cu")
		(net 60)
	)
	(segment
		(start 132.1 83.7)
		(end 131.9 83.5)
		(width 0.1)
		(layer "F.Cu")
		(net 60)
	)
	(segment
		(start 131.1 87.5)
		(end 131.1 86.8)
		(width 0.1)
		(layer "F.Cu")
		(net 60)
	)
	(segment
		(start 154.1 94.6)
		(end 140.9 94.6)
		(width 0.1)
		(layer "F.Cu")
		(net 60)
	)
	(segment
		(start 156.12 118.4)
		(end 155.9 118.4)
		(width 0.1)
		(layer "F.Cu")
		(net 60)
	)
	(segment
		(start 140.9 94.6)
		(end 134 87.7)
		(width 0.1)
		(layer "F.Cu")
		(net 60)
	)
	(segment
		(start 132.1 84.9)
		(end 132.1 83.7)
		(width 0.1)
		(layer "F.Cu")
		(net 60)
	)
	(segment
		(start 134 87.7)
		(end 131.3 87.7)
		(width 0.1)
		(layer "F.Cu")
		(net 60)
	)
	(segment
		(start 131.9 82.25)
		(end 132.5 81.65)
		(width 0.1)
		(layer "F.Cu")
		(net 60)
	)
	(segment
		(start 160.5 115.665686)
		(end 160.5 110.534314)
		(width 0.1)
		(layer "F.Cu")
		(net 60)
	)
	(segment
		(start 132.5 81.65)
		(end 135.5 81.65)
		(width 0.1)
		(layer "F.Cu")
		(net 60)
	)
	(segment
		(start 158.365686 117.8)
		(end 160.5 115.665686)
		(width 0.1)
		(layer "F.Cu")
		(net 60)
	)
	(segment
		(start 160.5 110.534314)
		(end 158.4 108.434314)
		(width 0.1)
		(layer "F.Cu")
		(net 60)
	)
	(segment
		(start 155.002 118.402)
		(end 155 118.4)
		(width 0.1)
		(layer "F.Cu")
		(net 60)
	)
	(segment
		(start 131.1 86.8)
		(end 131.9 86)
		(width 0.1)
		(layer "F.Cu")
		(net 60)
	)
	(segment
		(start 155.8 118.4)
		(end 155 118.4)
		(width 0.1)
		(layer "F.Cu")
		(net 60)
	)
	(segment
		(start 135.7 80.7)
		(end 136.4 80)
		(width 0.1)
		(layer "F.Cu")
		(net 60)
	)
	(segment
		(start 135.7 81.45)
		(end 135.7 80.7)
		(width 0.1)
		(layer "F.Cu")
		(net 60)
	)
	(segment
		(start 131.9 85.1)
		(end 132.1 84.9)
		(width 0.1)
		(layer "F.Cu")
		(net 60)
	)
	(segment
		(start 136.4 80)
		(end 136.4 79.2)
		(width 0.1)
		(layer "F.Cu")
		(net 60)
	)
	(segment
		(start 136.4 79.2)
		(end 136.130532 78.930532)
		(width 0.1)
		(layer "F.Cu")
		(net 60)
	)
	(segment
		(start 156.6 101.4)
		(end 156.6 97.1)
		(width 0.1)
		(layer "F.Cu")
		(net 60)
	)
	(segment
		(start 136.130532 78.930532)
		(end 136.130532 78.15)
		(width 0.1)
		(layer "F.Cu")
		(net 60)
	)
	(segment
		(start 135.5 81.65)
		(end 135.7 81.45)
		(width 0.1)
		(layer "F.Cu")
		(net 60)
	)
	(segment
		(start 158.4 108.434314)
		(end 158.4 103.2)
		(width 0.1)
		(layer "F.Cu")
		(net 60)
	)
	(segment
		(start 131.9 83.5)
		(end 131.9 82.25)
		(width 0.1)
		(layer "F.Cu")
		(net 60)
	)
	(segment
		(start 158.4 103.2)
		(end 156.6 101.4)
		(width 0.1)
		(layer "F.Cu")
		(net 60)
	)
	(segment
		(start 153.73 118.256)
		(end 154.856 118.256)
		(width 0.1)
		(layer "F.Cu")
		(net 60)
	)
	(segment
		(start 154.856 118.256)
		(end 155 118.4)
		(width 0.1)
		(layer "F.Cu")
		(net 60)
	)
	(segment
		(start 156.6 97.1)
		(end 154.1 94.6)
		(width 0.1)
		(layer "F.Cu")
		(net 60)
	)
	(via
		(at 155 118.4)
		(size 0.45)
		(drill 0.1)
		(layers "F.Cu" "B.Cu")
		(net 60)
	)
	(via
		(at 158 117.8)
		(size 0.45)
		(drill 0.1)
		(layers "F.Cu" "B.Cu")
		(net 60)
	)
	(segment
		(start 156.4 118.4)
		(end 155 118.4)
		(width 0.1)
		(layer "B.Cu")
		(net 60)
	)
	(segment
		(start 157 117.8)
		(end 156.4 118.4)
		(width 0.1)
		(layer "B.Cu")
		(net 60)
	)
	(segment
		(start 158 117.8)
		(end 157 117.8)
		(width 0.1)
		(layer "B.Cu")
		(net 60)
	)
	(segment
		(start 130.175 101.4)
		(end 132.3 101.4)
		(width 0.1)
		(layer "F.Cu")
		(net 61)
	)
	(segment
		(start 128.3 101)
		(end 129.775 101)
		(width 0.1)
		(layer "F.Cu")
		(net 61)
	)
	(segment
		(start 128.2 101.1)
		(end 128.3 101)
		(width 0.1)
		(layer "F.Cu")
		(net 61)
	)
	(segment
		(start 129.775 101)
		(end 130.175 101.4)
		(width 0.1)
		(layer "F.Cu")
		(net 61)
	)
	(via
		(at 128.2 101.1)
		(size 0.45)
		(drill 0.1)
		(layers "F.Cu" "B.Cu")
		(net 61)
	)
	(via
		(at 132.3 101.4)
		(size 0.45)
		(drill 0.1)
		(layers "F.Cu" "B.Cu")
		(net 61)
	)
	(via
		(at 140.430532 82.65)
		(size 0.45)
		(drill 0.1)
		(layers "F.Cu" "B.Cu")
		(net 61)
	)
	(via
		(at 79.585532 91.645)
		(size 0.45)
		(drill 0.1)
		(layers "F.Cu" "B.Cu")
		(net 61)
	)
	(segment
		(start 86.7 117.65)
		(end 81.6 117.65)
		(width 0.1)
		(layer "In5.Cu")
		(net 61)
	)
	(segment
		(start 100.499999 110.9)
		(end 100.307843 111.092156)
		(width 0.1)
		(layer "In5.Cu")
		(net 61)
	)
	(segment
		(start 81.25 117.3)
		(end 81.25 108)
		(width 0.1)
		(layer "In5.Cu")
		(net 61)
	)
	(segment
		(start 120.862734 104.3)
		(end 100.597054 104.3)
		(width 0.1)
		(layer "In5.Cu")
		(net 61)
	)
	(segment
		(start 132.5 96.5)
		(end 132.5 93.55)
		(width 0.1)
		(layer "In5.Cu")
		(net 61)
	)
	(segment
		(start 80.05 87.65)
		(end 80.05 88.1)
		(width 0.1)
		(layer "In5.Cu")
		(net 61)
	)
	(segment
		(start 77.45 94.4)
		(end 77.9 93.95)
		(width 0.1)
		(layer "In5.Cu")
		(net 61)
	)
	(segment
		(start 81.6 117.65)
		(end 81.25 117.3)
		(width 0.1)
		(layer "In5.Cu")
		(net 61)
	)
	(segment
		(start 77.725 103.075)
		(end 77.725 102.575)
		(width 0.1)
		(layer "In5.Cu")
		(net 61)
	)
	(segment
		(start 132.3 101.4)
		(end 131.6 101.4)
		(width 0.1)
		(layer "In5.Cu")
		(net 61)
	)
	(segment
		(start 100.307843 111.757843)
		(end 95.065689 116.999997)
		(width 0.1)
		(layer "In5.Cu")
		(net 61)
	)
	(segment
		(start 100.597054 104.3)
		(end 100.499999 104.397055)
		(width 0.1)
		(layer "In5.Cu")
		(net 61)
	)
	(segment
		(start 139.25 84.9)
		(end 139.25 83.85)
		(width 0.1)
		(layer "In5.Cu")
		(net 61)
	)
	(segment
		(start 100.499999 104.397055)
		(end 100.499999 110.9)
		(width 0.1)
		(layer "In5.Cu")
		(net 61)
	)
	(segment
		(start 77.45 102.3)
		(end 77.45 94.4)
		(width 0.1)
		(layer "In5.Cu")
		(net 61)
	)
	(segment
		(start 78.275 105.025)
		(end 78.275 103.625)
		(width 0.1)
		(layer "In5.Cu")
		(net 61)
	)
	(segment
		(start 132.5 93.55)
		(end 138.65 87.4)
		(width 0.1)
		(layer "In5.Cu")
		(net 61)
	)
	(segment
		(start 77.9 88.85)
		(end 79.3 87.45)
		(width 0.1)
		(layer "In5.Cu")
		(net 61)
	)
	(segment
		(start 79.2 88.95)
		(end 79.2 91.259468)
		(width 0.1)
		(layer "In5.Cu")
		(net 61)
	)
	(segment
		(start 77.9 93.95)
		(end 77.9 88.85)
		(width 0.1)
		(layer "In5.Cu")
		(net 61)
	)
	(segment
		(start 139.25 83.85)
		(end 138.25 82.85)
		(width 0.1)
		(layer "In5.Cu")
		(net 61)
	)
	(segment
		(start 139.730532 81.95)
		(end 140.430532 82.65)
		(width 0.1)
		(layer "In5.Cu")
		(net 61)
	)
	(segment
		(start 138.25 82.85)
		(end 138.25 82.25)
		(width 0.1)
		(layer "In5.Cu")
		(net 61)
	)
	(segment
		(start 79.3 87.45)
		(end 79.85 87.45)
		(width 0.1)
		(layer "In5.Cu")
		(net 61)
	)
	(segment
		(start 124.062734 101.1)
		(end 120.862734 104.3)
		(width 0.1)
		(layer "In5.Cu")
		(net 61)
	)
	(segment
		(start 138.25 82.25)
		(end 138.55 81.95)
		(width 0.1)
		(layer "In5.Cu")
		(net 61)
	)
	(segment
		(start 138.55 81.95)
		(end 139.730532 81.95)
		(width 0.1)
		(layer "In5.Cu")
		(net 61)
	)
	(segment
		(start 100.307843 111.092156)
		(end 100.307843 111.757843)
		(width 0.1)
		(layer "In5.Cu")
		(net 61)
	)
	(segment
		(start 78.275 103.625)
		(end 77.725 103.075)
		(width 0.1)
		(layer "In5.Cu")
		(net 61)
	)
	(segment
		(start 87.350003 116.999997)
		(end 86.7 117.65)
		(width 0.1)
		(layer "In5.Cu")
		(net 61)
	)
	(segment
		(start 79.2 91.259468)
		(end 79.585532 91.645)
		(width 0.1)
		(layer "In5.Cu")
		(net 61)
	)
	(segment
		(start 138.65 87.4)
		(end 138.65 85.5)
		(width 0.1)
		(layer "In5.Cu")
		(net 61)
	)
	(segment
		(start 79.85 87.45)
		(end 80.05 87.65)
		(width 0.1)
		(layer "In5.Cu")
		(net 61)
	)
	(segment
		(start 131.4 101.2)
		(end 131.4 97.6)
		(width 0.1)
		(layer "In5.Cu")
		(net 61)
	)
	(segment
		(start 131.6 101.4)
		(end 131.4 101.2)
		(width 0.1)
		(layer "In5.Cu")
		(net 61)
	)
	(segment
		(start 77.725 102.575)
		(end 77.45 102.3)
		(width 0.1)
		(layer "In5.Cu")
		(net 61)
	)
	(segment
		(start 128.2 101.1)
		(end 124.062734 101.1)
		(width 0.1)
		(layer "In5.Cu")
		(net 61)
	)
	(segment
		(start 95.065689 116.999997)
		(end 87.350003 116.999997)
		(width 0.1)
		(layer "In5.Cu")
		(net 61)
	)
	(segment
		(start 131.4 97.6)
		(end 132.5 96.5)
		(width 0.1)
		(layer "In5.Cu")
		(net 61)
	)
	(segment
		(start 138.65 85.5)
		(end 139.25 84.9)
		(width 0.1)
		(layer "In5.Cu")
		(net 61)
	)
	(segment
		(start 80.05 88.1)
		(end 79.2 88.95)
		(width 0.1)
		(layer "In5.Cu")
		(net 61)
	)
	(segment
		(start 81.25 108)
		(end 78.275 105.025)
		(width 0.1)
		(layer "In5.Cu")
		(net 61)
	)
	(segment
		(start 129.205532 75.65302)
		(end 129.702512 76.15)
		(width 0.17)
		(layer "F.Cu")
		(net 62)
	)
	(segment
		(start 128.930532 75.15)
		(end 129.205532 75.425)
		(width 0.17)
		(layer "F.Cu")
		(net 62)
	)
	(segment
		(start 129.702512 76.15)
		(end 130.85 76.15)
		(width 0.17)
		(layer "F.Cu")
		(net 62)
	)
	(segment
		(start 130.85 76.15)
		(end 130.975 76.275)
		(width 0.17)
		(layer "F.Cu")
		(net 62)
	)
	(segment
		(start 129.205532 75.425)
		(end 129.205532 75.65302)
		(width 0.17)
		(layer "F.Cu")
		(net 62)
	)
	(via
		(at 205.7 61.8)
		(size 0.45)
		(drill 0.1)
		(layers "F.Cu" "B.Cu")
		(net 62)
	)
	(via
		(at 130.975 76.275)
		(size 0.45)
		(drill 0.1)
		(layers "F.Cu" "B.Cu")
		(net 62)
	)
	(segment
		(start 204.733 61.180488)
		(end 205.227512 61.675)
		(width 0.17)
		(layer "B.Cu")
		(net 62)
	)
	(segment
		(start 204.658 59.290001)
		(end 204.733 59.365001)
		(width 0.17)
		(layer "B.Cu")
		(net 62)
	)
	(segment
		(start 205.227512 61.675)
		(end 205.575 61.675)
		(width 0.17)
		(layer "B.Cu")
		(net 62)
	)
	(segment
		(start 204.733 59.365001)
		(end 204.733 61.180488)
		(width 0.17)
		(layer "B.Cu")
		(net 62)
	)
	(segment
		(start 205.575 61.675)
		(end 205.7 61.8)
		(width 0.17)
		(layer "B.Cu")
		(net 62)
	)
	(segment
		(start 204.658 58.39)
		(end 204.658 59.290001)
		(width 0.17)
		(layer "B.Cu")
		(net 62)
	)
	(segment
		(start 149.037565 75.194963)
		(end 149.037565 75.755)
		(width 0.125)
		(layer "In2.Cu")
		(net 62)
	)
	(segment
		(start 151.237565 76.195)
		(end 151.237565 76.60503)
		(width 0.125)
		(layer "In2.Cu")
		(net 62)
	)
	(segment
		(start 151.570066 76.937531)
		(end 151.680066 76.937531)
		(width 0.125)
		(layer "In2.Cu")
		(net 62)
	)
	(segment
		(start 148.712567 75.755)
		(end 148.712567 75.194963)
		(width 0.125)
		(layer "In2.Cu")
		(net 62)
	)
	(segment
		(start 148.820066 75.087464)
		(end 148.930066 75.087464)
		(width 0.125)
		(layer "In2.Cu")
		(net 62)
	)
	(segment
		(start 131.162499 76.087501)
		(end 148.380066 76.087501)
		(width 0.125)
		(layer "In2.Cu")
		(net 62)
	)
	(segment
		(start 151.237565 75.862499)
		(end 151.237565 76.195)
		(width 0.125)
		(layer "In2.Cu")
		(net 62)
	)
	(segment
		(start 149.920066 75.087464)
		(end 150.030066 75.087464)
		(width 0.125)
		(layer "In2.Cu")
		(net 62)
	)
	(segment
		(start 149.037565 76.087501)
		(end 149.037565 76.60503)
		(width 0.125)
		(layer "In2.Cu")
		(net 62)
	)
	(segment
		(start 164.804531 76.087501)
		(end 166.315114 74.576918)
		(width 0.125)
		(layer "In2.Cu")
		(net 62)
	)
	(segment
		(start 205.146599 61.612501)
		(end 205.512501 61.612501)
		(width 0.125)
		(layer "In2.Cu")
		(net 62)
	)
	(segment
		(start 150.137565 75.194963)
		(end 150.137565 75.862499)
		(width 0.125)
		(layer "In2.Cu")
		(net 62)
	)
	(segment
		(start 150.912567 76.60503)
		(end 150.912567 76.087501)
		(width 0.125)
		(layer "In2.Cu")
		(net 62)
	)
	(segment
		(start 151.020066 75.087464)
		(end 151.130066 75.087464)
		(width 0.125)
		(layer "In2.Cu")
		(net 62)
	)
	(segment
		(start 151.237565 75.194963)
		(end 151.237565 75.862499)
		(width 0.125)
		(layer "In2.Cu")
		(net 62)
	)
	(segment
		(start 130.975 76.275)
		(end 131.162499 76.087501)
		(width 0.125)
		(layer "In2.Cu")
		(net 62)
	)
	(segment
		(start 204.4091 62.35)
		(end 205.146599 61.612501)
		(width 0.125)
		(layer "In2.Cu")
		(net 62)
	)
	(segment
		(start 149.812567 76.087501)
		(end 149.812567 75.862499)
		(width 0.125)
		(layer "In2.Cu")
		(net 62)
	)
	(segment
		(start 150.912567 76.087501)
		(end 150.912567 75.862499)
		(width 0.125)
		(layer "In2.Cu")
		(net 62)
	)
	(segment
		(start 149.812567 76.60503)
		(end 149.812567 76.087501)
		(width 0.125)
		(layer "In2.Cu")
		(net 62)
	)
	(segment
		(start 205.512501 61.612501)
		(end 205.7 61.8)
		(width 0.125)
		(layer "In2.Cu")
		(net 62)
	)
	(segment
		(start 152.120066 76.087501)
		(end 152.230066 76.087501)
		(width 0.125)
		(layer "In2.Cu")
		(net 62)
	)
	(segment
		(start 150.912567 75.862499)
		(end 150.912567 75.194963)
		(width 0.125)
		(layer "In2.Cu")
		(net 62)
	)
	(segment
		(start 149.812567 75.862499)
		(end 149.812567 75.194963)
		(width 0.125)
		(layer "In2.Cu")
		(net 62)
	)
	(segment
		(start 152.012567 76.60503)
		(end 152.012567 76.195)
		(width 0.125)
		(layer "In2.Cu")
		(net 62)
	)
	(segment
		(start 150.137565 76.087501)
		(end 150.137565 76.60503)
		(width 0.125)
		(layer "In2.Cu")
		(net 62)
	)
	(segment
		(start 178.542032 62.35)
		(end 204.4091 62.35)
		(width 0.125)
		(layer "In2.Cu")
		(net 62)
	)
	(segment
		(start 149.370066 76.937531)
		(end 149.480066 76.937531)
		(width 0.125)
		(layer "In2.Cu")
		(net 62)
	)
	(segment
		(start 150.137565 75.862499)
		(end 150.137565 76.087501)
		(width 0.125)
		(layer "In2.Cu")
		(net 62)
	)
	(segment
		(start 149.037565 75.755)
		(end 149.037565 76.087501)
		(width 0.125)
		(layer "In2.Cu")
		(net 62)
	)
	(segment
		(start 152.230066 76.087501)
		(end 164.804531 76.087501)
		(width 0.125)
		(layer "In2.Cu")
		(net 62)
	)
	(segment
		(start 150.470066 76.937531)
		(end 150.580066 76.937531)
		(width 0.125)
		(layer "In2.Cu")
		(net 62)
	)
	(segment
		(start 166.315114 74.576918)
		(end 178.542032 62.35)
		(width 0.125)
		(layer "In2.Cu")
		(net 62)
	)
	(arc
		(start 150.137565 76.60503)
		(mid 150.234952 76.840144)
		(end 150.470066 76.937531)
		(width 0.125)
		(layer "In2.Cu")
		(net 62)
	)
	(arc
		(start 149.037565 76.60503)
		(mid 149.134952 76.840144)
		(end 149.370066 76.937531)
		(width 0.125)
		(layer "In2.Cu")
		(net 62)
	)
	(arc
		(start 149.812567 75.194963)
		(mid 149.844053 75.11895)
		(end 149.920066 75.087464)
		(width 0.125)
		(layer "In2.Cu")
		(net 62)
	)
	(arc
		(start 148.712567 75.194963)
		(mid 148.744053 75.11895)
		(end 148.820066 75.087464)
		(width 0.125)
		(layer "In2.Cu")
		(net 62)
	)
	(arc
		(start 148.380066 76.087501)
		(mid 148.61518 75.990114)
		(end 148.712567 75.755)
		(width 0.125)
		(layer "In2.Cu")
		(net 62)
	)
	(arc
		(start 151.130066 75.087464)
		(mid 151.206079 75.11895)
		(end 151.237565 75.194963)
		(width 0.125)
		(layer "In2.Cu")
		(net 62)
	)
	(arc
		(start 149.480066 76.937531)
		(mid 149.71518 76.840144)
		(end 149.812567 76.60503)
		(width 0.125)
		(layer "In2.Cu")
		(net 62)
	)
	(arc
		(start 152.012567 76.195)
		(mid 152.044053 76.118987)
		(end 152.120066 76.087501)
		(width 0.125)
		(layer "In2.Cu")
		(net 62)
	)
	(arc
		(start 151.237565 76.60503)
		(mid 151.334952 76.840144)
		(end 151.570066 76.937531)
		(width 0.125)
		(layer "In2.Cu")
		(net 62)
	)
	(arc
		(start 150.580066 76.937531)
		(mid 150.81518 76.840144)
		(end 150.912567 76.60503)
		(width 0.125)
		(layer "In2.Cu")
		(net 62)
	)
	(arc
		(start 148.930066 75.087464)
		(mid 149.006079 75.11895)
		(end 149.037565 75.194963)
		(width 0.125)
		(layer "In2.Cu")
		(net 62)
	)
	(arc
		(start 151.680066 76.937531)
		(mid 151.91518 76.840144)
		(end 152.012567 76.60503)
		(width 0.125)
		(layer "In2.Cu")
		(net 62)
	)
	(arc
		(start 150.030066 75.087464)
		(mid 150.106079 75.11895)
		(end 150.137565 75.194963)
		(width 0.125)
		(layer "In2.Cu")
		(net 62)
	)
	(arc
		(start 150.912567 75.194963)
		(mid 150.944053 75.11895)
		(end 151.020066 75.087464)
		(width 0.125)
		(layer "In2.Cu")
		(net 62)
	)
	(segment
		(start 128.105532 79.025)
		(end 127.980532 78.9)
		(width 0.17)
		(layer "F.Cu")
		(net 63)
	)
	(segment
		(start 128.105532 79.375)
		(end 128.105532 79.025)
		(width 0.17)
		(layer "F.Cu")
		(net 63)
	)
	(segment
		(start 127.830532 79.65)
		(end 128.105532 79.375)
		(width 0.17)
		(layer "F.Cu")
		(net 63)
	)
	(via
		(at 127.980532 78.9)
		(size 0.45)
		(drill 0.1)
		(layers "F.Cu" "B.Cu")
		(net 63)
	)
	(via
		(at 67 108.7)
		(size 0.45)
		(drill 0.1)
		(layers "F.Cu" "B.Cu")
		(net 63)
	)
	(segment
		(start 66.875 108.825)
		(end 67 108.7)
		(width 0.17)
		(layer "B.Cu")
		(net 63)
	)
	(segment
		(start 66.875 114.072488)
		(end 66.875 108.825)
		(width 0.17)
		(layer "B.Cu")
		(net 63)
	)
	(segment
		(start 65.490001 114.96)
		(end 65.565001 114.885)
		(width 0.17)
		(layer "B.Cu")
		(net 63)
	)
	(segment
		(start 66.062488 114.885)
		(end 66.875 114.072488)
		(width 0.17)
		(layer "B.Cu")
		(net 63)
	)
	(segment
		(start 64.59 114.96)
		(end 65.490001 114.96)
		(width 0.17)
		(layer "B.Cu")
		(net 63)
	)
	(segment
		(start 65.565001 114.885)
		(end 66.062488 114.885)
		(width 0.17)
		(layer "B.Cu")
		(net 63)
	)
	(segment
		(start 86.3768 86.4925)
		(end 86.3768 85.3075)
		(width 0.125)
		(layer "In2.Cu")
		(net 63)
	)
	(segment
		(start 115.7466 83.2875)
		(end 111.9466 83.2875)
		(width 0.125)
		(layer "In2.Cu")
		(net 63)
	)
	(segment
		(start 85.6018 85.3075)
		(end 85.6018 86.4925)
		(width 0.125)
		(layer "In2.Cu")
		(net 63)
	)
	(segment
		(start 89.3534 81.7875)
		(end 92.044687 81.7875)
		(width 0.125)
		(layer "In2.Cu")
		(net 63)
	)
	(segment
		(start 85.2768 86.4925)
		(end 85.2768 86.12)
		(width 0.125)
		(layer "In2.Cu")
		(net 63)
	)
	(segment
		(start 119.7466 83.0875)
		(end 119.3466 82.6875)
		(width 0.125)
		(layer "In2.Cu")
		(net 63)
	)
	(segment
		(start 69.2534 85.7875)
		(end 68.1875 86.8534)
		(width 0.125)
		(layer "In2.Cu")
		(net 63)
	)
	(segment
		(start 100.0034 81.7875)
		(end 99.7034 82.0875)
		(width 0.125)
		(layer "In2.Cu")
		(net 63)
	)
	(segment
		(start 87.420773 85.401027)
		(end 87.0343 85.7875)
		(width 0.125)
		(layer "In2.Cu")
		(net 63)
	)
	(segment
		(start 95.6875 82.1534)
		(end 95.3534 82.4875)
		(width 0.125)
		(layer "In2.Cu")
		(net 63)
	)
	(segment
		(start 95.6875 81.6534)
		(end 95.6875 82.1534)
		(width 0.125)
		(layer "In2.Cu")
		(net 63)
	)
	(segment
		(start 68.1875 107.6)
		(end 68.05 107.7375)
		(width 0.125)
		(layer "In2.Cu")
		(net 63)
	)
	(segment
		(start 88.95 83.0091)
		(end 88.95 83.1966)
		(width 0.125)
		(layer "In2.Cu")
		(net 63)
	)
	(segment
		(start 89.3534 81.7875)
		(end 88.5875 82.5534)
		(width 0.125)
		(layer "In2.Cu")
		(net 63)
	)
	(segment
		(start 85.4943 86.6)
		(end 85.3843 86.6)
		(width 0.125)
		(layer "In2.Cu")
		(net 63)
	)
	(segment
		(start 111.9466 83.2875)
		(end 111.4466 82.7875)
		(width 0.125)
		(layer "In2.Cu")
		(net 63)
	)
	(segment
		(start 69.2534 85.7875)
		(end 84.9443 85.7875)
		(width 0.125)
		(layer "In2.Cu")
		(net 63)
	)
	(segment
		(start 88.5875 83.5591)
		(end 88.587501 84.234301)
		(width 0.125)
		(layer "In2.Cu")
		(net 63)
	)
	(segment
		(start 67.0466 109.2875)
		(end 66.812501 109.053401)
		(width 0.125)
		(layer "In2.Cu")
		(net 63)
	)
	(segment
		(start 68.1875 86.8534)
		(end 68.1875 107.6)
		(width 0.125)
		(layer "In2.Cu")
		(net 63)
	)
	(segment
		(start 87.889231 84.465878)
		(end 88.479667 85.056314)
		(width 0.125)
		(layer "In2.Cu")
		(net 63)
	)
	(segment
		(start 125.8534 82.2875)
		(end 125.2534 82.2875)
		(width 0.125)
		(layer "In2.Cu")
		(net 63)
	)
	(segment
		(start 66.812501 108.887499)
		(end 67 108.7)
		(width 0.125)
		(layer "In2.Cu")
		(net 63)
	)
	(segment
		(start 68.1875 108.0875)
		(end 68.1875 108.7534)
		(width 0.125)
		(layer "In2.Cu")
		(net 63)
	)
	(segment
		(start 68.05 107.95)
		(end 68.1875 108.0875)
		(width 0.125)
		(layer "In2.Cu")
		(net 63)
	)
	(segment
		(start 87.419005 84.465878)
		(end 87.341223 84.543659)
		(width 0.125)
		(layer "In2.Cu")
		(net 63)
	)
	(segment
		(start 117.3534 83.6875)
		(end 116.1466 83.6875)
		(width 0.125)
		(layer "In2.Cu")
		(net 63)
	)
	(segment
		(start 98.3466 82.0875)
		(end 97.3466 81.0875)
		(width 0.125)
		(layer "In2.Cu")
		(net 63)
	)
	(segment
		(start 92.594687 82.8)
		(end 92.484687 82.8)
		(width 0.125)
		(layer "In2.Cu")
		(net 63)
	)
	(segment
		(start 92.702187 82.12)
		(end 92.702187 82.6925)
		(width 0.125)
		(layer "In2.Cu")
		(net 63)
	)
	(segment
		(start 86.5943 86.6)
		(end 86.4843 86.6)
		(width 0.125)
		(layer "In2.Cu")
		(net 63)
	)
	(segment
		(start 95.3534 82.4875)
		(end 94.3466 82.4875)
		(width 0.125)
		(layer "In2.Cu")
		(net 63)
	)
	(segment
		(start 66.812501 109.053401)
		(end 66.812501 108.887499)
		(width 0.125)
		(layer "In2.Cu")
		(net 63)
	)
	(segment
		(start 94.3466 82.4875)
		(end 93.6466 81.7875)
		(width 0.125)
		(layer "In2.Cu")
		(net 63)
	)
	(segment
		(start 128.168031 79.972869)
		(end 125.8534 82.2875)
		(width 0.125)
		(layer "In2.Cu")
		(net 63)
	)
	(segment
		(start 93.6466 81.7875)
		(end 93.034687 81.7875)
		(width 0.125)
		(layer "In2.Cu")
		(net 63)
	)
	(segment
		(start 102.5466 81.7875)
		(end 100.0034 81.7875)
		(width 0.125)
		(layer "In2.Cu")
		(net 63)
	)
	(segment
		(start 111.4466 82.7875)
		(end 110.0534 82.7875)
		(width 0.125)
		(layer "In2.Cu")
		(net 63)
	)
	(segment
		(start 127.980532 78.9)
		(end 128.168031 79.087499)
		(width 0.125)
		(layer "In2.Cu")
		(net 63)
	)
	(segment
		(start 109.5534 83.2875)
		(end 104.0466 83.2875)
		(width 0.125)
		(layer "In2.Cu")
		(net 63)
	)
	(segment
		(start 67.6534 109.2875)
		(end 67.0466 109.2875)
		(width 0.125)
		(layer "In2.Cu")
		(net 63)
	)
	(segment
		(start 125.2534 82.2875)
		(end 124.4534 83.0875)
		(width 0.125)
		(layer "In2.Cu")
		(net 63)
	)
	(segment
		(start 99.7034 82.0875)
		(end 98.3466 82.0875)
		(width 0.125)
		(layer "In2.Cu")
		(net 63)
	)
	(segment
		(start 88.587501 84.704527)
		(end 88.709477 84.826503)
		(width 0.125)
		(layer "In2.Cu")
		(net 63)
	)
	(segment
		(start 96.2534 81.0875)
		(end 95.6875 81.6534)
		(width 0.125)
		(layer "In2.Cu")
		(net 63)
	)
	(segment
		(start 68.05 107.7375)
		(end 68.05 107.95)
		(width 0.125)
		(layer "In2.Cu")
		(net 63)
	)
	(segment
		(start 118.3534 82.6875)
		(end 117.3534 83.6875)
		(width 0.125)
		(layer "In2.Cu")
		(net 63)
	)
	(segment
		(start 104.0466 83.2875)
		(end 102.5466 81.7875)
		(width 0.125)
		(layer "In2.Cu")
		(net 63)
	)
	(segment
		(start 92.377187 82.6925)
		(end 92.377187 82.12)
		(width 0.125)
		(layer "In2.Cu")
		(net 63)
	)
	(segment
		(start 124.4534 83.0875)
		(end 119.7466 83.0875)
		(width 0.125)
		(layer "In2.Cu")
		(net 63)
	)
	(segment
		(start 87.341223 85.013885)
		(end 87.498554 85.171216)
		(width 0.125)
		(layer "In2.Cu")
		(net 63)
	)
	(segment
		(start 110.0534 82.7875)
		(end 109.5534 83.2875)
		(width 0.125)
		(layer "In2.Cu")
		(net 63)
	)
	(segment
		(start 88.709477 84.978531)
		(end 88.631695 85.056314)
		(width 0.125)
		(layer "In2.Cu")
		(net 63)
	)
	(segment
		(start 128.168031 79.087499)
		(end 128.168031 79.972869)
		(width 0.125)
		(layer "In2.Cu")
		(net 63)
	)
	(segment
		(start 86.0443 84.975)
		(end 85.9343 84.975)
		(width 0.125)
		(layer "In2.Cu")
		(net 63)
	)
	(segment
		(start 88.5875 82.5534)
		(end 88.5875 82.6466)
		(width 0.125)
		(layer "In2.Cu")
		(net 63)
	)
	(segment
		(start 97.3466 81.0875)
		(end 96.2534 81.0875)
		(width 0.125)
		(layer "In2.Cu")
		(net 63)
	)
	(segment
		(start 119.3466 82.6875)
		(end 118.3534 82.6875)
		(width 0.125)
		(layer "In2.Cu")
		(net 63)
	)
	(segment
		(start 86.7018 86.12)
		(end 86.7018 86.4925)
		(width 0.125)
		(layer "In2.Cu")
		(net 63)
	)
	(segment
		(start 87.498554 85.323244)
		(end 87.420773 85.401027)
		(width 0.125)
		(layer "In2.Cu")
		(net 63)
	)
	(segment
		(start 68.1875 108.7534)
		(end 67.6534 109.2875)
		(width 0.125)
		(layer "In2.Cu")
		(net 63)
	)
	(segment
		(start 116.1466 83.6875)
		(end 115.7466 83.2875)
		(width 0.125)
		(layer "In2.Cu")
		(net 63)
	)
	(arc
		(start 85.9343 84.975)
		(mid 85.699187 85.072387)
		(end 85.6018 85.3075)
		(width 0.125)
		(layer "In2.Cu")
		(net 63)
	)
	(arc
		(start 87.341223 84.543659)
		(mid 87.243836 84.778772)
		(end 87.341223 85.013885)
		(width 0.125)
		(layer "In2.Cu")
		(net 63)
	)
	(arc
		(start 88.95 83.1966)
		(mid 88.929864 83.245214)
		(end 88.88125 83.26535)
		(width 0.125)
		(layer "In2.Cu")
		(net 63)
	)
	(arc
		(start 93.034687 81.7875)
		(mid 92.799574 81.884887)
		(end 92.702187 82.12)
		(width 0.125)
		(layer "In2.Cu")
		(net 63)
	)
	(arc
		(start 92.484687 82.8)
		(mid 92.408673 82.768514)
		(end 92.377187 82.6925)
		(width 0.125)
		(layer "In2.Cu")
		(net 63)
	)
	(arc
		(start 88.5875 82.6466)
		(mid 88.673537 82.854313)
		(end 88.88125 82.94035)
		(width 0.125)
		(layer "In2.Cu")
		(net 63)
	)
	(arc
		(start 87.0343 85.7875)
		(mid 86.799187 85.884887)
		(end 86.7018 86.12)
		(width 0.125)
		(layer "In2.Cu")
		(net 63)
	)
	(arc
		(start 88.88125 83.26535)
		(mid 88.673537 83.351387)
		(end 88.5875 83.5591)
		(width 0.125)
		(layer "In2.Cu")
		(net 63)
	)
	(arc
		(start 92.377187 82.12)
		(mid 92.2798 81.884887)
		(end 92.044687 81.7875)
		(width 0.125)
		(layer "In2.Cu")
		(net 63)
	)
	(arc
		(start 85.2768 86.12)
		(mid 85.179413 85.884887)
		(end 84.9443 85.7875)
		(width 0.125)
		(layer "In2.Cu")
		(net 63)
	)
	(arc
		(start 88.709477 84.826503)
		(mid 88.740963 84.902517)
		(end 88.709477 84.978531)
		(width 0.125)
		(layer "In2.Cu")
		(net 63)
	)
	(arc
		(start 86.3768 85.3075)
		(mid 86.279413 85.072387)
		(end 86.0443 84.975)
		(width 0.125)
		(layer "In2.Cu")
		(net 63)
	)
	(arc
		(start 88.631695 85.056314)
		(mid 88.555681 85.0878)
		(end 88.479667 85.056314)
		(width 0.125)
		(layer "In2.Cu")
		(net 63)
	)
	(arc
		(start 85.6018 86.4925)
		(mid 85.570314 86.568514)
		(end 85.4943 86.6)
		(width 0.125)
		(layer "In2.Cu")
		(net 63)
	)
	(arc
		(start 86.7018 86.4925)
		(mid 86.670314 86.568514)
		(end 86.5943 86.6)
		(width 0.125)
		(layer "In2.Cu")
		(net 63)
	)
	(arc
		(start 87.498554 85.171216)
		(mid 87.53004 85.24723)
		(end 87.498554 85.323244)
		(width 0.125)
		(layer "In2.Cu")
		(net 63)
	)
	(arc
		(start 92.702187 82.6925)
		(mid 92.670701 82.768514)
		(end 92.594687 82.8)
		(width 0.125)
		(layer "In2.Cu")
		(net 63)
	)
	(arc
		(start 88.88125 82.94035)
		(mid 88.929864 82.960486)
		(end 88.95 83.0091)
		(width 0.125)
		(layer "In2.Cu")
		(net 63)
	)
	(arc
		(start 85.3843 86.6)
		(mid 85.308286 86.568514)
		(end 85.2768 86.4925)
		(width 0.125)
		(layer "In2.Cu")
		(net 63)
	)
	(arc
		(start 86.4843 86.6)
		(mid 86.408286 86.568514)
		(end 86.3768 86.4925)
		(width 0.125)
		(layer "In2.Cu")
		(net 63)
	)
	(arc
		(start 87.889231 84.465878)
		(mid 87.654118 84.368491)
		(end 87.419005 84.465878)
		(width 0.125)
		(layer "In2.Cu")
		(net 63)
	)
	(arc
		(start 88.587501 84.234301)
		(mid 88.490114 84.469414)
		(end 88.587501 84.704527)
		(width 0.125)
		(layer "In2.Cu")
		(net 63)
	)
	(segment
		(start 126.030532 85.65)
		(end 125.755532 85.925)
		(width 0.17)
		(layer "F.Cu")
		(net 64)
	)
	(segment
		(start 125.755532 86.275)
		(end 125.880532 86.4)
		(width 0.17)
		(layer "F.Cu")
		(net 64)
	)
	(segment
		(start 125.755532 85.925)
		(end 125.755532 86.275)
		(width 0.17)
		(layer "F.Cu")
		(net 64)
	)
	(via
		(at 125.880532 86.4)
		(size 0.45)
		(drill 0.1)
		(layers "F.Cu" "B.Cu")
		(net 64)
	)
	(via
		(at 65.9 112.9875)
		(size 0.45)
		(drill 0.1)
		(layers "F.Cu" "B.Cu")
		(net 64)
	)
	(segment
		(start 65.643938 112.875)
		(end 65.7875 112.875)
		(width 0.17)
		(layer "B.Cu")
		(net 64)
	)
	(segment
		(start 65.04 112.96)
		(end 65.115 112.885)
		(width 0.17)
		(layer "B.Cu")
		(net 64)
	)
	(segment
		(start 65.115 112.885)
		(end 65.633938 112.885)
		(width 0.17)
		(layer "B.Cu")
		(net 64)
	)
	(segment
		(start 65.633938 112.885)
		(end 65.643938 112.875)
		(width 0.17)
		(layer "B.Cu")
		(net 64)
	)
	(segment
		(start 64.59 112.96)
		(end 65.04 112.96)
		(width 0.17)
		(layer "B.Cu")
		(net 64)
	)
	(segment
		(start 65.7875 112.875)
		(end 65.9 112.9875)
		(width 0.17)
		(layer "B.Cu")
		(net 64)
	)
	(segment
		(start 89.7125 89.208492)
		(end 89.632199 89.128191)
		(width 0.125)
		(layer "In2.Cu")
		(net 64)
	)
	(segment
		(start 90.849528 88.450469)
		(end 91.402187 89.003128)
		(width 0.125)
		(layer "In2.Cu")
		(net 64)
	)
	(segment
		(start 125.3466 87.3125)
		(end 125.693033 86.966067)
		(width 0.125)
		(layer "In2.Cu")
		(net 64)
	)
	(segment
		(start 92.6271 86.832)
		(end 92.6271 86.318447)
		(width 0.125)
		(layer "In2.Cu")
		(net 64)
	)
	(segment
		(start 99.4826 87.2125)
		(end 104.5534 87.2125)
		(width 0.125)
		(layer "In2.Cu")
		(net 64)
	)
	(segment
		(start 95.410799 86.780101)
		(end 95.648401 86.780101)
		(width 0.125)
		(layer "In2.Cu")
		(net 64)
	)
	(segment
		(start 76.886 90.866254)
		(end 77.02 90.866254)
		(width 0.125)
		(layer "In2.Cu")
		(net 64)
	)
	(segment
		(start 108.6466 87.3125)
		(end 125.3466 87.3125)
		(width 0.125)
		(layer "In2.Cu")
		(net 64)
	)
	(segment
		(start 79.473 89.8125)
		(end 79.78675 89.8125)
		(width 0.125)
		(layer "In2.Cu")
		(net 64)
	)
	(segment
		(start 77.556 89.8125)
		(end 77.69 89.8125)
		(width 0.125)
		(layer "In2.Cu")
		(net 64)
	)
	(segment
		(start 79.94225 89.968)
		(end 79.94225 90.081553)
		(width 0.125)
		(layer "In2.Cu")
		(net 64)
	)
	(segment
		(start 93.4526 88.262053)
		(end 93.5866 88.262053)
		(width 0.125)
		(layer "In2.Cu")
		(net 64)
	)
	(segment
		(start 97.4726 88.262053)
		(end 97.6066 88.262053)
		(width 0.125)
		(layer "In2.Cu")
		(net 64)
	)
	(segment
		(start 105.4534 88.1125)
		(end 107.8466 88.1125)
		(width 0.125)
		(layer "In2.Cu")
		(net 64)
	)
	(segment
		(start 97.9871 87.881553)
		(end 97.9871 87.368)
		(width 0.125)
		(layer "In2.Cu")
		(net 64)
	)
	(segment
		(start 78.803 90.1625)
		(end 79.123 90.1625)
		(width 0.125)
		(layer "In2.Cu")
		(net 64)
	)
	(segment
		(start 97.0921 87.368)
		(end 97.0921 87.881553)
		(width 0.125)
		(layer "In2.Cu")
		(net 64)
	)
	(segment
		(start 107.8466 88.1125)
		(end 108.6466 87.3125)
		(width 0.125)
		(layer "In2.Cu")
		(net 64)
	)
	(segment
		(start 93.0721 86.318447)
		(end 93.0721 87.881553)
		(width 0.125)
		(layer "In2.Cu")
		(net 64)
	)
	(segment
		(start 98.8126 88.262077)
		(end 98.9466 88.262077)
		(width 0.125)
		(layer "In2.Cu")
		(net 64)
	)
	(segment
		(start 96.6471 87.78156)
		(end 96.6471 87.368)
		(width 0.125)
		(layer "In2.Cu")
		(net 64)
	)
	(segment
		(start 95.7521 86.8838)
		(end 95.7521 87.78156)
		(width 0.125)
		(layer "In2.Cu")
		(net 64)
	)
	(segment
		(start 72.046599 112.812501)
		(end 72.7125 112.1466)
		(width 0.125)
		(layer "In2.Cu")
		(net 64)
	)
	(segment
		(start 90.579716 87.960747)
		(end 90.674468 87.865996)
		(width 0.125)
		(layer "In2.Cu")
		(net 64)
	)
	(segment
		(start 90.216667 89.083332)
		(end 90.769325 89.63599)
		(width 0.125)
		(layer "In2.Cu")
		(net 64)
	)
	(segment
		(start 80.99275 89.8125)
		(end 89.6466 89.8125)
		(width 0.125)
		(layer "In2.Cu")
		(net 64)
	)
	(segment
		(start 98.4321 87.368)
		(end 98.4321 87.881577)
		(width 0.125)
		(layer "In2.Cu")
		(net 64)
	)
	(segment
		(start 94.7926 88.212071)
		(end 94.9266 88.212071)
		(width 0.125)
		(layer "In2.Cu")
		(net 64)
	)
	(segment
		(start 93.9671 87.881553)
		(end 93.9671 86.318423)
		(width 0.125)
		(layer "In2.Cu")
		(net 64)
	)
	(segment
		(start 89.946863 88.813527)
		(end 90.21667 89.083334)
		(width 0.125)
		(layer "In2.Cu")
		(net 64)
	)
	(segment
		(start 91.607547 87.851553)
		(end 92.2466 87.2125)
		(width 0.125)
		(layer "In2.Cu")
		(net 64)
	)
	(segment
		(start 94.4121 86.318423)
		(end 94.4121 87.831571)
		(width 0.125)
		(layer "In2.Cu")
		(net 64)
	)
	(segment
		(start 95.3071 87.831571)
		(end 95.3071 86.8838)
		(width 0.125)
		(layer "In2.Cu")
		(net 64)
	)
	(segment
		(start 90.579716 88.180657)
		(end 90.84953 88.450471)
		(width 0.125)
		(layer "In2.Cu")
		(net 64)
	)
	(segment
		(start 77.4005 90.485754)
		(end 77.4005 89.968)
		(width 0.125)
		(layer "In2.Cu")
		(net 64)
	)
	(segment
		(start 104.5534 87.2125)
		(end 105.4534 88.1125)
		(width 0.125)
		(layer "In2.Cu")
		(net 64)
	)
	(segment
		(start 78.5155 89.214246)
		(end 78.5155 89.875)
		(width 0.125)
		(layer "In2.Cu")
		(net 64)
	)
	(segment
		(start 94.1226 86.162923)
		(end 94.2566 86.162923)
		(width 0.125)
		(layer "In2.Cu")
		(net 64)
	)
	(segment
		(start 66.074999 112.812501)
		(end 72.046599 112.812501)
		(width 0.125)
		(layer "In2.Cu")
		(net 64)
	)
	(segment
		(start 90.894378 87.865996)
		(end 90.974688 87.946306)
		(width 0.125)
		(layer "In2.Cu")
		(net 64)
	)
	(segment
		(start 96.8026 87.2125)
		(end 96.9366 87.2125)
		(width 0.125)
		(layer "In2.Cu")
		(net 64)
	)
	(segment
		(start 89.6322 88.908279)
		(end 89.726953 88.813527)
		(width 0.125)
		(layer "In2.Cu")
		(net 64)
	)
	(segment
		(start 90.849528 88.450469)
		(end 90.84953 88.450471)
		(width 0.125)
		(layer "In2.Cu")
		(net 64)
	)
	(segment
		(start 72.7125 112.1466)
		(end 72.7125 90.2466)
		(width 0.125)
		(layer "In2.Cu")
		(net 64)
	)
	(segment
		(start 78.0705 89.432)
		(end 78.0705 89.214246)
		(width 0.125)
		(layer "In2.Cu")
		(net 64)
	)
	(segment
		(start 99.3271 87.881577)
		(end 99.3271 87.368)
		(width 0.125)
		(layer "In2.Cu")
		(net 64)
	)
	(segment
		(start 65.9 112.9875)
		(end 66.074999 112.812501)
		(width 0.125)
		(layer "In2.Cu")
		(net 64)
	)
	(segment
		(start 89.6466 89.8125)
		(end 89.7125 89.7466)
		(width 0.125)
		(layer "In2.Cu")
		(net 64)
	)
	(segment
		(start 96.1326 88.16206)
		(end 96.2666 88.16206)
		(width 0.125)
		(layer "In2.Cu")
		(net 64)
	)
	(segment
		(start 76.5055 89.968)
		(end 76.5055 90.485754)
		(width 0.125)
		(layer "In2.Cu")
		(net 64)
	)
	(segment
		(start 125.693033 86.587499)
		(end 125.880532 86.4)
		(width 0.125)
		(layer "In2.Cu")
		(net 64)
	)
	(segment
		(start 80.32275 90.462053)
		(end 80.45675 90.462053)
		(width 0.125)
		(layer "In2.Cu")
		(net 64)
	)
	(segment
		(start 91.307434 89.63599)
		(end 91.402187 89.541236)
		(width 0.125)
		(layer "In2.Cu")
		(net 64)
	)
	(segment
		(start 80.83725 90.081553)
		(end 80.83725 89.968)
		(width 0.125)
		(layer "In2.Cu")
		(net 64)
	)
	(segment
		(start 125.693033 86.966067)
		(end 125.693033 86.587499)
		(width 0.125)
		(layer "In2.Cu")
		(net 64)
	)
	(segment
		(start 91.512796 87.946306)
		(end 91.607547 87.851553)
		(width 0.125)
		(layer "In2.Cu")
		(net 64)
	)
	(segment
		(start 78.226 89.058746)
		(end 78.36 89.058746)
		(width 0.125)
		(layer "In2.Cu")
		(net 64)
	)
	(segment
		(start 92.7826 86.162947)
		(end 92.9166 86.162947)
		(width 0.125)
		(layer "In2.Cu")
		(net 64)
	)
	(segment
		(start 72.7125 90.2466)
		(end 73.1466 89.8125)
		(width 0.125)
		(layer "In2.Cu")
		(net 64)
	)
	(segment
		(start 90.21667 89.083334)
		(end 90.216667 89.083332)
		(width 0.125)
		(layer "In2.Cu")
		(net 64)
	)
	(segment
		(start 98.1426 87.2125)
		(end 98.2766 87.2125)
		(width 0.125)
		(layer "In2.Cu")
		(net 64)
	)
	(segment
		(start 73.1466 89.8125)
		(end 76.35 89.8125)
		(width 0.125)
		(layer "In2.Cu")
		(net 64)
	)
	(arc
		(start 92.2466 87.2125)
		(mid 92.515654 87.101054)
		(end 92.6271 86.832)
		(width 0.125)
		(layer "In2.Cu")
		(net 64)
	)
	(arc
		(start 97.6066 88.262053)
		(mid 97.875654 88.150607)
		(end 97.9871 87.881553)
		(width 0.125)
		(layer "In2.Cu")
		(net 64)
	)
	(arc
		(start 95.3071 86.8838)
		(mid 95.337473 86.810474)
		(end 95.410799 86.780101)
		(width 0.125)
		(layer "In2.Cu")
		(net 64)
	)
	(arc
		(start 98.2766 87.2125)
		(mid 98.386555 87.258045)
		(end 98.4321 87.368)
		(width 0.125)
		(layer "In2.Cu")
		(net 64)
	)
	(arc
		(start 78.0705 89.214246)
		(mid 78.116045 89.104291)
		(end 78.226 89.058746)
		(width 0.125)
		(layer "In2.Cu")
		(net 64)
	)
	(arc
		(start 92.6271 86.318447)
		(mid 92.672645 86.208492)
		(end 92.7826 86.162947)
		(width 0.125)
		(layer "In2.Cu")
		(net 64)
	)
	(arc
		(start 94.9266 88.212071)
		(mid 95.195654 88.100625)
		(end 95.3071 87.831571)
		(width 0.125)
		(layer "In2.Cu")
		(net 64)
	)
	(arc
		(start 96.9366 87.2125)
		(mid 97.046555 87.258045)
		(end 97.0921 87.368)
		(width 0.125)
		(layer "In2.Cu")
		(net 64)
	)
	(arc
		(start 95.7521 87.78156)
		(mid 95.863546 88.050614)
		(end 96.1326 88.16206)
		(width 0.125)
		(layer "In2.Cu")
		(net 64)
	)
	(arc
		(start 90.674468 87.865996)
		(mid 90.784423 87.820451)
		(end 90.894378 87.865996)
		(width 0.125)
		(layer "In2.Cu")
		(net 64)
	)
	(arc
		(start 79.4105 89.875)
		(mid 79.428806 89.830806)
		(end 79.473 89.8125)
		(width 0.125)
		(layer "In2.Cu")
		(net 64)
	)
	(arc
		(start 79.78675 89.8125)
		(mid 79.896705 89.858045)
		(end 79.94225 89.968)
		(width 0.125)
		(layer "In2.Cu")
		(net 64)
	)
	(arc
		(start 89.726953 88.813527)
		(mid 89.836908 88.767982)
		(end 89.946863 88.813527)
		(width 0.125)
		(layer "In2.Cu")
		(net 64)
	)
	(arc
		(start 77.4005 89.968)
		(mid 77.446045 89.858045)
		(end 77.556 89.8125)
		(width 0.125)
		(layer "In2.Cu")
		(net 64)
	)
	(arc
		(start 95.648401 86.780101)
		(mid 95.721727 86.810474)
		(end 95.7521 86.8838)
		(width 0.125)
		(layer "In2.Cu")
		(net 64)
	)
	(arc
		(start 94.2566 86.162923)
		(mid 94.366555 86.208468)
		(end 94.4121 86.318423)
		(width 0.125)
		(layer "In2.Cu")
		(net 64)
	)
	(arc
		(start 96.6471 87.368)
		(mid 96.692645 87.258045)
		(end 96.8026 87.2125)
		(width 0.125)
		(layer "In2.Cu")
		(net 64)
	)
	(arc
		(start 98.9466 88.262077)
		(mid 99.215654 88.150631)
		(end 99.3271 87.881577)
		(width 0.125)
		(layer "In2.Cu")
		(net 64)
	)
	(arc
		(start 89.7125 89.7466)
		(mid 89.823946 89.477546)
		(end 89.7125 89.208492)
		(width 0.125)
		(layer "In2.Cu")
		(net 64)
	)
	(arc
		(start 97.9871 87.368)
		(mid 98.032645 87.258045)
		(end 98.1426 87.2125)
		(width 0.125)
		(layer "In2.Cu")
		(net 64)
	)
	(arc
		(start 92.9166 86.162947)
		(mid 93.026555 86.208492)
		(end 93.0721 86.318447)
		(width 0.125)
		(layer "In2.Cu")
		(net 64)
	)
	(arc
		(start 76.5055 90.485754)
		(mid 76.616946 90.754808)
		(end 76.886 90.866254)
		(width 0.125)
		(layer "In2.Cu")
		(net 64)
	)
	(arc
		(start 90.769325 89.63599)
		(mid 91.03838 89.747436)
		(end 91.307434 89.63599)
		(width 0.125)
		(layer "In2.Cu")
		(net 64)
	)
	(arc
		(start 90.579716 88.180657)
		(mid 90.534171 88.070702)
		(end 90.579716 87.960747)
		(width 0.125)
		(layer "In2.Cu")
		(net 64)
	)
	(arc
		(start 79.94225 90.081553)
		(mid 80.053696 90.350607)
		(end 80.32275 90.462053)
		(width 0.125)
		(layer "In2.Cu")
		(net 64)
	)
	(arc
		(start 93.0721 87.881553)
		(mid 93.183546 88.150607)
		(end 93.4526 88.262053)
		(width 0.125)
		(layer "In2.Cu")
		(net 64)
	)
	(arc
		(start 77.69 89.8125)
		(mid 77.959054 89.701054)
		(end 78.0705 89.432)
		(width 0.125)
		(layer "In2.Cu")
		(net 64)
	)
	(arc
		(start 90.974688 87.946306)
		(mid 91.243742 88.057752)
		(end 91.512796 87.946306)
		(width 0.125)
		(layer "In2.Cu")
		(net 64)
	)
	(arc
		(start 76.35 89.8125)
		(mid 76.459955 89.858045)
		(end 76.5055 89.968)
		(width 0.125)
		(layer "In2.Cu")
		(net 64)
	)
	(arc
		(start 96.2666 88.16206)
		(mid 96.535654 88.050614)
		(end 96.6471 87.78156)
		(width 0.125)
		(layer "In2.Cu")
		(net 64)
	)
	(arc
		(start 79.123 90.1625)
		(mid 79.326293 90.078293)
		(end 79.4105 89.875)
		(width 0.125)
		(layer "In2.Cu")
		(net 64)
	)
	(arc
		(start 94.4121 87.831571)
		(mid 94.523546 88.100625)
		(end 94.7926 88.212071)
		(width 0.125)
		(layer "In2.Cu")
		(net 64)
	)
	(arc
		(start 89.632199 89.128191)
		(mid 89.586655 89.018234)
		(end 89.6322 88.908279)
		(width 0.125)
		(layer "In2.Cu")
		(net 64)
	)
	(arc
		(start 77.02 90.866254)
		(mid 77.289054 90.754808)
		(end 77.4005 90.485754)
		(width 0.125)
		(layer "In2.Cu")
		(net 64)
	)
	(arc
		(start 78.36 89.058746)
		(mid 78.469955 89.104291)
		(end 78.5155 89.214246)
		(width 0.125)
		(layer "In2.Cu")
		(net 64)
	)
	(arc
		(start 91.402187 89.541236)
		(mid 91.513633 89.272182)
		(end 91.402187 89.003128)
		(width 0.125)
		(layer "In2.Cu")
		(net 64)
	)
	(arc
		(start 80.45675 90.462053)
		(mid 80.725804 90.350607)
		(end 80.83725 90.081553)
		(width 0.125)
		(layer "In2.Cu")
		(net 64)
	)
	(arc
		(start 80.83725 89.968)
		(mid 80.882795 89.858045)
		(end 80.99275 89.8125)
		(width 0.125)
		(layer "In2.Cu")
		(net 64)
	)
	(arc
		(start 98.4321 87.881577)
		(mid 98.543546 88.150631)
		(end 98.8126 88.262077)
		(width 0.125)
		(layer "In2.Cu")
		(net 64)
	)
	(arc
		(start 93.9671 86.318423)
		(mid 94.012645 86.208468)
		(end 94.1226 86.162923)
		(width 0.125)
		(layer "In2.Cu")
		(net 64)
	)
	(arc
		(start 93.5866 88.262053)
		(mid 93.855654 88.150607)
		(end 93.9671 87.881553)
		(width 0.125)
		(layer "In2.Cu")
		(net 64)
	)
	(arc
		(start 78.5155 89.875)
		(mid 78.599707 90.078293)
		(end 78.803 90.1625)
		(width 0.125)
		(layer "In2.Cu")
		(net 64)
	)
	(arc
		(start 99.3271 87.368)
		(mid 99.372645 87.258045)
		(end 99.4826 87.2125)
		(width 0.125)
		(layer "In2.Cu")
		(net 64)
	)
	(arc
		(start 97.0921 87.881553)
		(mid 97.203546 88.150607)
		(end 97.4726 88.262053)
		(width 0.125)
		(layer "In2.Cu")
		(net 64)
	)
	(segment
		(start 132.45 111.05)
		(end 132.45 110.65)
		(width 0.1)
		(layer "F.Cu")
		(net 65)
	)
	(segment
		(start 130.1 111.6)
		(end 131.9 111.6)
		(width 0.1)
		(layer "F.Cu")
		(net 65)
	)
	(segment
		(start 127.8 111.2)
		(end 129.7 111.2)
		(width 0.1)
		(layer "F.Cu")
		(net 65)
	)
	(segment
		(start 129.7 111.2)
		(end 130.1 111.6)
		(width 0.1)
		(layer "F.Cu")
		(net 65)
	)
	(segment
		(start 131.9 111.6)
		(end 132.45 111.05)
		(width 0.1)
		(layer "F.Cu")
		(net 65)
	)
	(via
		(at 127.8 111.2)
		(size 0.45)
		(drill 0.1)
		(layers "F.Cu" "B.Cu")
		(free yes)
		(net 65)
	)
	(via
		(at 132.45 110.65)
		(size 0.45)
		(drill 0.1)
		(layers "F.Cu" "B.Cu")
		(net 65)
	)
	(via
		(at 77.5 106.2)
		(size 0.45)
		(drill 0.1)
		(layers "F.Cu" "B.Cu")
		(net 65)
	)
	(via
		(at 137.930532 81.15)
		(size 0.45)
		(drill 0.1)
		(layers "F.Cu" "B.Cu")
		(net 65)
	)
	(segment
		(start 76.360532 106.2)
		(end 75.775532 105.615)
		(width 0.1)
		(layer "B.Cu")
		(net 65)
	)
	(segment
		(start 77.5 106.2)
		(end 76.360532 106.2)
		(width 0.1)
		(layer "B.Cu")
		(net 65)
	)
	(segment
		(start 136.9 87.3)
		(end 131.2 93)
		(width 0.1)
		(layer "In5.Cu")
		(net 65)
	)
	(segment
		(start 127 110.8)
		(end 113.73137 110.8)
		(width 0.1)
		(layer "In5.Cu")
		(net 65)
	)
	(segment
		(start 127.4 111.2)
		(end 127 110.8)
		(width 0.1)
		(layer "In5.Cu")
		(net 65)
	)
	(segment
		(start 110.6 108.4)
		(end 106.1 108.4)
		(width 0.1)
		(layer "In5.Cu")
		(net 65)
	)
	(segment
		(start 112.699598 109.768228)
		(end 111.968228 109.768228)
		(width 0.1)
		(layer "In5.Cu")
		(net 65)
	)
	(segment
		(start 130.6 96.6)
		(end 130.6 110)
		(width 0.1)
		(layer "In5.Cu")
		(net 65)
	)
	(segment
		(start 79.15 109.55)
		(end 77.5 107.9)
		(width 0.1)
		(layer "In5.Cu")
		(net 65)
	)
	(segment
		(start 136.9 82.1)
		(end 136.9 87.3)
		(width 0.1)
		(layer "In5.Cu")
		(net 65)
	)
	(segment
		(start 137.930532 81.15)
		(end 137.85 81.15)
		(width 0.1)
		(layer "In5.Cu")
		(net 65)
	)
	(segment
		(start 137.85 81.15)
		(end 136.9 82.1)
		(width 0.1)
		(layer "In5.Cu")
		(net 65)
	)
	(segment
		(start 131.2 93)
		(end 131.2 96)
		(width 0.1)
		(layer "In5.Cu")
		(net 65)
	)
	(segment
		(start 131.2 96)
		(end 130.6 96.6)
		(width 0.1)
		(layer "In5.Cu")
		(net 65)
	)
	(segment
		(start 127.8 111.2)
		(end 127.4 111.2)
		(width 0.1)
		(layer "In5.Cu")
		(net 65)
	)
	(segment
		(start 106.1 108.4)
		(end 104 110.5)
		(width 0.1)
		(layer "In5.Cu")
		(net 65)
	)
	(segment
		(start 104 115.55)
		(end 101.6 117.95)
		(width 0.1)
		(layer "In5.Cu")
		(net 65)
	)
	(segment
		(start 79.4 120)
		(end 79.15 119.75)
		(width 0.1)
		(layer "In5.Cu")
		(net 65)
	)
	(segment
		(start 79.15 119.75)
		(end 79.15 109.55)
		(width 0.1)
		(layer "In5.Cu")
		(net 65)
	)
	(segment
		(start 130.9 110.3)
		(end 132.1 110.3)
		(width 0.1)
		(layer "In5.Cu")
		(net 65)
	)
	(segment
		(start 100.2 119.4)
		(end 86.75 119.4)
		(width 0.1)
		(layer "In5.Cu")
		(net 65)
	)
	(segment
		(start 101.6 117.95)
		(end 101.6 118)
		(width 0.1)
		(layer "In5.Cu")
		(net 65)
	)
	(segment
		(start 77.5 107.9)
		(end 77.5 106.2)
		(width 0.1)
		(layer "In5.Cu")
		(net 65)
	)
	(segment
		(start 86.15 120)
		(end 79.4 120)
		(width 0.1)
		(layer "In5.Cu")
		(net 65)
	)
	(segment
		(start 86.75 119.4)
		(end 86.15 120)
		(width 0.1)
		(layer "In5.Cu")
		(net 65)
	)
	(segment
		(start 111.968228 109.768228)
		(end 110.6 108.4)
		(width 0.1)
		(layer "In5.Cu")
		(net 65)
	)
	(segment
		(start 113.73137 110.8)
		(end 112.699598 109.768228)
		(width 0.1)
		(layer "In5.Cu")
		(net 65)
	)
	(segment
		(start 104 110.5)
		(end 104 115.55)
		(width 0.1)
		(layer "In5.Cu")
		(net 65)
	)
	(segment
		(start 130.6 110)
		(end 130.9 110.3)
		(width 0.1)
		(layer "In5.Cu")
		(net 65)
	)
	(segment
		(start 132.1 110.3)
		(end 132.45 110.65)
		(width 0.1)
		(layer "In5.Cu")
		(net 65)
	)
	(segment
		(start 101.6 118)
		(end 100.2 119.4)
		(width 0.1)
		(layer "In5.Cu")
		(net 65)
	)
	(segment
		(start 126.380532 78)
		(end 126.230532 78.15)
		(width 0.17)
		(layer "F.Cu")
		(net 66)
	)
	(segment
		(start 126.380532 77.6)
		(end 126.380532 78)
		(width 0.17)
		(layer "F.Cu")
		(net 66)
	)
	(via
		(at 62.825 101.325)
		(size 0.45)
		(drill 0.1)
		(layers "F.Cu" "B.Cu")
		(net 66)
	)
	(via
		(at 126.380532 77.6)
		(size 0.45)
		(drill 0.1)
		(layers "F.Cu" "B.Cu")
		(net 66)
	)
	(segment
		(start 63.286 102.386)
		(end 62.95 102.05)
		(width 0.17)
		(layer "B.Cu")
		(net 66)
	)
	(segment
		(start 64.065 102.386)
		(end 63.286 102.386)
		(width 0.17)
		(layer "B.Cu")
		(net 66)
	)
	(segment
		(start 62.95 101.45)
		(end 62.825 101.325)
		(width 0.17)
		(layer "B.Cu")
		(net 66)
	)
	(segment
		(start 64.59 102.461)
		(end 64.14 102.461)
		(width 0.17)
		(layer "B.Cu")
		(net 66)
	)
	(segment
		(start 62.95 102.05)
		(end 62.95 101.45)
		(width 0.17)
		(layer "B.Cu")
		(net 66)
	)
	(segment
		(start 64.14 102.461)
		(end 64.065 102.386)
		(width 0.17)
		(layer "B.Cu")
		(net 66)
	)
	(segment
		(start 102.499894 75.534206)
		(end 102.6966 75.534206)
		(width 0.125)
		(layer "In2.Cu")
		(net 66)
	)
	(segment
		(start 112.66535 75.391253)
		(end 112.66535 76.175)
		(width 0.125)
		(layer "In2.Cu")
		(net 66)
	)
	(segment
		(start 112.99035 76.175)
		(end 112.99035 75.194684)
		(width 0.125)
		(layer "In2.Cu")
		(net 66)
	)
	(segment
		(start 95.6875 75.7534)
		(end 96.3534 75.0875)
		(width 0.125)
		(layer "In2.Cu")
		(net 66)
	)
	(segment
		(start 113.87285 75.8875)
		(end 113.98285 75.8875)
		(width 0.125)
		(layer "In2.Cu")
		(net 66)
	)
	(segment
		(start 115.41535 75.78935)
		(end 115.41535 76.210649)
		(width 0.125)
		(layer "In2.Cu")
		(net 66)
	)
	(segment
		(start 84.628306 76.212599)
		(end 84.706085 76.134817)
		(width 0.125)
		(layer "In2.Cu")
		(net 66)
	)
	(segment
		(start 98.1466 76.2375)
		(end 99.5034 76.2375)
		(width 0.125)
		(layer "In2.Cu")
		(net 66)
	)
	(segment
		(start 83.850489 76.990416)
		(end 83.928268 76.912634)
		(width 0.125)
		(layer "In2.Cu")
		(net 66)
	)
	(segment
		(start 117.61535 75.394663)
		(end 117.61535 75.78)
		(width 0.125)
		(layer "In2.Cu")
		(net 66)
	)
	(segment
		(start 83.458938 76.750893)
		(end 83.698461 76.990416)
		(width 0.125)
		(layer "In2.Cu")
		(net 66)
	)
	(segment
		(start 122.3466 75.8875)
		(end 125.0466 78.5875)
		(width 0.125)
		(layer "In2.Cu")
		(net 66)
	)
	(segment
		(start 103.049894 75.8875)
		(end 105.7466 75.8875)
		(width 0.125)
		(layer "In2.Cu")
		(net 66)
	)
	(segment
		(start 114.64035 76.755337)
		(end 114.64035 75.78935)
		(width 0.125)
		(layer "In2.Cu")
		(net 66)
	)
	(segment
		(start 115.74035 76.210649)
		(end 115.74035 75.694673)
		(width 0.125)
		(layer "In2.Cu")
		(net 66)
	)
	(segment
		(start 83.928268 76.760606)
		(end 83.688736 76.521074)
		(width 0.125)
		(layer "In2.Cu")
		(net 66)
	)
	(segment
		(start 98.0125 76.1034)
		(end 98.1466 76.2375)
		(width 0.125)
		(layer "In2.Cu")
		(net 66)
	)
	(segment
		(start 84.236745 75.973066)
		(end 84.476278 76.212599)
		(width 0.125)
		(layer "In2.Cu")
		(net 66)
	)
	(segment
		(start 118.49035 76.755317)
		(end 118.49035 76.22)
		(width 0.125)
		(layer "In2.Cu")
		(net 66)
	)
	(segment
		(start 115.513498 76.308797)
		(end 115.642202 76.308797)
		(width 0.125)
		(layer "In2.Cu")
		(net 66)
	)
	(segment
		(start 84.706085 76.134817)
		(end 85.0534 75.7875)
		(width 0.125)
		(layer "In2.Cu")
		(net 66)
	)
	(segment
		(start 112.72785 76.2375)
		(end 112.92785 76.2375)
		(width 0.125)
		(layer "In2.Cu")
		(net 66)
	)
	(segment
		(start 100.3866 74.858758)
		(end 100.4966 74.858758)
		(width 0.125)
		(layer "In2.Cu")
		(net 66)
	)
	(segment
		(start 111.34035 76.70874)
		(end 111.34035 76.22)
		(width 0.125)
		(layer "In2.Cu")
		(net 66)
	)
	(segment
		(start 96.3534 75.0875)
		(end 97.4466 75.0875)
		(width 0.125)
		(layer "In2.Cu")
		(net 66)
	)
	(segment
		(start 94.4466 76.4875)
		(end 95.2534 76.4875)
		(width 0.125)
		(layer "In2.Cu")
		(net 66)
	)
	(segment
		(start 100.9366 75.8875)
		(end 101.0466 75.8875)
		(width 0.125)
		(layer "In2.Cu")
		(net 66)
	)
	(segment
		(start 111.89035 75.78)
		(end 111.89035 75.391253)
		(width 0.125)
		(layer "In2.Cu")
		(net 66)
	)
	(segment
		(start 100.0541 75.78)
		(end 100.0541 75.191258)
		(width 0.125)
		(layer "In2.Cu")
		(net 66)
	)
	(segment
		(start 83.688736 76.050848)
		(end 83.766519 75.973066)
		(width 0.125)
		(layer "In2.Cu")
		(net 66)
	)
	(segment
		(start 117.72285 75.8875)
		(end 117.83285 75.8875)
		(width 0.125)
		(layer "In2.Cu")
		(net 66)
	)
	(segment
		(start 82.6875 78.1534)
		(end 83.15045 77.69045)
		(width 0.125)
		(layer "In2.Cu")
		(net 66)
	)
	(segment
		(start 83.15045 77.69045)
		(end 83.150451 77.690451)
		(width 0.125)
		(layer "In2.Cu")
		(net 66)
	)
	(segment
		(start 62.825 101.1875)
		(end 63.087499 100.925001)
		(width 0.125)
		(layer "In2.Cu")
		(net 66)
	)
	(segment
		(start 93.7466 75.7875)
		(end 94.4466 76.4875)
		(width 0.125)
		(layer "In2.Cu")
		(net 66)
	)
	(segment
		(start 108.3534 75.0875)
		(end 109.3466 75.0875)
		(width 0.125)
		(layer "In2.Cu")
		(net 66)
	)
	(segment
		(start 111.01535 75.81865)
		(end 111.01535 76.70874)
		(width 0.125)
		(layer "In2.Cu")
		(net 66)
	)
	(segment
		(start 82.6875 80.3534)
		(end 82.6875 78.1534)
		(width 0.125)
		(layer "In2.Cu")
		(net 66)
	)
	(segment
		(start 105.7466 75.8875)
		(end 106.4466 76.5875)
		(width 0.125)
		(layer "In2.Cu")
		(net 66)
	)
	(segment
		(start 111.67285 75.8875)
		(end 111.78285 75.8875)
		(width 0.125)
		(layer "In2.Cu")
		(net 66)
	)
	(segment
		(start 126.568031 77.972869)
		(end 126.568031 77.787499)
		(width 0.125)
		(layer "In2.Cu")
		(net 66)
	)
	(segment
		(start 117.17285 75.062163)
		(end 117.28285 75.062163)
		(width 0.125)
		(layer "In2.Cu")
		(net 66)
	)
	(segment
		(start 97.4466 75.0875)
		(end 98.0125 75.6534)
		(width 0.125)
		(layer "In2.Cu")
		(net 66)
	)
	(segment
		(start 85.0534 75.7875)
		(end 93.7466 75.7875)
		(width 0.125)
		(layer "In2.Cu")
		(net 66)
	)
	(segment
		(start 95.2534 76.4875)
		(end 95.6875 76.0534)
		(width 0.125)
		(layer "In2.Cu")
		(net 66)
	)
	(segment
		(start 63.087499 100.925001)
		(end 63.087499 86.453401)
		(width 0.125)
		(layer "In2.Cu")
		(net 66)
	)
	(segment
		(start 109.3466 75.0875)
		(end 110.1466 75.8875)
		(width 0.125)
		(layer "In2.Cu")
		(net 66)
	)
	(segment
		(start 102.0366 75.8875)
		(end 102.1466 75.8875)
		(width 0.125)
		(layer "In2.Cu")
		(net 66)
	)
	(segment
		(start 118.27285 76.862817)
		(end 118.38285 76.862817)
		(width 0.125)
		(layer "In2.Cu")
		(net 66)
	)
	(segment
		(start 107.7875 75.6534)
		(end 108.3534 75.0875)
		(width 0.125)
		(layer "In2.Cu")
		(net 66)
	)
	(segment
		(start 82.3534 80.6875)
		(end 82.6875 80.3534)
		(width 0.125)
		(layer "In2.Cu")
		(net 66)
	)
	(segment
		(start 112.22285 75.058753)
		(end 112.33285 75.058753)
		(width 0.125)
		(layer "In2.Cu")
		(net 66)
	)
	(segment
		(start 63.087499 86.453401)
		(end 68.8534 80.6875)
		(width 0.125)
		(layer "In2.Cu")
		(net 66)
	)
	(segment
		(start 114.963499 75.466201)
		(end 115.092201 75.466201)
		(width 0.125)
		(layer "In2.Cu")
		(net 66)
	)
	(segment
		(start 95.6875 76.0534)
		(end 95.6875 75.7534)
		(width 0.125)
		(layer "In2.Cu")
		(net 66)
	)
	(segment
		(start 114.42285 76.862837)
		(end 114.53285 76.862837)
		(width 0.125)
		(layer "In2.Cu")
		(net 66)
	)
	(segment
		(start 99.8534 75.8875)
		(end 99.9466 75.8875)
		(width 0.125)
		(layer "In2.Cu")
		(net 66)
	)
	(segment
		(start 62.825 101.325)
		(end 62.825 101.1875)
		(width 0.125)
		(layer "In2.Cu")
		(net 66)
	)
	(segment
		(start 116.51535 75.694673)
		(end 116.51535 75.78)
		(width 0.125)
		(layer "In2.Cu")
		(net 66)
	)
	(segment
		(start 116.84035 75.78)
		(end 116.84035 75.394663)
		(width 0.125)
		(layer "In2.Cu")
		(net 66)
	)
	(segment
		(start 111.12285 76.81624)
		(end 111.23285 76.81624)
		(width 0.125)
		(layer "In2.Cu")
		(net 66)
	)
	(segment
		(start 101.1541 75.78)
		(end 101.1541 75.541264)
		(width 0.125)
		(layer "In2.Cu")
		(net 66)
	)
	(segment
		(start 118.82285 75.8875)
		(end 122.3466 75.8875)
		(width 0.125)
		(layer "In2.Cu")
		(net 66)
	)
	(segment
		(start 98.0125 75.6534)
		(end 98.0125 76.1034)
		(width 0.125)
		(layer "In2.Cu")
		(net 66)
	)
	(segment
		(start 126.568031 77.787499)
		(end 126.380532 77.6)
		(width 0.125)
		(layer "In2.Cu")
		(net 66)
	)
	(segment
		(start 113.76535 75.194684)
		(end 113.76535 75.78)
		(width 0.125)
		(layer "In2.Cu")
		(net 66)
	)
	(segment
		(start 116.07285 75.362173)
		(end 116.18285 75.362173)
		(width 0.125)
		(layer "In2.Cu")
		(net 66)
	)
	(segment
		(start 68.8534 80.6875)
		(end 82.3534 80.6875)
		(width 0.125)
		(layer "In2.Cu")
		(net 66)
	)
	(segment
		(start 101.9291 75.541264)
		(end 101.9291 75.78)
		(width 0.125)
		(layer "In2.Cu")
		(net 66)
	)
	(segment
		(start 125.9534 78.5875)
		(end 126.568031 77.972869)
		(width 0.125)
		(layer "In2.Cu")
		(net 66)
	)
	(segment
		(start 118.16535 76.22)
		(end 118.16535 76.755317)
		(width 0.125)
		(layer "In2.Cu")
		(net 66)
	)
	(segment
		(start 82.910929 76.828675)
		(end 82.988712 76.750893)
		(width 0.125)
		(layer "In2.Cu")
		(net 66)
	)
	(segment
		(start 99.5034 76.2375)
		(end 99.8534 75.8875)
		(width 0.125)
		(layer "In2.Cu")
		(net 66)
	)
	(segment
		(start 101.4866 75.208764)
		(end 101.5966 75.208764)
		(width 0.125)
		(layer "In2.Cu")
		(net 66)
	)
	(segment
		(start 107.2534 76.5875)
		(end 107.7875 76.0534)
		(width 0.125)
		(layer "In2.Cu")
		(net 66)
	)
	(segment
		(start 114.31535 76.22)
		(end 114.31535 76.755337)
		(width 0.125)
		(layer "In2.Cu")
		(net 66)
	)
	(segment
		(start 125.0466 78.5875)
		(end 125.9534 78.5875)
		(width 0.125)
		(layer "In2.Cu")
		(net 66)
	)
	(segment
		(start 110.5093 75.5248)
		(end 110.7215 75.5248)
		(width 0.125)
		(layer "In2.Cu")
		(net 66)
	)
	(segment
		(start 116.62285 75.8875)
		(end 116.73285 75.8875)
		(width 0.125)
		(layer "In2.Cu")
		(net 66)
	)
	(segment
		(start 107.7875 76.0534)
		(end 107.7875 75.6534)
		(width 0.125)
		(layer "In2.Cu")
		(net 66)
	)
	(segment
		(start 100.8291 75.191258)
		(end 100.8291 75.78)
		(width 0.125)
		(layer "In2.Cu")
		(net 66)
	)
	(segment
		(start 113.32285 74.862184)
		(end 113.43285 74.862184)
		(width 0.125)
		(layer "In2.Cu")
		(net 66)
	)
	(segment
		(start 83.150451 77.538423)
		(end 82.910929 77.298901)
		(width 0.125)
		(layer "In2.Cu")
		(net 66)
	)
	(segment
		(start 106.4466 76.5875)
		(end 107.2534 76.5875)
		(width 0.125)
		(layer "In2.Cu")
		(net 66)
	)
	(arc
		(start 114.31535 76.755337)
		(mid 114.346836 76.831351)
		(end 114.42285 76.862837)
		(width 0.125)
		(layer "In2.Cu")
		(net 66)
	)
	(arc
		(start 102.210747 75.823353)
		(mid 102.295436 75.618895)
		(end 102.499894 75.534206)
		(width 0.125)
		(layer "In2.Cu")
		(net 66)
	)
	(arc
		(start 83.698461 76.990416)
		(mid 83.774475 77.021902)
		(end 83.850489 76.990416)
		(width 0.125)
		(layer "In2.Cu")
		(net 66)
	)
	(arc
		(start 84.476278 76.212599)
		(mid 84.552292 76.244085)
		(end 84.628306 76.212599)
		(width 0.125)
		(layer "In2.Cu")
		(net 66)
	)
	(arc
		(start 115.41535 76.210649)
		(mid 115.444097 76.28005)
		(end 115.513498 76.308797)
		(width 0.125)
		(layer "In2.Cu")
		(net 66)
	)
	(arc
		(start 111.23285 76.81624)
		(mid 111.308864 76.784754)
		(end 111.34035 76.70874)
		(width 0.125)
		(layer "In2.Cu")
		(net 66)
	)
	(arc
		(start 112.66535 76.175)
		(mid 112.683656 76.219194)
		(end 112.72785 76.2375)
		(width 0.125)
		(layer "In2.Cu")
		(net 66)
	)
	(arc
		(start 117.61535 75.78)
		(mid 117.646836 75.856014)
		(end 117.72285 75.8875)
		(width 0.125)
		(layer "In2.Cu")
		(net 66)
	)
	(arc
		(start 100.4966 74.858758)
		(mid 100.731713 74.956145)
		(end 100.8291 75.191258)
		(width 0.125)
		(layer "In2.Cu")
		(net 66)
	)
	(arc
		(start 82.910929 77.298901)
		(mid 82.813542 77.063788)
		(end 82.910929 76.828675)
		(width 0.125)
		(layer "In2.Cu")
		(net 66)
	)
	(arc
		(start 118.38285 76.862817)
		(mid 118.458864 76.831331)
		(end 118.49035 76.755317)
		(width 0.125)
		(layer "In2.Cu")
		(net 66)
	)
	(arc
		(start 83.150451 77.690451)
		(mid 83.181937 77.614437)
		(end 83.150451 77.538423)
		(width 0.125)
		(layer "In2.Cu")
		(net 66)
	)
	(arc
		(start 113.76535 75.78)
		(mid 113.796836 75.856014)
		(end 113.87285 75.8875)
		(width 0.125)
		(layer "In2.Cu")
		(net 66)
	)
	(arc
		(start 115.74035 75.694673)
		(mid 115.837737 75.45956)
		(end 116.07285 75.362173)
		(width 0.125)
		(layer "In2.Cu")
		(net 66)
	)
	(arc
		(start 113.43285 74.862184)
		(mid 113.667963 74.959571)
		(end 113.76535 75.194684)
		(width 0.125)
		(layer "In2.Cu")
		(net 66)
	)
	(arc
		(start 102.1466 75.8875)
		(mid 102.191959 75.868712)
		(end 102.210747 75.823353)
		(width 0.125)
		(layer "In2.Cu")
		(net 66)
	)
	(arc
		(start 110.7215 75.5248)
		(mid 110.929283 75.610867)
		(end 111.01535 75.81865)
		(width 0.125)
		(layer "In2.Cu")
		(net 66)
	)
	(arc
		(start 116.51535 75.78)
		(mid 116.546836 75.856014)
		(end 116.62285 75.8875)
		(width 0.125)
		(layer "In2.Cu")
		(net 66)
	)
	(arc
		(start 112.33285 75.058753)
		(mid 112.567963 75.15614)
		(end 112.66535 75.391253)
		(width 0.125)
		(layer "In2.Cu")
		(net 66)
	)
	(arc
		(start 100.8291 75.78)
		(mid 100.860586 75.856014)
		(end 100.9366 75.8875)
		(width 0.125)
		(layer "In2.Cu")
		(net 66)
	)
	(arc
		(start 83.766519 75.973066)
		(mid 84.001632 75.875679)
		(end 84.236745 75.973066)
		(width 0.125)
		(layer "In2.Cu")
		(net 66)
	)
	(arc
		(start 83.688736 76.521074)
		(mid 83.591349 76.285961)
		(end 83.688736 76.050848)
		(width 0.125)
		(layer "In2.Cu")
		(net 66)
	)
	(arc
		(start 110.1466 75.8875)
		(mid 110.195284 75.867334)
		(end 110.21545 75.81865)
		(width 0.125)
		(layer "In2.Cu")
		(net 66)
	)
	(arc
		(start 116.73285 75.8875)
		(mid 116.808864 75.856014)
		(end 116.84035 75.78)
		(width 0.125)
		(layer "In2.Cu")
		(net 66)
	)
	(arc
		(start 114.64035 75.78935)
		(mid 114.734998 75.560849)
		(end 114.963499 75.466201)
		(width 0.125)
		(layer "In2.Cu")
		(net 66)
	)
	(arc
		(start 82.988712 76.750893)
		(mid 83.223825 76.653506)
		(end 83.458938 76.750893)
		(width 0.125)
		(layer "In2.Cu")
		(net 66)
	)
	(arc
		(start 101.1541 75.541264)
		(mid 101.251487 75.306151)
		(end 101.4866 75.208764)
		(width 0.125)
		(layer "In2.Cu")
		(net 66)
	)
	(arc
		(start 112.99035 75.194684)
		(mid 113.087737 74.959571)
		(end 113.32285 74.862184)
		(width 0.125)
		(layer "In2.Cu")
		(net 66)
	)
	(arc
		(start 112.92785 76.2375)
		(mid 112.972044 76.219194)
		(end 112.99035 76.175)
		(width 0.125)
		(layer "In2.Cu")
		(net 66)
	)
	(arc
		(start 114.53285 76.862837)
		(mid 114.608864 76.831351)
		(end 114.64035 76.755337)
		(width 0.125)
		(layer "In2.Cu")
		(net 66)
	)
	(arc
		(start 115.642202 76.308797)
		(mid 115.711603 76.28005)
		(end 115.74035 76.210649)
		(width 0.125)
		(layer "In2.Cu")
		(net 66)
	)
	(arc
		(start 101.9291 75.78)
		(mid 101.960586 75.856014)
		(end 102.0366 75.8875)
		(width 0.125)
		(layer "In2.Cu")
		(net 66)
	)
	(arc
		(start 117.83285 75.8875)
		(mid 118.067963 75.984887)
		(end 118.16535 76.22)
		(width 0.125)
		(layer "In2.Cu")
		(net 66)
	)
	(arc
		(start 111.78285 75.8875)
		(mid 111.858864 75.856014)
		(end 111.89035 75.78)
		(width 0.125)
		(layer "In2.Cu")
		(net 66)
	)
	(arc
		(start 115.092201 75.466201)
		(mid 115.320702 75.560849)
		(end 115.41535 75.78935)
		(width 0.125)
		(layer "In2.Cu")
		(net 66)
	)
	(arc
		(start 111.01535 76.70874)
		(mid 111.046836 76.784754)
		(end 111.12285 76.81624)
		(width 0.125)
		(layer "In2.Cu")
		(net 66)
	)
	(arc
		(start 83.928268 76.912634)
		(mid 83.959754 76.83662)
		(end 83.928268 76.760606)
		(width 0.125)
		(layer "In2.Cu")
		(net 66)
	)
	(arc
		(start 116.84035 75.394663)
		(mid 116.937737 75.15955)
		(end 117.17285 75.062163)
		(width 0.125)
		(layer "In2.Cu")
		(net 66)
	)
	(arc
		(start 113.98285 75.8875)
		(mid 114.217963 75.984887)
		(end 114.31535 76.22)
		(width 0.125)
		(layer "In2.Cu")
		(net 66)
	)
	(arc
		(start 101.0466 75.8875)
		(mid 101.122614 75.856014)
		(end 101.1541 75.78)
		(width 0.125)
		(layer "In2.Cu")
		(net 66)
	)
	(arc
		(start 116.18285 75.362173)
		(mid 116.417963 75.45956)
		(end 116.51535 75.694673)
		(width 0.125)
		(layer "In2.Cu")
		(net 66)
	)
	(arc
		(start 102.6966 75.534206)
		(mid 102.901058 75.618895)
		(end 102.985747 75.823353)
		(width 0.125)
		(layer "In2.Cu")
		(net 66)
	)
	(arc
		(start 102.985747 75.823353)
		(mid 103.004535 75.868712)
		(end 103.049894 75.8875)
		(width 0.125)
		(layer "In2.Cu")
		(net 66)
	)
	(arc
		(start 100.0541 75.191258)
		(mid 100.151487 74.956145)
		(end 100.3866 74.858758)
		(width 0.125)
		(layer "In2.Cu")
		(net 66)
	)
	(arc
		(start 111.89035 75.391253)
		(mid 111.987737 75.15614)
		(end 112.22285 75.058753)
		(width 0.125)
		(layer "In2.Cu")
		(net 66)
	)
	(arc
		(start 99.9466 75.8875)
		(mid 100.022614 75.856014)
		(end 100.0541 75.78)
		(width 0.125)
		(layer "In2.Cu")
		(net 66)
	)
	(arc
		(start 118.49035 76.22)
		(mid 118.587737 75.984887)
		(end 118.82285 75.8875)
		(width 0.125)
		(layer "In2.Cu")
		(net 66)
	)
	(arc
		(start 111.34035 76.22)
		(mid 111.437737 75.984887)
		(end 111.67285 75.8875)
		(width 0.125)
		(layer "In2.Cu")
		(net 66)
	)
	(arc
		(start 110.21545 75.81865)
		(mid 110.301517 75.610867)
		(end 110.5093 75.5248)
		(width 0.125)
		(layer "In2.Cu")
		(net 66)
	)
	(arc
		(start 101.5966 75.208764)
		(mid 101.831713 75.306151)
		(end 101.9291 75.541264)
		(width 0.125)
		(layer "In2.Cu")
		(net 66)
	)
	(arc
		(start 118.16535 76.755317)
		(mid 118.196836 76.831331)
		(end 118.27285 76.862817)
		(width 0.125)
		(layer "In2.Cu")
		(net 66)
	)
	(arc
		(start 117.28285 75.062163)
		(mid 117.517963 75.15955)
		(end 117.61535 75.394663)
		(width 0.125)
		(layer "In2.Cu")
		(net 66)
	)
	(segment
		(start 88.9 83.1)
		(end 89.030532 82.969468)
		(width 0.1)
		(layer "F.Cu")
		(net 67)
	)
	(segment
		(start 88.6 84.75)
		(end 88.75 84.6)
		(width 0.1)
		(layer "F.Cu")
		(net 67)
	)
	(segment
		(start 78.8 81.3)
		(end 79.675 82.175)
		(width 0.1)
		(layer "F.Cu")
		(net 67)
	)
	(segment
		(start 83.925 82.175)
		(end 84.45 82.7)
		(width 0.1)
		(layer "F.Cu")
		(net 67)
	)
	(segment
		(start 85.8 84.65)
		(end 86.4 84.65)
		(width 0.1)
		(layer "F.Cu")
		(net 67)
	)
	(segment
		(start 108.117984 66.782016)
		(end 106.45 68.45)
		(width 0.1)
		(layer "F.Cu")
		(net 67)
	)
	(segment
		(start 108.117984 66.442158)
		(end 108.117984 66.782016)
		(width 0.1)
		(layer "F.Cu")
		(net 67)
	)
	(segment
		(start 106.45 68.45)
		(end 97.25 68.45)
		(width 0.1)
		(layer "F.Cu")
		(net 67)
	)
	(segment
		(start 86.4 84.65)
		(end 87.9 86.15)
		(width 0.1)
		(layer "F.Cu")
		(net 67)
	)
	(segment
		(start 84.45 82.7)
		(end 84.45 83.3)
		(width 0.1)
		(layer "F.Cu")
		(net 67)
	)
	(segment
		(start 88.75 84.6)
		(end 88.75 84.05)
		(width 0.1)
		(layer "F.Cu")
		(net 67)
	)
	(segment
		(start 79.675 82.175)
		(end 83.925 82.175)
		(width 0.1)
		(layer "F.Cu")
		(net 67)
	)
	(segment
		(start 97.25 68.45)
		(end 96 67.2)
		(width 0.1)
		(layer "F.Cu")
		(net 67)
	)
	(segment
		(start 94.5 67.2)
		(end 92.7 69)
		(width 0.1)
		(layer "F.Cu")
		(net 67)
	)
	(segment
		(start 88.35 86.15)
		(end 88.6 85.9)
		(width 0.1)
		(layer "F.Cu")
		(net 67)
	)
	(segment
		(start 79.55 69.75)
		(end 79.55 74.45)
		(width 0.1)
		(layer "F.Cu")
		(net 67)
	)
	(segment
		(start 92.7 69)
		(end 80.3 69)
		(width 0.1)
		(layer "F.Cu")
		(net 67)
	)
	(segment
		(start 88.9 83.9)
		(end 88.9 83.1)
		(width 0.1)
		(layer "F.Cu")
		(net 67)
	)
	(segment
		(start 88.75 84.05)
		(end 88.9 83.9)
		(width 0.1)
		(layer "F.Cu")
		(net 67)
	)
	(segment
		(start 79.55 74.45)
		(end 78.8 75.2)
		(width 0.1)
		(layer "F.Cu")
		(net 67)
	)
	(segment
		(start 88.6 85.9)
		(end 88.6 84.75)
		(width 0.1)
		(layer "F.Cu")
		(net 67)
	)
	(segment
		(start 89.030532 82.969468)
		(end 89.030532 82.65)
		(width 0.1)
		(layer "F.Cu")
		(net 67)
	)
	(segment
		(start 87.9 86.15)
		(end 88.35 86.15)
		(width 0.1)
		(layer "F.Cu")
		(net 67)
	)
	(segment
		(start 78.8 75.2)
		(end 78.8 81.3)
		(width 0.1)
		(layer "F.Cu")
		(net 67)
	)
	(segment
		(start 96 67.2)
		(end 94.5 67.2)
		(width 0.1)
		(layer "F.Cu")
		(net 67)
	)
	(segment
		(start 84.45 83.3)
		(end 85.8 84.65)
		(width 0.1)
		(layer "F.Cu")
		(net 67)
	)
	(segment
		(start 80.3 69)
		(end 79.55 69.75)
		(width 0.1)
		(layer "F.Cu")
		(net 67)
	)
	(via
		(at 108.117984 66.442158)
		(size 0.45)
		(drill 0.1)
		(layers "F.Cu" "B.Cu")
		(net 67)
	)
	(via
		(at 183.95 72.15)
		(size 0.45)
		(drill 0.1)
		(layers "F.Cu" "B.Cu")
		(net 67)
	)
	(via
		(at 192.6 71.6)
		(size 0.45)
		(drill 0.1)
		(layers "F.Cu" "B.Cu")
		(net 67)
	)
	(via
		(at 182.49625 58.65375)
		(size 0.45)
		(drill 0.1)
		(layers "F.Cu" "B.Cu")
		(net 67)
	)
	(segment
		(start 193.191795 71.6)
		(end 192.6 71.6)
		(width 0.1)
		(layer "B.Cu")
		(net 67)
	)
	(segment
		(start 198 65.4)
		(end 197.5 65.9)
		(width 0.1)
		(layer "B.Cu")
		(net 67)
	)
	(segment
		(start 197.5 65.9)
		(end 197.5 67.291795)
		(width 0.1)
		(layer "B.Cu")
		(net 67)
	)
	(segment
		(start 198.65 65.55)
		(end 198.5 65.4)
		(width 0.1)
		(layer "B.Cu")
		(net 67)
	)
	(segment
		(start 197.5 67.291795)
		(end 193.191795 71.6)
		(width 0.1)
		(layer "B.Cu")
		(net 67)
	)
	(segment
		(start 183.95 65.65)
		(end 183.95 72.15)
		(width 0.1)
		(layer "B.Cu")
		(net 67)
	)
	(segment
		(start 198.5 65.4)
		(end 198 65.4)
		(width 0.1)
		(layer "B.Cu")
		(net 67)
	)
	(segment
		(start 183.4 59.557501)
		(end 183.4 65.1)
		(width 0.1)
		(layer "B.Cu")
		(net 67)
	)
	(segment
		(start 182.49625 58.65375)
		(end 183.4 59.557501)
		(width 0.1)
		(layer "B.Cu")
		(net 67)
	)
	(segment
		(start 183.4 65.1)
		(end 183.95 65.65)
		(width 0.1)
		(layer "B.Cu")
		(net 67)
	)
	(segment
		(start 198.65 65.95)
		(end 198.65 65.55)
		(width 0.1)
		(layer "B.Cu")
		(net 67)
	)
	(segment
		(start 118.85 68.2)
		(end 119.85 69.2)
		(width 0.1)
		(layer "In2.Cu")
		(net 67)
	)
	(segment
		(start 108.117984 66.442158)
		(end 108.117984 67.157984)
		(width 0.1)
		(layer "In2.Cu")
		(net 67)
	)
	(segment
		(start 144 69)
		(end 146.45 71.45)
		(width 0.1)
		(layer "In2.Cu")
		(net 67)
	)
	(segment
		(start 139.8 70.4)
		(end 141.9 70.4)
		(width 0.1)
		(layer "In2.Cu")
		(net 67)
	)
	(segment
		(start 163.1 70.8)
		(end 163.1 68.4)
		(width 0.1)
		(layer "In2.Cu")
		(net 67)
	)
	(segment
		(start 176.8 57.25)
		(end 180.35 57.25)
		(width 0.1)
		(layer "In2.Cu")
		(net 67)
	)
	(segment
		(start 133.7 69)
		(end 139 69)
		(width 0.1)
		(layer "In2.Cu")
		(net 67)
	)
	(segment
		(start 133 69.7)
		(end 133.7 69)
		(width 0.1)
		(layer "In2.Cu")
		(net 67)
	)
	(segment
		(start 166.25 67.8)
		(end 176.8 57.25)
		(width 0.1)
		(layer "In2.Cu")
		(net 67)
	)
	(segment
		(start 162.45 71.45)
		(end 163.1 70.8)
		(width 0.1)
		(layer "In2.Cu")
		(net 67)
	)
	(segment
		(start 141.9 70.4)
		(end 143.3 69)
		(width 0.1)
		(layer "In2.Cu")
		(net 67)
	)
	(segment
		(start 182.242499 58.4)
		(end 182.49625 58.65375)
		(width 0.1)
		(layer "In2.Cu")
		(net 67)
	)
	(segment
		(start 143.3 69)
		(end 144 69)
		(width 0.1)
		(layer "In2.Cu")
		(net 67)
	)
	(segment
		(start 139.3 69.9)
		(end 139.8 70.4)
		(width 0.1)
		(layer "In2.Cu")
		(net 67)
	)
	(segment
		(start 180.35 57.25)
		(end 181.5 58.4)
		(width 0.1)
		(layer "In2.Cu")
		(net 67)
	)
	(segment
		(start 119.85 69.2)
		(end 123.5 69.2)
		(width 0.1)
		(layer "In2.Cu")
		(net 67)
	)
	(segment
		(start 108.117984 67.157984)
		(end 109.16 68.2)
		(width 0.1)
		(layer "In2.Cu")
		(net 67)
	)
	(segment
		(start 124 69.7)
		(end 133 69.7)
		(width 0.1)
		(layer "In2.Cu")
		(net 67)
	)
	(segment
		(start 139.3 69.3)
		(end 139.3 69.9)
		(width 0.1)
		(layer "In2.Cu")
		(net 67)
	)
	(segment
		(start 163.7 67.8)
		(end 166.25 67.8)
		(width 0.1)
		(layer "In2.Cu")
		(net 67)
	)
	(segment
		(start 163.1 68.4)
		(end 163.7 67.8)
		(width 0.1)
		(layer "In2.Cu")
		(net 67)
	)
	(segment
		(start 123.5 69.2)
		(end 124 69.7)
		(width 0.1)
		(layer "In2.Cu")
		(net 67)
	)
	(segment
		(start 139 69)
		(end 139.3 69.3)
		(width 0.1)
		(layer "In2.Cu")
		(net 67)
	)
	(segment
		(start 109.16 68.2)
		(end 118.85 68.2)
		(width 0.1)
		(layer "In2.Cu")
		(net 67)
	)
	(segment
		(start 146.45 71.45)
		(end 162.45 71.45)
		(width 0.1)
		(layer "In2.Cu")
		(net 67)
	)
	(segment
		(start 181.5 58.4)
		(end 182.242499 58.4)
		(width 0.1)
		(layer "In2.Cu")
		(net 67)
	)
	(segment
		(start 183.95 72.1)
		(end 187.05 69)
		(width 0.1)
		(layer "In5.Cu")
		(net 67)
	)
	(segment
		(start 183.95 72.15)
		(end 183.95 72.1)
		(width 0.1)
		(layer "In5.Cu")
		(net 67)
	)
	(segment
		(start 192.6 70.35)
		(end 192.6 71.6)
		(width 0.1)
		(layer "In5.Cu")
		(net 67)
	)
	(segment
		(start 187.05 69)
		(end 187.05 64.8)
		(width 0.1)
		(layer "In5.Cu")
		(net 67)
	)
	(segment
		(start 187.05 64.8)
		(end 187.6 64.25)
		(width 0.1)
		(layer "In5.Cu")
		(net 67)
	)
	(segment
		(start 188.7 64.25)
		(end 189.05 64.6)
		(width 0.1)
		(layer "In5.Cu")
		(net 67)
	)
	(segment
		(start 189.05 66.8)
		(end 192.6 70.35)
		(width 0.1)
		(layer "In5.Cu")
		(net 67)
	)
	(segment
		(start 187.6 64.25)
		(end 188.7 64.25)
		(width 0.1)
		(layer "In5.Cu")
		(net 67)
	)
	(segment
		(start 189.05 64.6)
		(end 189.05 66.8)
		(width 0.1)
		(layer "In5.Cu")
		(net 67)
	)
	(segment
		(start 126.505532 84.425)
		(end 126.230532 84.15)
		(width 0.17)
		(layer "F.Cu")
		(net 68)
	)
	(segment
		(start 126.39 84.91)
		(end 126.39 84.890532)
		(width 0.17)
		(layer "F.Cu")
		(net 68)
	)
	(segment
		(start 126.505532 84.775)
		(end 126.505532 84.425)
		(width 0.17)
		(layer "F.Cu")
		(net 68)
	)
	(segment
		(start 126.39 84.890532)
		(end 126.505532 84.775)
		(width 0.17)
		(layer "F.Cu")
		(net 68)
	)
	(via
		(at 126.39 84.91)
		(size 0.45)
		(drill 0.1)
		(layers "F.Cu" "B.Cu")
		(net 68)
	)
	(via
		(at 63.3 111.51)
		(size 0.45)
		(drill 0.1)
		(layers "F.Cu" "B.Cu")
		(net 68)
	)
	(segment
		(start 63.614999 111.385)
		(end 63.425 111.385)
		(width 0.17)
		(layer "B.Cu")
		(net 68)
	)
	(segment
		(start 63.689999 111.46)
		(end 63.614999 111.385)
		(width 0.17)
		(layer "B.Cu")
		(net 68)
	)
	(segment
		(start 63.425 111.385)
		(end 63.3 111.51)
		(width 0.17)
		(layer "B.Cu")
		(net 68)
	)
	(segment
		(start 64.59 111.46)
		(end 63.689999 111.46)
		(width 0.17)
		(layer "B.Cu")
		(net 68)
	)
	(segment
		(start 105.882542 85.221644)
		(end 106.004542 85.221644)
		(width 0.125)
		(layer "In2.Cu")
		(net 68)
	)
	(segment
		(start 111.203292 85.579539)
		(end 111.203292 86.475)
		(width 0.125)
		(layer "In2.Cu")
		(net 68)
	)
	(segment
		(start 106.361042 85.578144)
		(end 106.361042 86.501559)
		(width 0.125)
		(layer "In2.Cu")
		(net 68)
	)
	(segment
		(start 65.3334 110.873903)
		(end 65.4034 110.873903)
		(width 0.125)
		(layer "In2.Cu")
		(net 68)
	)
	(segment
		(start 117.975792 86.1875)
		(end 118.204542 86.1875)
		(width 0.125)
		(layer "In2.Cu")
		(net 68)
	)
	(segment
		(start 116.468292 86.475)
		(end 116.468292 86.125)
		(width 0.125)
		(layer "In2.Cu")
		(net 68)
	)
	(segment
		(start 110.368292 86.475)
		(end 110.368292 85.579539)
		(width 0.125)
		(layer "In2.Cu")
		(net 68)
	)
	(segment
		(start 108.322542 86.1875)
		(end 108.444542 86.1875)
		(width 0.125)
		(layer "In2.Cu")
		(net 68)
	)
	(segment
		(start 64.668773 111.572131)
		(end 64.71827 111.522631)
		(width 0.125)
		(layer "In2.Cu")
		(net 68)
	)
	(segment
		(start 65.6834 111.1875)
		(end 70.7534 111.1875)
		(width 0.125)
		(layer "In2.Cu")
		(net 68)
	)
	(segment
		(start 119.874792 86.1875)
		(end 124.5534 86.1875)
		(width 0.125)
		(layer "In2.Cu")
		(net 68)
	)
	(segment
		(start 94.7466 84.7875)
		(end 96.1466 86.1875)
		(width 0.125)
		(layer "In2.Cu")
		(net 68)
	)
	(segment
		(start 114.028292 86.475)
		(end 114.028292 85.582936)
		(width 0.125)
		(layer "In2.Cu")
		(net 68)
	)
	(segment
		(start 107.581042 85.578144)
		(end 107.581042 86.721859)
		(width 0.125)
		(layer "In2.Cu")
		(net 68)
	)
	(segment
		(start 126.174833 85.3875)
		(end 126.380532 85.181801)
		(width 0.125)
		(layer "In2.Cu")
		(net 68)
	)
	(segment
		(start 116.114542 86.5375)
		(end 116.405792 86.5375)
		(width 0.125)
		(layer "In2.Cu")
		(net 68)
	)
	(segment
		(start 62.5125 111.5466)
		(end 62.5125 112.0534)
		(width 0.125)
		(layer "In2.Cu")
		(net 68)
	)
	(segment
		(start 71.2875 88.7534)
		(end 71.7534 88.2875)
		(width 0.125)
		(layer "In2.Cu")
		(net 68)
	)
	(segment
		(start 114.384792 85.226436)
		(end 114.506792 85.226436)
		(width 0.125)
		(layer "In2.Cu")
		(net 68)
	)
	(segment
		(start 64.71827 111.522631)
		(end 65.0534 111.1875)
		(width 0.125)
		(layer "In2.Cu")
		(net 68)
	)
	(segment
		(start 117.365792 86.5375)
		(end 117.625792 86.5375)
		(width 0.125)
		(layer "In2.Cu")
		(net 68)
	)
	(segment
		(start 118.908292 86.475)
		(end 118.908292 85.660976)
		(width 0.125)
		(layer "In2.Cu")
		(net 68)
	)
	(segment
		(start 110.014542 86.5375)
		(end 110.305792 86.5375)
		(width 0.125)
		(layer "In2.Cu")
		(net 68)
	)
	(segment
		(start 126.380532 85.181801)
		(end 126.380532 84.919468)
		(width 0.125)
		(layer "In2.Cu")
		(net 68)
	)
	(segment
		(start 96.1466 86.1875)
		(end 105.394542 86.1875)
		(width 0.125)
		(layer "In2.Cu")
		(net 68)
	)
	(segment
		(start 105.526042 86.056)
		(end 105.526042 85.578144)
		(width 0.125)
		(layer "In2.Cu")
		(net 68)
	)
	(segment
		(start 107.966042 86.721859)
		(end 107.966042 86.544)
		(width 0.125)
		(layer "In2.Cu")
		(net 68)
	)
	(segment
		(start 64.223295 111.819616)
		(end 64.022744 111.619065)
		(width 0.125)
		(layer "In2.Cu")
		(net 68)
	)
	(segment
		(start 70.7534 111.1875)
		(end 71.2875 110.6534)
		(width 0.125)
		(layer "In2.Cu")
		(net 68)
	)
	(segment
		(start 114.863292 85.582936)
		(end 114.863292 86.475)
		(width 0.125)
		(layer "In2.Cu")
		(net 68)
	)
	(segment
		(start 117.303292 86.125)
		(end 117.303292 86.475)
		(width 0.125)
		(layer "In2.Cu")
		(net 68)
	)
	(segment
		(start 126.380532 84.919468)
		(end 126.39 84.91)
		(width 0.125)
		(layer "In2.Cu")
		(net 68)
	)
	(segment
		(start 113.674542 86.5375)
		(end 113.965792 86.5375)
		(width 0.125)
		(layer "In2.Cu")
		(net 68)
	)
	(segment
		(start 64.022743 111.421077)
		(end 64.072243 111.371578)
		(width 0.125)
		(layer "In2.Cu")
		(net 68)
	)
	(segment
		(start 62.736599 111.322501)
		(end 62.5125 111.5466)
		(width 0.125)
		(layer "In2.Cu")
		(net 68)
	)
	(segment
		(start 125.3534 85.3875)
		(end 126.174833 85.3875)
		(width 0.125)
		(layer "In2.Cu")
		(net 68)
	)
	(segment
		(start 71.7534 88.2875)
		(end 89.1534 88.2875)
		(width 0.125)
		(layer "In2.Cu")
		(net 68)
	)
	(segment
		(start 106.746042 86.501559)
		(end 106.746042 85.578144)
		(width 0.125)
		(layer "In2.Cu")
		(net 68)
	)
	(segment
		(start 112.454542 86.5375)
		(end 112.714542 86.5375)
		(width 0.125)
		(layer "In2.Cu")
		(net 68)
	)
	(segment
		(start 65.1934 111.0475)
		(end 65.1934 111.013903)
		(width 0.125)
		(layer "In2.Cu")
		(net 68)
	)
	(segment
		(start 63.9534 112.2875)
		(end 64.223294 112.017606)
		(width 0.125)
		(layer "In2.Cu")
		(net 68)
	)
	(segment
		(start 107.102542 85.221644)
		(end 107.224542 85.221644)
		(width 0.125)
		(layer "In2.Cu")
		(net 68)
	)
	(segment
		(start 110.724792 85.223039)
		(end 110.846792 85.223039)
		(width 0.125)
		(layer "In2.Cu")
		(net 68)
	)
	(segment
		(start 71.2875 110.6534)
		(end 71.2875 88.7534)
		(width 0.125)
		(layer "In2.Cu")
		(net 68)
	)
	(segment
		(start 63.3 111.51)
		(end 63.112501 111.322501)
		(width 0.125)
		(layer "In2.Cu")
		(net 68)
	)
	(segment
		(start 113.064542 86.1875)
		(end 113.324542 86.1875)
		(width 0.125)
		(layer "In2.Cu")
		(net 68)
	)
	(segment
		(start 116.755792 85.8375)
		(end 117.015792 85.8375)
		(width 0.125)
		(layer "In2.Cu")
		(net 68)
	)
	(segment
		(start 62.7466 112.2875)
		(end 63.9534 112.2875)
		(width 0.125)
		(layer "In2.Cu")
		(net 68)
	)
	(segment
		(start 111.875792 86.1875)
		(end 112.104542 86.1875)
		(width 0.125)
		(layer "In2.Cu")
		(net 68)
	)
	(segment
		(start 114.925792 86.5375)
		(end 115.185792 86.5375)
		(width 0.125)
		(layer "In2.Cu")
		(net 68)
	)
	(segment
		(start 119.743292 85.660976)
		(end 119.743292 86.056)
		(width 0.125)
		(layer "In2.Cu")
		(net 68)
	)
	(segment
		(start 115.535792 86.1875)
		(end 115.764542 86.1875)
		(width 0.125)
		(layer "In2.Cu")
		(net 68)
	)
	(segment
		(start 64.270233 111.371578)
		(end 64.470785 111.57213)
		(width 0.125)
		(layer "In2.Cu")
		(net 68)
	)
	(segment
		(start 111.265792 86.5375)
		(end 111.525792 86.5375)
		(width 0.125)
		(layer "In2.Cu")
		(net 68)
	)
	(segment
		(start 108.794542 86.5375)
		(end 109.054542 86.5375)
		(width 0.125)
		(layer "In2.Cu")
		(net 68)
	)
	(segment
		(start 63.112501 111.322501)
		(end 62.736599 111.322501)
		(width 0.125)
		(layer "In2.Cu")
		(net 68)
	)
	(segment
		(start 118.554542 86.5375)
		(end 118.845792 86.5375)
		(width 0.125)
		(layer "In2.Cu")
		(net 68)
	)
	(segment
		(start 107.712542 86.853359)
		(end 107.834542 86.853359)
		(width 0.125)
		(layer "In2.Cu")
		(net 68)
	)
	(segment
		(start 92.6534 84.7875)
		(end 94.7466 84.7875)
		(width 0.125)
		(layer "In2.Cu")
		(net 68)
	)
	(segment
		(start 65.5434 111.013903)
		(end 65.5434 111.0475)
		(width 0.125)
		(layer "In2.Cu")
		(net 68)
	)
	(segment
		(start 109.404542 86.1875)
		(end 109.664542 86.1875)
		(width 0.125)
		(layer "In2.Cu")
		(net 68)
	)
	(segment
		(start 119.264792 85.304476)
		(end 119.386792 85.304476)
		(width 0.125)
		(layer "In2.Cu")
		(net 68)
	)
	(segment
		(start 106.450101 86.590618)
		(end 106.656983 86.590618)
		(width 0.125)
		(layer "In2.Cu")
		(net 68)
	)
	(segment
		(start 89.1534 88.2875)
		(end 92.6534 84.7875)
		(width 0.125)
		(layer "In2.Cu")
		(net 68)
	)
	(segment
		(start 62.5125 112.0534)
		(end 62.7466 112.2875)
		(width 0.125)
		(layer "In2.Cu")
		(net 68)
	)
	(segment
		(start 124.5534 86.1875)
		(end 125.3534 85.3875)
		(width 0.125)
		(layer "In2.Cu")
		(net 68)
	)
	(arc
		(start 107.224542 85.221644)
		(mid 107.476626 85.32606)
		(end 107.581042 85.578144)
		(width 0.125)
		(layer "In2.Cu")
		(net 68)
	)
	(arc
		(start 107.834542 86.853359)
		(mid 107.927527 86.814844)
		(end 107.966042 86.721859)
		(width 0.125)
		(layer "In2.Cu")
		(net 68)
	)
	(arc
		(start 65.4034 110.873903)
		(mid 65.502395 110.914908)
		(end 65.5434 111.013903)
		(width 0.125)
		(layer "In2.Cu")
		(net 68)
	)
	(arc
		(start 116.405792 86.5375)
		(mid 116.449986 86.519194)
		(end 116.468292 86.475)
		(width 0.125)
		(layer "In2.Cu")
		(net 68)
	)
	(arc
		(start 109.054542 86.5375)
		(mid 109.098736 86.519194)
		(end 109.117042 86.475)
		(width 0.125)
		(layer "In2.Cu")
		(net 68)
	)
	(arc
		(start 114.863292 86.475)
		(mid 114.881598 86.519194)
		(end 114.925792 86.5375)
		(width 0.125)
		(layer "In2.Cu")
		(net 68)
	)
	(arc
		(start 112.104542 86.1875)
		(mid 112.307835 86.271707)
		(end 112.392042 86.475)
		(width 0.125)
		(layer "In2.Cu")
		(net 68)
	)
	(arc
		(start 109.117042 86.475)
		(mid 109.201249 86.271707)
		(end 109.404542 86.1875)
		(width 0.125)
		(layer "In2.Cu")
		(net 68)
	)
	(arc
		(start 107.581042 86.721859)
		(mid 107.619557 86.814844)
		(end 107.712542 86.853359)
		(width 0.125)
		(layer "In2.Cu")
		(net 68)
	)
	(arc
		(start 119.386792 85.304476)
		(mid 119.638876 85.408892)
		(end 119.743292 85.660976)
		(width 0.125)
		(layer "In2.Cu")
		(net 68)
	)
	(arc
		(start 64.022744 111.619065)
		(mid 63.981739 111.520071)
		(end 64.022743 111.421077)
		(width 0.125)
		(layer "In2.Cu")
		(net 68)
	)
	(arc
		(start 108.732042 86.475)
		(mid 108.750348 86.519194)
		(end 108.794542 86.5375)
		(width 0.125)
		(layer "In2.Cu")
		(net 68)
	)
	(arc
		(start 111.203292 86.475)
		(mid 111.221598 86.519194)
		(end 111.265792 86.5375)
		(width 0.125)
		(layer "In2.Cu")
		(net 68)
	)
	(arc
		(start 114.506792 85.226436)
		(mid 114.758876 85.330852)
		(end 114.863292 85.582936)
		(width 0.125)
		(layer "In2.Cu")
		(net 68)
	)
	(arc
		(start 115.764542 86.1875)
		(mid 115.967835 86.271707)
		(end 116.052042 86.475)
		(width 0.125)
		(layer "In2.Cu")
		(net 68)
	)
	(arc
		(start 110.305792 86.5375)
		(mid 110.349986 86.519194)
		(end 110.368292 86.475)
		(width 0.125)
		(layer "In2.Cu")
		(net 68)
	)
	(arc
		(start 112.714542 86.5375)
		(mid 112.758736 86.519194)
		(end 112.777042 86.475)
		(width 0.125)
		(layer "In2.Cu")
		(net 68)
	)
	(arc
		(start 110.846792 85.223039)
		(mid 111.098876 85.327455)
		(end 111.203292 85.579539)
		(width 0.125)
		(layer "In2.Cu")
		(net 68)
	)
	(arc
		(start 118.492042 86.475)
		(mid 118.510348 86.519194)
		(end 118.554542 86.5375)
		(width 0.125)
		(layer "In2.Cu")
		(net 68)
	)
	(arc
		(start 113.965792 86.5375)
		(mid 114.009986 86.519194)
		(end 114.028292 86.475)
		(width 0.125)
		(layer "In2.Cu")
		(net 68)
	)
	(arc
		(start 64.223294 112.017606)
		(mid 64.2643 111.918611)
		(end 64.223295 111.819616)
		(width 0.125)
		(layer "In2.Cu")
		(net 68)
	)
	(arc
		(start 118.908292 85.660976)
		(mid 119.012708 85.408892)
		(end 119.264792 85.304476)
		(width 0.125)
		(layer "In2.Cu")
		(net 68)
	)
	(arc
		(start 112.777042 86.475)
		(mid 112.861249 86.271707)
		(end 113.064542 86.1875)
		(width 0.125)
		(layer "In2.Cu")
		(net 68)
	)
	(arc
		(start 106.656983 86.590618)
		(mid 106.719957 86.564533)
		(end 106.746042 86.501559)
		(width 0.125)
		(layer "In2.Cu")
		(net 68)
	)
	(arc
		(start 115.185792 86.5375)
		(mid 115.229986 86.519194)
		(end 115.248292 86.475)
		(width 0.125)
		(layer "In2.Cu")
		(net 68)
	)
	(arc
		(start 107.966042 86.544)
		(mid 108.070458 86.291916)
		(end 108.322542 86.1875)
		(width 0.125)
		(layer "In2.Cu")
		(net 68)
	)
	(arc
		(start 115.248292 86.475)
		(mid 115.332499 86.271707)
		(end 115.535792 86.1875)
		(width 0.125)
		(layer "In2.Cu")
		(net 68)
	)
	(arc
		(start 112.392042 86.475)
		(mid 112.410348 86.519194)
		(end 112.454542 86.5375)
		(width 0.125)
		(layer "In2.Cu")
		(net 68)
	)
	(arc
		(start 117.625792 86.5375)
		(mid 117.669986 86.519194)
		(end 117.688292 86.475)
		(width 0.125)
		(layer "In2.Cu")
		(net 68)
	)
	(arc
		(start 111.525792 86.5375)
		(mid 111.569986 86.519194)
		(end 111.588292 86.475)
		(width 0.125)
		(layer "In2.Cu")
		(net 68)
	)
	(arc
		(start 105.526042 85.578144)
		(mid 105.630458 85.32606)
		(end 105.882542 85.221644)
		(width 0.125)
		(layer "In2.Cu")
		(net 68)
	)
	(arc
		(start 116.468292 86.125)
		(mid 116.552499 85.921707)
		(end 116.755792 85.8375)
		(width 0.125)
		(layer "In2.Cu")
		(net 68)
	)
	(arc
		(start 110.368292 85.579539)
		(mid 110.472708 85.327455)
		(end 110.724792 85.223039)
		(width 0.125)
		(layer "In2.Cu")
		(net 68)
	)
	(arc
		(start 109.952042 86.475)
		(mid 109.970348 86.519194)
		(end 110.014542 86.5375)
		(width 0.125)
		(layer "In2.Cu")
		(net 68)
	)
	(arc
		(start 116.052042 86.475)
		(mid 116.070348 86.519194)
		(end 116.114542 86.5375)
		(width 0.125)
		(layer "In2.Cu")
		(net 68)
	)
	(arc
		(start 106.361042 86.501559)
		(mid 106.387127 86.564533)
		(end 106.450101 86.590618)
		(width 0.125)
		(layer "In2.Cu")
		(net 68)
	)
	(arc
		(start 65.1934 111.013903)
		(mid 65.234405 110.914908)
		(end 65.3334 110.873903)
		(width 0.125)
		(layer "In2.Cu")
		(net 68)
	)
	(arc
		(start 108.444542 86.1875)
		(mid 108.647835 86.271707)
		(end 108.732042 86.475)
		(width 0.125)
		(layer "In2.Cu")
		(net 68)
	)
	(arc
		(start 118.845792 86.5375)
		(mid 118.889986 86.519194)
		(end 118.908292 86.475)
		(width 0.125)
		(layer "In2.Cu")
		(net 68)
	)
	(arc
		(start 119.743292 86.056)
		(mid 119.781807 86.148985)
		(end 119.874792 86.1875)
		(width 0.125)
		(layer "In2.Cu")
		(net 68)
	)
	(arc
		(start 65.5434 111.0475)
		(mid 65.584405 111.146495)
		(end 65.6834 111.1875)
		(width 0.125)
		(layer "In2.Cu")
		(net 68)
	)
	(arc
		(start 106.746042 85.578144)
		(mid 106.850458 85.32606)
		(end 107.102542 85.221644)
		(width 0.125)
		(layer "In2.Cu")
		(net 68)
	)
	(arc
		(start 65.0534 111.1875)
		(mid 65.152395 111.146495)
		(end 65.1934 111.0475)
		(width 0.125)
		(layer "In2.Cu")
		(net 68)
	)
	(arc
		(start 64.072243 111.371578)
		(mid 64.171238 111.330573)
		(end 64.270233 111.371578)
		(width 0.125)
		(layer "In2.Cu")
		(net 68)
	)
	(arc
		(start 109.664542 86.1875)
		(mid 109.867835 86.271707)
		(end 109.952042 86.475)
		(width 0.125)
		(layer "In2.Cu")
		(net 68)
	)
	(arc
		(start 106.004542 85.221644)
		(mid 106.256626 85.32606)
		(end 106.361042 85.578144)
		(width 0.125)
		(layer "In2.Cu")
		(net 68)
	)
	(arc
		(start 117.688292 86.475)
		(mid 117.772499 86.271707)
		(end 117.975792 86.1875)
		(width 0.125)
		(layer "In2.Cu")
		(net 68)
	)
	(arc
		(start 113.324542 86.1875)
		(mid 113.527835 86.271707)
		(end 113.612042 86.475)
		(width 0.125)
		(layer "In2.Cu")
		(net 68)
	)
	(arc
		(start 113.612042 86.475)
		(mid 113.630348 86.519194)
		(end 113.674542 86.5375)
		(width 0.125)
		(layer "In2.Cu")
		(net 68)
	)
	(arc
		(start 118.204542 86.1875)
		(mid 118.407835 86.271707)
		(end 118.492042 86.475)
		(width 0.125)
		(layer "In2.Cu")
		(net 68)
	)
	(arc
		(start 111.588292 86.475)
		(mid 111.672499 86.271707)
		(end 111.875792 86.1875)
		(width 0.125)
		(layer "In2.Cu")
		(net 68)
	)
	(arc
		(start 105.394542 86.1875)
		(mid 105.487527 86.148985)
		(end 105.526042 86.056)
		(width 0.125)
		(layer "In2.Cu")
		(net 68)
	)
	(arc
		(start 114.028292 85.582936)
		(mid 114.132708 85.330852)
		(end 114.384792 85.226436)
		(width 0.125)
		(layer "In2.Cu")
		(net 68)
	)
	(arc
		(start 64.470785 111.57213)
		(mid 64.569778 111.613136)
		(end 64.668773 111.572131)
		(width 0.125)
		(layer "In2.Cu")
		(net 68)
	)
	(arc
		(start 117.303292 86.475)
		(mid 117.321598 86.519194)
		(end 117.365792 86.5375)
		(width 0.125)
		(layer "In2.Cu")
		(net 68)
	)
	(arc
		(start 117.015792 85.8375)
		(mid 117.219085 85.921707)
		(end 117.303292 86.125)
		(width 0.125)
		(layer "In2.Cu")
		(net 68)
	)
	(segment
		(start 127.825 110.4)
		(end 127.8 110.425)
		(width 0.1)
		(layer "F.Cu")
		(net 69)
	)
	(segment
		(start 130.2 110.8)
		(end 129.8 110.4)
		(width 0.1)
		(layer "F.Cu")
		(net 69)
	)
	(segment
		(start 136 87.2)
		(end 137.8 87.2)
		(width 0.1)
		(layer "F.Cu")
		(net 69)
	)
	(segment
		(start 131.1 110.825)
		(end 131.075 110.8)
		(width 0.1)
		(layer "F.Cu")
		(net 69)
	)
	(segment
		(start 138.630532 86.369468)
		(end 138.630532 85.65)
		(width 0.1)
		(layer "F.Cu")
		(net 69)
	)
	(segment
		(start 129.8 110.4)
		(end 127.825 110.4)
		(width 0.1)
		(layer "F.Cu")
		(net 69)
	)
	(segment
		(start 137.8 87.2)
		(end 138.630532 86.369468)
		(width 0.1)
		(layer "F.Cu")
		(net 69)
	)
	(segment
		(start 131.075 110.8)
		(end 130.2 110.8)
		(width 0.1)
		(layer "F.Cu")
		(net 69)
	)
	(via
		(at 131.1 110.825)
		(size 0.45)
		(drill 0.1)
		(layers "F.Cu" "B.Cu")
		(net 69)
	)
	(via
		(at 127.8 110.425)
		(size 0.45)
		(drill 0.1)
		(layers "F.Cu" "B.Cu")
		(net 69)
	)
	(via
		(at 136 87.2)
		(size 0.45)
		(drill 0.1)
		(layers "F.Cu" "B.Cu")
		(net 69)
	)
	(via
		(at 77.8 104.9)
		(size 0.45)
		(drill 0.1)
		(layers "F.Cu" "B.Cu")
		(net 69)
	)
	(segment
		(start 75.775532 104.345)
		(end 76.330532 104.9)
		(width 0.1)
		(layer "B.Cu")
		(net 69)
	)
	(segment
		(start 76.330532 104.9)
		(end 77.8 104.9)
		(width 0.1)
		(layer "B.Cu")
		(net 69)
	)
	(segment
		(start 104.075 108.125)
		(end 100.8 111.4)
		(width 0.1)
		(layer "In5.Cu")
		(net 69)
	)
	(segment
		(start 105.2 107.4)
		(end 104.475 108.125)
		(width 0.1)
		(layer "In5.Cu")
		(net 69)
	)
	(segment
		(start 80.25 117)
		(end 80.25 108.15)
		(width 0.1)
		(layer "In5.Cu")
		(net 69)
	)
	(segment
		(start 100.8 112.35)
		(end 95.075 118.075)
		(width 0.1)
		(layer "In5.Cu")
		(net 69)
	)
	(segment
		(start 86.975 117.925)
		(end 86.2 118.7)
		(width 0.1)
		(layer "In5.Cu")
		(net 69)
	)
	(segment
		(start 89.775 118.075)
		(end 89.625 117.925)
		(width 0.1)
		(layer "In5.Cu")
		(net 69)
	)
	(segment
		(start 80.25 108.15)
		(end 79.6 107.5)
		(width 0.1)
		(layer "In5.Cu")
		(net 69)
	)
	(segment
		(start 127 110)
		(end 114.062742 110)
		(width 0.1)
		(layer "In5.Cu")
		(net 69)
	)
	(segment
		(start 112.8 108.2)
		(end 111.6 108.2)
		(width 0.1)
		(layer "In5.Cu")
		(net 69)
	)
	(segment
		(start 79.1 107.5)
		(end 78.75 107.15)
		(width 0.1)
		(layer "In5.Cu")
		(net 69)
	)
	(segment
		(start 89.625 117.925)
		(end 86.975 117.925)
		(width 0.1)
		(layer "In5.Cu")
		(net 69)
	)
	(segment
		(start 110.8 107.4)
		(end 105.2 107.4)
		(width 0.1)
		(layer "In5.Cu")
		(net 69)
	)
	(segment
		(start 95.075 118.075)
		(end 89.775 118.075)
		(width 0.1)
		(layer "In5.Cu")
		(net 69)
	)
	(segment
		(start 130.625 110.825)
		(end 131.1 110.825)
		(width 0.1)
		(layer "In5.Cu")
		(net 69)
	)
	(segment
		(start 79.6 107.5)
		(end 79.1 107.5)
		(width 0.1)
		(layer "In5.Cu")
		(net 69)
	)
	(segment
		(start 81.95 118.7)
		(end 80.25 117)
		(width 0.1)
		(layer "In5.Cu")
		(net 69)
	)
	(segment
		(start 113.4 108.8)
		(end 112.8 108.2)
		(width 0.1)
		(layer "In5.Cu")
		(net 69)
	)
	(segment
		(start 111.6 108.2)
		(end 110.8 107.4)
		(width 0.1)
		(layer "In5.Cu")
		(net 69)
	)
	(segment
		(start 136 87.2)
		(end 136 87.6)
		(width 0.1)
		(layer "In5.Cu")
		(net 69)
	)
	(segment
		(start 78.75 106.65)
		(end 77.8 105.7)
		(width 0.1)
		(layer "In5.Cu")
		(net 69)
	)
	(segment
		(start 130.8 95.8)
		(end 130.35 96.25)
		(width 0.1)
		(layer "In5.Cu")
		(net 69)
	)
	(segment
		(start 130.8 92.8)
		(end 130.8 95.8)
		(width 0.1)
		(layer "In5.Cu")
		(net 69)
	)
	(segment
		(start 130.35 96.25)
		(end 130.35 110.55)
		(width 0.1)
		(layer "In5.Cu")
		(net 69)
	)
	(segment
		(start 78.75 107.15)
		(end 78.75 106.65)
		(width 0.1)
		(layer "In5.Cu")
		(net 69)
	)
	(segment
		(start 130.35 110.55)
		(end 130.625 110.825)
		(width 0.1)
		(layer "In5.Cu")
		(net 69)
	)
	(segment
		(start 104.475 108.125)
		(end 104.075 108.125)
		(width 0.1)
		(layer "In5.Cu")
		(net 69)
	)
	(segment
		(start 114.062742 110)
		(end 113.4 109.337258)
		(width 0.1)
		(layer "In5.Cu")
		(net 69)
	)
	(segment
		(start 86.2 118.7)
		(end 81.95 118.7)
		(width 0.1)
		(layer "In5.Cu")
		(net 69)
	)
	(segment
		(start 100.8 111.4)
		(end 100.8 112.35)
		(width 0.1)
		(layer "In5.Cu")
		(net 69)
	)
	(segment
		(start 77.8 105.7)
		(end 77.8 104.9)
		(width 0.1)
		(layer "In5.Cu")
		(net 69)
	)
	(segment
		(start 136 87.6)
		(end 130.8 92.8)
		(width 0.1)
		(layer "In5.Cu")
		(net 69)
	)
	(segment
		(start 113.4 109.337258)
		(end 113.4 108.8)
		(width 0.1)
		(layer "In5.Cu")
		(net 69)
	)
	(segment
		(start 127.775 110.45)
		(end 127.45 110.45)
		(width 0.1)
		(layer "In5.Cu")
		(net 69)
	)
	(segment
		(start 127.8 110.425)
		(end 127.775 110.45)
		(width 0.1)
		(layer "In5.Cu")
		(net 69)
	)
	(segment
		(start 127.45 110.45)
		(end 127 110)
		(width 0.1)
		(layer "In5.Cu")
		(net 69)
	)
	(segment
		(start 129.555532 75.508044)
		(end 129.847488 75.8)
		(width 0.17)
		(layer "F.Cu")
		(net 70)
	)
	(segment
		(start 129.847488 75.8)
		(end 130.85 75.8)
		(width 0.17)
		(layer "F.Cu")
		(net 70)
	)
	(segment
		(start 130.85 75.8)
		(end 130.975 75.675)
		(width 0.17)
		(layer "F.Cu")
		(net 70)
	)
	(segment
		(start 129.830532 75.15)
		(end 129.555532 75.425)
		(width 0.17)
		(layer "F.Cu")
		(net 70)
	)
	(segment
		(start 129.555532 75.425)
		(end 129.555532 75.508044)
		(width 0.17)
		(layer "F.Cu")
		(net 70)
	)
	(via
		(at 205.7 61.2)
		(size 0.45)
		(drill 0.1)
		(layers "F.Cu" "B.Cu")
		(net 70)
	)
	(via
		(at 130.975 75.675)
		(size 0.45)
		(drill 0.1)
		(layers "F.Cu" "B.Cu")
		(net 70)
	)
	(segment
		(start 205.083 59.365001)
		(end 205.083 61.035512)
		(width 0.17)
		(layer "B.Cu")
		(net 70)
	)
	(segment
		(start 205.372488 61.325)
		(end 205.575 61.325)
		(width 0.17)
		(layer "B.Cu")
		(net 70)
	)
	(segment
		(start 205.158 58.39)
		(end 205.158 59.290001)
		(width 0.17)
		(layer "B.Cu")
		(net 70)
	)
	(segment
		(start 205.575 61.325)
		(end 205.7 61.2)
		(width 0.17)
		(layer "B.Cu")
		(net 70)
	)
	(segment
		(start 205.158 59.290001)
		(end 205.083 59.365001)
		(width 0.17)
		(layer "B.Cu")
		(net 70)
	)
	(segment
		(start 205.083 61.035512)
		(end 205.372488 61.325)
		(width 0.17)
		(layer "B.Cu")
		(net 70)
	)
	(segment
		(start 149.262567 76.087501)
		(end 149.262567 76.60503)
		(width 0.125)
		(layer "In2.Cu")
		(net 70)
	)
	(segment
		(start 132.223981 75.602519)
		(end 132.223981 75.722499)
		(width 0.125)
		(layer "In2.Cu")
		(net 70)
	)
	(segment
		(start 149.587565 76.60503)
		(end 149.587565 76.087501)
		(width 0.125)
		(layer "In2.Cu")
		(net 70)
	)
	(segment
		(start 151.462567 76.195)
		(end 151.462567 76.60503)
		(width 0.125)
		(layer "In2.Cu")
		(net 70)
	)
	(segment
		(start 204.8316 61.609303)
		(end 204.874025 61.566876)
		(width 0.125)
		(layer "In2.Cu")
		(net 70)
	)
	(segment
		(start 148.130066 75.862499)
		(end 148.380066 75.862499)
		(width 0.125)
		(layer "In2.Cu")
		(net 70)
	)
	(segment
		(start 164.711333 75.862499)
		(end 166.156014 74.417818)
		(width 0.125)
		(layer "In2.Cu")
		(net 70)
	)
	(segment
		(start 150.687565 76.087501)
		(end 150.687565 75.862499)
		(width 0.125)
		(layer "In2.Cu")
		(net 70)
	)
	(segment
		(start 132.363981 75.862499)
		(end 148.130066 75.862499)
		(width 0.125)
		(layer "In2.Cu")
		(net 70)
	)
	(segment
		(start 149.262567 75.194963)
		(end 149.262567 75.755)
		(width 0.125)
		(layer "In2.Cu")
		(net 70)
	)
	(segment
		(start 151.020066 74.862462)
		(end 151.130066 74.862462)
		(width 0.125)
		(layer "In2.Cu")
		(net 70)
	)
	(segment
		(start 132.013981 75.462519)
		(end 132.083981 75.462519)
		(width 0.125)
		(layer "In2.Cu")
		(net 70)
	)
	(segment
		(start 150.362567 75.862499)
		(end 150.362567 76.087501)
		(width 0.125)
		(layer "In2.Cu")
		(net 70)
	)
	(segment
		(start 204.44976 61.821435)
		(end 204.405142 61.776817)
		(width 0.125)
		(layer "In2.Cu")
		(net 70)
	)
	(segment
		(start 151.570066 76.712529)
		(end 151.680066 76.712529)
		(width 0.125)
		(layer "In2.Cu")
		(net 70)
	)
	(segment
		(start 149.920066 74.862462)
		(end 150.030066 74.862462)
		(width 0.125)
		(layer "In2.Cu")
		(net 70)
	)
	(segment
		(start 148.487565 75.755)
		(end 148.487565 75.194963)
		(width 0.125)
		(layer "In2.Cu")
		(net 70)
	)
	(segment
		(start 152.120066 75.862499)
		(end 152.230066 75.862499)
		(width 0.125)
		(layer "In2.Cu")
		(net 70)
	)
	(segment
		(start 166.156014 74.417818)
		(end 178.448833 62.124999)
		(width 0.125)
		(layer "In2.Cu")
		(net 70)
	)
	(segment
		(start 150.687565 76.60503)
		(end 150.687565 76.087501)
		(width 0.125)
		(layer "In2.Cu")
		(net 70)
	)
	(segment
		(start 131.162499 75.862499)
		(end 131.733981 75.862499)
		(width 0.125)
		(layer "In2.Cu")
		(net 70)
	)
	(segment
		(start 150.687565 75.862499)
		(end 150.687565 75.194963)
		(width 0.125)
		(layer "In2.Cu")
		(net 70)
	)
	(segment
		(start 149.587565 76.087501)
		(end 149.587565 75.862499)
		(width 0.125)
		(layer "In2.Cu")
		(net 70)
	)
	(segment
		(start 151.462567 75.862499)
		(end 151.462567 76.195)
		(width 0.125)
		(layer "In2.Cu")
		(net 70)
	)
	(segment
		(start 151.462567 75.194963)
		(end 151.462567 75.862499)
		(width 0.125)
		(layer "In2.Cu")
		(net 70)
	)
	(segment
		(start 149.587565 75.862499)
		(end 149.587565 75.194963)
		(width 0.125)
		(layer "In2.Cu")
		(net 70)
	)
	(segment
		(start 204.617275 61.564684)
		(end 204.661894 61.609303)
		(width 0.125)
		(layer "In2.Cu")
		(net 70)
	)
	(segment
		(start 148.820066 74.862462)
		(end 148.930066 74.862462)
		(width 0.125)
		(layer "In2.Cu")
		(net 70)
	)
	(segment
		(start 151.787565 76.60503)
		(end 151.787565 76.195)
		(width 0.125)
		(layer "In2.Cu")
		(net 70)
	)
	(segment
		(start 204.874025 61.566876)
		(end 205.053401 61.387499)
		(width 0.125)
		(layer "In2.Cu")
		(net 70)
	)
	(segment
		(start 150.362567 76.087501)
		(end 150.362567 76.60503)
		(width 0.125)
		(layer "In2.Cu")
		(net 70)
	)
	(segment
		(start 204.405142 61.607111)
		(end 204.447569 61.564685)
		(width 0.125)
		(layer "In2.Cu")
		(net 70)
	)
	(segment
		(start 152.230066 75.862499)
		(end 164.711333 75.862499)
		(width 0.125)
		(layer "In2.Cu")
		(net 70)
	)
	(segment
		(start 130.975 75.675)
		(end 131.162499 75.862499)
		(width 0.125)
		(layer "In2.Cu")
		(net 70)
	)
	(segment
		(start 205.512501 61.387499)
		(end 205.7 61.2)
		(width 0.125)
		(layer "In2.Cu")
		(net 70)
	)
	(segment
		(start 205.053401 61.387499)
		(end 205.512501 61.387499)
		(width 0.125)
		(layer "In2.Cu")
		(net 70)
	)
	(segment
		(start 149.370066 76.712529)
		(end 149.480066 76.712529)
		(width 0.125)
		(layer "In2.Cu")
		(net 70)
	)
	(segment
		(start 178.448833 62.124999)
		(end 204.315901 62.124999)
		(width 0.125)
		(layer "In2.Cu")
		(net 70)
	)
	(segment
		(start 150.470066 76.712529)
		(end 150.580066 76.712529)
		(width 0.125)
		(layer "In2.Cu")
		(net 70)
	)
	(segment
		(start 150.362567 75.194963)
		(end 150.362567 75.862499)
		(width 0.125)
		(layer "In2.Cu")
		(net 70)
	)
	(segment
		(start 131.873981 75.722499)
		(end 131.873981 75.602519)
		(width 0.125)
		(layer "In2.Cu")
		(net 70)
	)
	(segment
		(start 204.315901 62.124999)
		(end 204.449759 61.991141)
		(width 0.125)
		(layer "In2.Cu")
		(net 70)
	)
	(segment
		(start 149.262567 75.755)
		(end 149.262567 76.087501)
		(width 0.125)
		(layer "In2.Cu")
		(net 70)
	)
	(arc
		(start 204.405142 61.776817)
		(mid 204.369995 61.691964)
		(end 204.405142 61.607111)
		(width 0.125)
		(layer "In2.Cu")
		(net 70)
	)
	(arc
		(start 204.447569 61.564685)
		(mid 204.532422 61.529538)
		(end 204.617275 61.564684)
		(width 0.125)
		(layer "In2.Cu")
		(net 70)
	)
	(arc
		(start 151.462567 76.60503)
		(mid 151.494053 76.681043)
		(end 151.570066 76.712529)
		(width 0.125)
		(layer "In2.Cu")
		(net 70)
	)
	(arc
		(start 149.262567 76.60503)
		(mid 149.294053 76.681043)
		(end 149.370066 76.712529)
		(width 0.125)
		(layer "In2.Cu")
		(net 70)
	)
	(arc
		(start 149.587565 75.194963)
		(mid 149.684952 74.959849)
		(end 149.920066 74.862462)
		(width 0.125)
		(layer "In2.Cu")
		(net 70)
	)
	(arc
		(start 151.787565 76.195)
		(mid 151.884952 75.959886)
		(end 152.120066 75.862499)
		(width 0.125)
		(layer "In2.Cu")
		(net 70)
	)
	(arc
		(start 150.362567 76.60503)
		(mid 150.394053 76.681043)
		(end 150.470066 76.712529)
		(width 0.125)
		(layer "In2.Cu")
		(net 70)
	)
	(arc
		(start 131.873981 75.602519)
		(mid 131.914986 75.503524)
		(end 132.013981 75.462519)
		(width 0.125)
		(layer "In2.Cu")
		(net 70)
	)
	(arc
		(start 148.930066 74.862462)
		(mid 149.16518 74.959849)
		(end 149.262567 75.194963)
		(width 0.125)
		(layer "In2.Cu")
		(net 70)
	)
	(arc
		(start 204.449759 61.991141)
		(mid 204.484907 61.906288)
		(end 204.44976 61.821435)
		(width 0.125)
		(layer "In2.Cu")
		(net 70)
	)
	(arc
		(start 204.661894 61.609303)
		(mid 204.746747 61.64445)
		(end 204.8316 61.609303)
		(width 0.125)
		(layer "In2.Cu")
		(net 70)
	)
	(arc
		(start 132.223981 75.722499)
		(mid 132.264986 75.821494)
		(end 132.363981 75.862499)
		(width 0.125)
		(layer "In2.Cu")
		(net 70)
	)
	(arc
		(start 150.580066 76.712529)
		(mid 150.656079 76.681043)
		(end 150.687565 76.60503)
		(width 0.125)
		(layer "In2.Cu")
		(net 70)
	)
	(arc
		(start 148.380066 75.862499)
		(mid 148.456079 75.831013)
		(end 148.487565 75.755)
		(width 0.125)
		(layer "In2.Cu")
		(net 70)
	)
	(arc
		(start 148.487565 75.194963)
		(mid 148.584952 74.959849)
		(end 148.820066 74.862462)
		(width 0.125)
		(layer "In2.Cu")
		(net 70)
	)
	(arc
		(start 151.130066 74.862462)
		(mid 151.36518 74.959849)
		(end 151.462567 75.194963)
		(width 0.125)
		(layer "In2.Cu")
		(net 70)
	)
	(arc
		(start 131.733981 75.862499)
		(mid 131.832976 75.821494)
		(end 131.873981 75.722499)
		(width 0.125)
		(layer "In2.Cu")
		(net 70)
	)
	(arc
		(start 149.480066 76.712529)
		(mid 149.556079 76.681043)
		(end 149.587565 76.60503)
		(width 0.125)
		(layer "In2.Cu")
		(net 70)
	)
	(arc
		(start 150.030066 74.862462)
		(mid 150.26518 74.959849)
		(end 150.362567 75.194963)
		(width 0.125)
		(layer "In2.Cu")
		(net 70)
	)
	(arc
		(start 151.680066 76.712529)
		(mid 151.756079 76.681043)
		(end 151.787565 76.60503)
		(width 0.125)
		(layer "In2.Cu")
		(net 70)
	)
	(arc
		(start 150.687565 75.194963)
		(mid 150.784952 74.959849)
		(end 151.020066 74.862462)
		(width 0.125)
		(layer "In2.Cu")
		(net 70)
	)
	(arc
		(start 132.083981 75.462519)
		(mid 132.182976 75.503524)
		(end 132.223981 75.602519)
		(width 0.125)
		(layer "In2.Cu")
		(net 70)
	)
	(segment
		(start 233.930532 115.239468)
		(end 233.97 115.2)
		(width 0.2)
		(layer "F.Cu")
		(net 71)
	)
	(segment
		(start 233.930532 117.439468)
		(end 233.87 117.5)
		(width 0.2)
		(layer "F.Cu")
		(net 71)
	)
	(segment
		(start 233.930532 116.3475)
		(end 233.930532 117.439468)
		(width 0.2)
		(layer "F.Cu")
		(net 71)
	)
	(segment
		(start 231.430532 114.0725)
		(end 231.430532 112.939468)
		(width 0.2)
		(layer "F.Cu")
		(net 71)
	)
	(segment
		(start 231.430532 115.239468)
		(end 231.47 115.2)
		(width 0.2)
		(layer "F.Cu")
		(net 71)
	)
	(segment
		(start 233.930532 112.939468)
		(end 233.97 112.9)
		(width 0.2)
		(layer "F.Cu")
		(net 71)
	)
	(segment
		(start 233.930532 115.160532)
		(end 233.97 115.2)
		(width 0.2)
		(layer "F.Cu")
		(net 71)
	)
	(segment
		(start 231.430532 115.160532)
		(end 231.47 115.2)
		(width 0.2)
		(layer "F.Cu")
		(net 71)
	)
	(segment
		(start 232.060532 122.410532)
		(end 232.3 122.65)
		(width 0.2)
		(layer "F.Cu")
		(net 71)
	)
	(segment
		(start 233.930532 116.3475)
		(end 233.930532 115.239468)
		(width 0.2)
		(layer "F.Cu")
		(net 71)
	)
	(segment
		(start 233.930532 114.0725)
		(end 233.930532 115.160532)
		(width 0.2)
		(layer "F.Cu")
		(net 71)
	)
	(segment
		(start 231.430532 114.0725)
		(end 231.430532 115.160532)
		(width 0.2)
		(layer "F.Cu")
		(net 71)
	)
	(segment
		(start 233.930532 114.0725)
		(end 233.930532 112.939468)
		(width 0.2)
		(layer "F.Cu")
		(net 71)
	)
	(segment
		(start 231.430532 116.3475)
		(end 231.430532 117.460532)
		(width 0.2)
		(layer "F.Cu")
		(net 71)
	)
	(segment
		(start 231.430532 117.460532)
		(end 231.47 117.5)
		(width 0.2)
		(layer "F.Cu")
		(net 71)
	)
	(segment
		(start 231.430532 116.3475)
		(end 231.430532 115.239468)
		(width 0.2)
		(layer "F.Cu")
		(net 71)
	)
	(segment
		(start 231.430532 112.939468)
		(end 231.47 112.9)
		(width 0.2)
		(layer "F.Cu")
		(net 71)
	)
	(segment
		(start 232.060532 121.71)
		(end 232.060532 122.410532)
		(width 0.2)
		(layer "F.Cu")
		(net 71)
	)
	(via
		(at 233.97 115.2)
		(size 0.45)
		(drill 0.1)
		(layers "F.Cu" "B.Cu")
		(net 71)
	)
	(via
		(at 232.3 122.65)
		(size 0.45)
		(drill 0.1)
		(layers "F.Cu" "B.Cu")
		(net 71)
	)
	(via
		(at 231.47 115.2)
		(size 0.45)
		(drill 0.1)
		(layers "F.Cu" "B.Cu")
		(net 71)
	)
	(via
		(at 231.47 117.5)
		(size 0.45)
		(drill 0.1)
		(layers "F.Cu" "B.Cu")
		(net 71)
	)
	(via
		(at 231.47 112.9)
		(size 0.45)
		(drill 0.1)
		(layers "F.Cu" "B.Cu")
		(net 71)
	)
	(via
		(at 233.87 117.5)
		(size 0.45)
		(drill 0.1)
		(layers "F.Cu" "B.Cu")
		(net 71)
	)
	(via
		(at 233.97 112.9)
		(size 0.45)
		(drill 0.1)
		(layers "F.Cu" "B.Cu")
		(net 71)
	)
	(segment
		(start 209.9 121)
		(end 210.8 120.1)
		(width 0.1)
		(layer "B.Cu")
		(net 71)
	)
	(segment
		(start 222.1 116.4)
		(end 223 115.5)
		(width 0.1)
		(layer "B.Cu")
		(net 71)
	)
	(segment
		(start 226.5 117.1)
		(end 231.27 117.1)
		(width 0.1)
		(layer "B.Cu")
		(net 71)
	)
	(segment
		(start 224.9 115.5)
		(end 226.5 117.1)
		(width 0.1)
		(layer "B.Cu")
		(net 71)
	)
	(segment
		(start 231.47 116.1)
		(end 231.47 115.2)
		(width 0.2)
		(layer "B.Cu")
		(net 71)
	)
	(segment
		(start 230.97 116.6)
		(end 231.17 116.4)
		(width 0.2)
		(layer "B.Cu")
		(net 71)
	)
	(segment
		(start 214.8 120.1)
		(end 218.5 116.4)
		(width 0.1)
		(layer "B.Cu")
		(net 71)
	)
	(segment
		(start 207.18 121)
		(end 209.9 121)
		(width 0.1)
		(layer "B.Cu")
		(net 71)
	)
	(segment
		(start 231.17 116.4)
		(end 231.47 116.1)
		(width 0.2)
		(layer "B.Cu")
		(net 71)
	)
	(segment
		(start 231.17 113.8)
		(end 231.47 114.1)
		(width 0.2)
		(layer "B.Cu")
		(net 71)
	)
	(segment
		(start 231.27 117.1)
		(end 231.47 116.9)
		(width 0.1)
		(layer "B.Cu")
		(net 71)
	)
	(segment
		(start 231.47 114.1)
		(end 231.47 115.2)
		(width 0.2)
		(layer "B.Cu")
		(net 71)
	)
	(segment
		(start 223 115.5)
		(end 224.9 115.5)
		(width 0.1)
		(layer "B.Cu")
		(net 71)
	)
	(segment
		(start 218.5 116.4)
		(end 222.1 116.4)
		(width 0.1)
		(layer "B.Cu")
		(net 71)
	)
	(segment
		(start 230.77 116.6)
		(end 230.97 116.6)
		(width 0.2)
		(layer "B.Cu")
		(net 71)
	)
	(segment
		(start 231.47 116.9)
		(end 231.47 116.1)
		(width 0.1)
		(layer "B.Cu")
		(net 71)
	)
	(segment
		(start 210.8 120.1)
		(end 214.8 120.1)
		(width 0.1)
		(layer "B.Cu")
		(net 71)
	)
	(segment
		(start 230.55 113.8)
		(end 231.17 113.8)
		(width 0.2)
		(layer "B.Cu")
		(net 71)
	)
	(via
		(at 91.730532 82.65)
		(size 0.45)
		(drill 0.1)
		(layers "F.Cu" "B.Cu")
		(net 72)
	)
	(segment
		(start 91.730532 83.069468)
		(end 91.4 83.4)
		(width 0.1)
		(layer "B.Cu")
		(net 72)
	)
	(segment
		(start 91.730532 82.65)
		(end 91.730532 83.069468)
		(width 0.1)
		(layer "B.Cu")
		(net 72)
	)
	(segment
		(start 134.4 136.9)
		(end 134.9 137.4)
		(width 0.1)
		(layer "F.Cu")
		(net 74)
	)
	(segment
		(start 135.52 108.1)
		(end 134.8 108.1)
		(width 0.1)
		(layer "F.Cu")
		(net 74)
	)
	(segment
		(start 133.7 111.6)
		(end 135.7 113.6)
		(width 0.1)
		(layer "F.Cu")
		(net 74)
	)
	(segment
		(start 67.704 88.496)
		(end 67.704 87.701)
		(width 0.1)
		(layer "F.Cu")
		(net 74)
	)
	(segment
		(start 134.8 108.1)
		(end 133.7 109.2)
		(width 0.1)
		(layer "F.Cu")
		(net 74)
	)
	(segment
		(start 64.72 86.105)
		(end 64.72 86.78)
		(width 0.1)
		(layer "F.Cu")
		(net 74)
	)
	(segment
		(start 64.6 85.985)
		(end 64.72 86.105)
		(width 0.1)
		(layer "F.Cu")
		(net 74)
	)
	(segment
		(start 134.4 136.8)
		(end 134.4 136.9)
		(width 0.1)
		(layer "F.Cu")
		(net 74)
	)
	(segment
		(start 135.7 113.6)
		(end 135.7 123.2)
		(width 0.1)
		(layer "F.Cu")
		(net 74)
	)
	(segment
		(start 63.22 86.41)
		(end 63.645 85.985)
		(width 0.1)
		(layer "F.Cu")
		(net 74)
	)
	(segment
		(start 68.66 86.36)
		(end 68.8 86.5)
		(width 0.1)
		(layer "F.Cu")
		(net 74)
	)
	(segment
		(start 64.72 86.78)
		(end 64.2 87.3)
		(width 0.1)
		(layer "F.Cu")
		(net 74)
	)
	(segment
		(start 67.8 86.36)
		(end 68.66 86.36)
		(width 0.1)
		(layer "F.Cu")
		(net 74)
	)
	(segment
		(start 68.8 86.5)
		(end 68.8 87.2)
		(width 0.1)
		(layer "F.Cu")
		(net 74)
	)
	(segment
		(start 135.7 130.3)
		(end 135 131)
		(width 0.1)
		(layer "F.Cu")
		(net 74)
	)
	(segment
		(start 134.7 132.5)
		(end 134.7 136)
		(width 0.1)
		(layer "F.Cu")
		(net 74)
	)
	(segment
		(start 63.645 85.985)
		(end 64.6 85.985)
		(width 0.1)
		(layer "F.Cu")
		(net 74)
	)
	(segment
		(start 134.7 136)
		(end 134.4 136.3)
		(width 0.1)
		(layer "F.Cu")
		(net 74)
	)
	(segment
		(start 134.7 131.3)
		(end 134.7 132.5)
		(width 0.1)
		(layer "F.Cu")
		(net 74)
	)
	(segment
		(start 134.9 137.4)
		(end 135 137.4)
		(width 0.1)
		(layer "F.Cu")
		(net 74)
	)
	(segment
		(start 63.364 87.741)
		(end 63.364 86.554)
		(width 0.1)
		(layer "F.Cu")
		(net 74)
	)
	(segment
		(start 64.2 87.3)
		(end 64.2 88.2)
		(width 0.1)
		(layer "F.Cu")
		(net 74)
	)
	(segment
		(start 67.704 86.456)
		(end 67.8 86.36)
		(width 0.1)
		(layer "F.Cu")
		(net 74)
	)
	(segment
		(start 67.6 88.6)
		(end 67.704 88.496)
		(width 0.1)
		(layer "F.Cu")
		(net 74)
	)
	(segment
		(start 135 131)
		(end 134.7 131.3)
		(width 0.1)
		(layer "F.Cu")
		(net 74)
	)
	(segment
		(start 134.4 136.3)
		(end 134.4 136.8)
		(width 0.1)
		(layer "F.Cu")
		(net 74)
	)
	(segment
		(start 63.364 86.554)
		(end 63.22 86.41)
		(width 0.1)
		(layer "F.Cu")
		(net 74)
	)
	(segment
		(start 64.2 88.2)
		(end 64.8 88.8)
		(width 0.1)
		(layer "F.Cu")
		(net 74)
	)
	(segment
		(start 135.7 123.2)
		(end 135.7 130.3)
		(width 0.1)
		(layer "F.Cu")
		(net 74)
	)
	(segment
		(start 133.7 109.2)
		(end 133.7 111.6)
		(width 0.1)
		(layer "F.Cu")
		(net 74)
	)
	(segment
		(start 65.9 88.8)
		(end 66.1 88.6)
		(width 0.1)
		(layer "F.Cu")
		(net 74)
	)
	(segment
		(start 64.8 88.8)
		(end 65.9 88.8)
		(width 0.1)
		(layer "F.Cu")
		(net 74)
	)
	(segment
		(start 66.1 88.6)
		(end 67.6 88.6)
		(width 0.1)
		(layer "F.Cu")
		(net 74)
	)
	(segment
		(start 67.704 87.701)
		(end 67.704 86.456)
		(width 0.1)
		(layer "F.Cu")
		(net 74)
	)
	(via
		(at 135 137.4)
		(size 0.45)
		(drill 0.1)
		(layers "F.Cu" "B.Cu")
		(net 74)
	)
	(via
		(at 68.8 87.2)
		(size 0.45)
		(drill 0.1)
		(layers "F.Cu" "B.Cu")
		(net 74)
	)
	(segment
		(start 68.2 89.5)
		(end 68.2 136)
		(width 0.1)
		(layer "In7.Cu")
		(net 74)
	)
	(segment
		(start 122.3 137.1)
		(end 134.7 137.1)
		(width 0.1)
		(layer "In7.Cu")
		(net 74)
	)
	(segment
		(start 121.2 138.2)
		(end 122.3 137.1)
		(width 0.1)
		(layer "In7.Cu")
		(net 74)
	)
	(segment
		(start 71.6 139.4)
		(end 86.7 139.4)
		(width 0.1)
		(layer "In7.Cu")
		(net 74)
	)
	(segment
		(start 99.7 140.3)
		(end 100.8 141.4)
		(width 0.1)
		(layer "In7.Cu")
		(net 74)
	)
	(segment
		(start 134.7 137.1)
		(end 135 137.4)
		(width 0.1)
		(layer "In7.Cu")
		(net 74)
	)
	(segment
		(start 68.8 87.2)
		(end 68.8 88.9)
		(width 0.1)
		(layer "In7.Cu")
		(net 74)
	)
	(segment
		(start 86.7 139.4)
		(end 87.6 140.3)
		(width 0.1)
		(layer "In7.Cu")
		(net 74)
	)
	(segment
		(start 68.8 88.9)
		(end 68.2 89.5)
		(width 0.1)
		(layer "In7.Cu")
		(net 74)
	)
	(segment
		(start 119 141.4)
		(end 121.2 139.2)
		(width 0.1)
		(layer "In7.Cu")
		(net 74)
	)
	(segment
		(start 121.2 139.2)
		(end 121.2 138.2)
		(width 0.1)
		(layer "In7.Cu")
		(net 74)
	)
	(segment
		(start 87.6 140.3)
		(end 99.7 140.3)
		(width 0.1)
		(layer "In7.Cu")
		(net 74)
	)
	(segment
		(start 100.8 141.4)
		(end 119 141.4)
		(width 0.1)
		(layer "In7.Cu")
		(net 74)
	)
	(segment
		(start 68.2 136)
		(end 71.6 139.4)
		(width 0.1)
		(layer "In7.Cu")
		(net 74)
	)
	(segment
		(start 75 118.8)
		(end 77 118.8)
		(width 0.1)
		(layer "F.Cu")
		(net 75)
	)
	(segment
		(start 77 118.8)
		(end 80 121.8)
		(width 0.1)
		(layer "F.Cu")
		(net 75)
	)
	(segment
		(start 85.6 132.8)
		(end 84 132.8)
		(width 0.1)
		(layer "F.Cu")
		(net 75)
	)
	(segment
		(start 80 128.8)
		(end 80 121.8)
		(width 0.1)
		(layer "F.Cu")
		(net 75)
	)
	(segment
		(start 86.6 133.8)
		(end 85.6 132.8)
		(width 0.1)
		(layer "F.Cu")
		(net 75)
	)
	(segment
		(start 75 118.8)
		(end 74.5 118.3)
		(width 0.1)
		(layer "F.Cu")
		(net 75)
	)
	(segment
		(start 80 128.8)
		(end 84 132.8)
		(width 0.1)
		(layer "F.Cu")
		(net 75)
	)
	(segment
		(start 86.6 136.4)
		(end 86.6 133.8)
		(width 0.1)
		(layer "F.Cu")
		(net 75)
	)
	(segment
		(start 87 136.8)
		(end 86.6 136.4)
		(width 0.1)
		(layer "F.Cu")
		(net 75)
	)
	(segment
		(start 87.7 136.8)
		(end 87 136.8)
		(width 0.1)
		(layer "F.Cu")
		(net 75)
	)
	(via
		(at 87.7 136.8)
		(size 0.45)
		(drill 0.1)
		(layers "F.Cu" "B.Cu")
		(net 75)
	)
	(via
		(at 74.5 118.3)
		(size 0.45)
		(drill 0.1)
		(layers "F.Cu" "B.Cu")
		(net 75)
	)
	(via
		(at 145.8 93.4)
		(size 0.45)
		(drill 0.1)
		(layers "F.Cu" "B.Cu")
		(net 75)
	)
	(via
		(at 138.830532 81.15)
		(size 0.45)
		(drill 0.1)
		(layers "F.Cu" "B.Cu")
		(net 75)
	)
	(segment
		(start 140.975 86.125)
		(end 142.35 87.5)
		(width 0.1)
		(layer "B.Cu")
		(net 75)
	)
	(segment
		(start 143.1 94.25)
		(end 144.95 94.25)
		(width 0.1)
		(layer "B.Cu")
		(net 75)
	)
	(segment
		(start 140.5 82)
		(end 139.680532 82)
		(width 0.1)
		(layer "B.Cu")
		(net 75)
	)
	(segment
		(start 142.35 93.5)
		(end 143.1 94.25)
		(width 0.1)
		(layer "B.Cu")
		(net 75)
	)
	(segment
		(start 140.975 86.125)
		(end 140.975 82.475)
		(width 0.1)
		(layer "B.Cu")
		(net 75)
	)
	(segment
		(start 139.680532 82)
		(end 138.830532 81.15)
		(width 0.1)
		(layer "B.Cu")
		(net 75)
	)
	(segment
		(start 142.35 93.5)
		(end 142.35 87.5)
		(width 0.1)
		(layer "B.Cu")
		(net 75)
	)
	(segment
		(start 140.975 82.475)
		(end 140.5 82)
		(width 0.1)
		(layer "B.Cu")
		(net 75)
	)
	(segment
		(start 145.8 93.4)
		(end 144.95 94.25)
		(width 0.1)
		(layer "B.Cu")
		(net 75)
	)
	(segment
		(start 99.85 132.75)
		(end 95.15 132.75)
		(width 0.1)
		(layer "In5.Cu")
		(net 75)
	)
	(segment
		(start 145.799999 103.300001)
		(end 145.3 103.8)
		(width 0.1)
		(layer "In5.Cu")
		(net 75)
	)
	(segment
		(start 145.799999 107.499999)
		(end 145.799999 117.794113)
		(width 0.1)
		(layer "In5.Cu")
		(net 75)
	)
	(segment
		(start 138.694113 124.899999)
		(end 113.094113 124.899999)
		(width 0.1)
		(layer "In5.Cu")
		(net 75)
	)
	(segment
		(start 95.15 132.75)
		(end 91.1 136.8)
		(width 0.1)
		(layer "In5.Cu")
		(net 75)
	)
	(segment
		(start 145.799999 117.794113)
		(end 138.694113 124.899999)
		(width 0.1)
		(layer "In5.Cu")
		(net 75)
	)
	(segment
		(start 113.094113 124.899999)
		(end 106.194112 131.8)
		(width 0.1)
		(layer "In5.Cu")
		(net 75)
	)
	(segment
		(start 106.194112 131.8)
		(end 100.8 131.8)
		(width 0.1)
		(layer "In5.Cu")
		(net 75)
	)
	(segment
		(start 100.8 131.8)
		(end 99.85 132.75)
		(width 0.1)
		(layer "In5.Cu")
		(net 75)
	)
	(segment
		(start 145.3 103.8)
		(end 145.3 107)
		(width 0.1)
		(layer "In5.Cu")
		(net 75)
	)
	(segment
		(start 145.8 93.4)
		(end 145.799999 103.300001)
		(width 0.1)
		(layer "In5.Cu")
		(net 75)
	)
	(segment
		(start 145.3 107)
		(end 145.799999 107.499999)
		(width 0.1)
		(layer "In5.Cu")
		(net 75)
	)
	(segment
		(start 91.1 136.8)
		(end 87.7 136.8)
		(width 0.1)
		(layer "In5.Cu")
		(net 75)
	)
	(segment
		(start 92.830532 74.830532)
		(end 92.830532 75.15)
		(width 0.1)
		(layer "F.Cu")
		(net 76)
	)
	(segment
		(start 92.2 74.2)
		(end 92.830532 74.830532)
		(width 0.1)
		(layer "F.Cu")
		(net 76)
	)
	(segment
		(start 92.2 72.7)
		(end 92.2 74.2)
		(width 0.1)
		(layer "F.Cu")
		(net 76)
	)
	(via
		(at 92.2 72.7)
		(size 0.45)
		(drill 0.1)
		(layers "F.Cu" "B.Cu")
		(net 76)
	)
	(segment
		(start 125.405532 76.925)
		(end 125.405532 77.175)
		(width 0.17)
		(layer "F.Cu")
		(net 77)
	)
	(segment
		(start 125.405532 77.175)
		(end 125.280532 77.3)
		(width 0.17)
		(layer "F.Cu")
		(net 77)
	)
	(segment
		(start 125.130532 76.65)
		(end 125.405532 76.925)
		(width 0.17)
		(layer "F.Cu")
		(net 77)
	)
	(via
		(at 125.280532 77.3)
		(size 0.45)
		(drill 0.1)
		(layers "F.Cu" "B.Cu")
		(net 77)
	)
	(via
		(at 62.4875 104.3)
		(size 0.45)
		(drill 0.1)
		(layers "F.Cu" "B.Cu")
		(net 77)
	)
	(segment
		(start 63.689999 105.46)
		(end 63.614999 105.535)
		(width 0.17)
		(layer "B.Cu")
		(net 77)
	)
	(segment
		(start 63.614999 105.535)
		(end 62.782488 105.535)
		(width 0.17)
		(layer "B.Cu")
		(net 77)
	)
	(segment
		(start 64.59 105.46)
		(end 63.689999 105.46)
		(width 0.17)
		(layer "B.Cu")
		(net 77)
	)
	(segment
		(start 62.375 105.127512)
		(end 62.375 104.4125)
		(width 0.17)
		(layer "B.Cu")
		(net 77)
	)
	(segment
		(start 62.782488 105.535)
		(end 62.375 105.127512)
		(width 0.17)
		(layer "B.Cu")
		(net 77)
	)
	(segment
		(start 62.375 104.4125)
		(end 62.4875 104.3)
		(width 0.17)
		(layer "B.Cu")
		(net 77)
	)
	(segment
		(start 62.4875 104.3)
		(end 62.312501 104.125001)
		(width 0.125)
		(layer "In2.Cu")
		(net 77)
	)
	(segment
		(start 92.754082 75.458947)
		(end 92.864082 75.458947)
		(width 0.125)
		(layer "In2.Cu")
		(net 77)
	)
	(segment
		(start 99.88015 72.77895)
		(end 99.9966 72.77895)
		(width 0.125)
		(layer "In2.Cu")
		(net 77)
	)
	(segment
		(start 81.6125 77.7466)
		(end 84.9466 74.4125)
		(width 0.125)
		(layer "In2.Cu")
		(net 77)
	)
	(segment
		(start 90.554082 75.464846)
		(end 90.664082 75.464846)
		(width 0.125)
		(layer "In2.Cu")
		(net 77)
	)
	(segment
		(start 119.8534 74.4125)
		(end 122.020555 74.4125)
		(width 0.125)
		(layer "In2.Cu")
		(net 77)
	)
	(segment
		(start 88.223844 74.4125)
		(end 89.014082 74.4125)
		(width 0.125)
		(layer "In2.Cu")
		(net 77)
	)
	(segment
		(start 125.468031 76.427131)
		(end 125.468031 77.112501)
		(width 0.125)
		(layer "In2.Cu")
		(net 77)
	)
	(segment
		(start 107.9534 74.4125)
		(end 109.7466 74.4125)
		(width 0.125)
		(layer "In2.Cu")
		(net 77)
	)
	(segment
		(start 89.914082 74.4125)
		(end 90.114082 74.4125)
		(width 0.125)
		(layer "In2.Cu")
		(net 77)
	)
	(segment
		(start 95.977814 74.776232)
		(end 96.164082 74.776232)
		(width 0.125)
		(layer "In2.Cu")
		(net 77)
	)
	(segment
		(start 122.440555 74.6425)
		(end 122.440555 74.5325)
		(width 0.125)
		(layer "In2.Cu")
		(net 77)
	)
	(segment
		(start 122.560555 74.4125)
		(end 123.6534 74.4125)
		(width 0.125)
		(layer "In2.Cu")
		(net 77)
	)
	(segment
		(start 94.954082 74.858949)
		(end 95.064082 74.858949)
		(width 0.125)
		(layer "In2.Cu")
		(net 77)
	)
	(segment
		(start 87.663844 74.5725)
		(end 87.663844 74.573605)
		(width 0.125)
		(layer "In2.Cu")
		(net 77)
	)
	(segment
		(start 94.404082 73.366053)
		(end 94.514082 73.366053)
		(width 0.125)
		(layer "In2.Cu")
		(net 77)
	)
	(segment
		(start 89.364082 74.7625)
		(end 89.564082 74.7625)
		(width 0.125)
		(layer "In2.Cu")
		(net 77)
	)
	(segment
		(start 92.114082 74.4125)
		(end 92.314082 74.4125)
		(width 0.125)
		(layer "In2.Cu")
		(net 77)
	)
	(segment
		(start 111.2466 72.9125)
		(end 118.3534 72.9125)
		(width 0.125)
		(layer "In2.Cu")
		(net 77)
	)
	(segment
		(start 91.564082 74.7625)
		(end 91.764082 74.7625)
		(width 0.125)
		(layer "In2.Cu")
		(net 77)
	)
	(segment
		(start 103.3534 74.3125)
		(end 105.8466 74.3125)
		(width 0.125)
		(layer "In2.Cu")
		(net 77)
	)
	(segment
		(start 99.090316 73.568782)
		(end 99.4466 73.2125)
		(width 0.125)
		(layer "In2.Cu")
		(net 77)
	)
	(segment
		(start 94.621582 73.473553)
		(end 94.621582 74.526449)
		(width 0.125)
		(layer "In2.Cu")
		(net 77)
	)
	(segment
		(start 95.396582 74.526449)
		(end 95.396582 74.52)
		(width 0.125)
		(layer "In2.Cu")
		(net 77)
	)
	(segment
		(start 106.3466 73.8125)
		(end 107.3534 73.8125)
		(width 0.125)
		(layer "In2.Cu")
		(net 77)
	)
	(segment
		(start 94.296582 75.126447)
		(end 94.296582 73.473553)
		(width 0.125)
		(layer "In2.Cu")
		(net 77)
	)
	(segment
		(start 98.2466 74.4125)
		(end 98.312499 74.346599)
		(width 0.125)
		(layer "In2.Cu")
		(net 77)
	)
	(segment
		(start 81.0466 79.7125)
		(end 81.6125 79.1466)
		(width 0.125)
		(layer "In2.Cu")
		(net 77)
	)
	(segment
		(start 99.363497 74.149554)
		(end 99.012533 73.79859)
		(width 0.125)
		(layer "In2.Cu")
		(net 77)
	)
	(segment
		(start 84.9466 74.4125)
		(end 86.703844 74.4125)
		(width 0.125)
		(layer "In2.Cu")
		(net 77)
	)
	(segment
		(start 100.8791 72.88)
		(end 100.8791 72.283664)
		(width 0.125)
		(layer "In2.Cu")
		(net 77)
	)
	(segment
		(start 62.3125 86.1466)
		(end 68.7466 79.7125)
		(width 0.125)
		(layer "In2.Cu")
		(net 77)
	)
	(segment
		(start 92.421582 74.52)
		(end 92.421582 75.126447)
		(width 0.125)
		(layer "In2.Cu")
		(net 77)
	)
	(segment
		(start 105.8466 74.3125)
		(end 106.3466 73.8125)
		(width 0.125)
		(layer "In2.Cu")
		(net 77)
	)
	(segment
		(start 93.854082 75.458947)
		(end 93.964082 75.458947)
		(width 0.125)
		(layer "In2.Cu")
		(net 77)
	)
	(segment
		(start 102.2534 73.2125)
		(end 103.3534 74.3125)
		(width 0.125)
		(layer "In2.Cu")
		(net 77)
	)
	(segment
		(start 100.9866 72.176164)
		(end 101.0966 72.176164)
		(width 0.125)
		(layer "In2.Cu")
		(net 77)
	)
	(segment
		(start 100.43015 73.2125)
		(end 100.5466 73.2125)
		(width 0.125)
		(layer "In2.Cu")
		(net 77)
	)
	(segment
		(start 125.2534 76.2125)
		(end 125.468031 76.427131)
		(width 0.125)
		(layer "In2.Cu")
		(net 77)
	)
	(segment
		(start 109.7466 74.4125)
		(end 111.2466 72.9125)
		(width 0.125)
		(layer "In2.Cu")
		(net 77)
	)
	(segment
		(start 68.7466 79.7125)
		(end 81.0466 79.7125)
		(width 0.125)
		(layer "In2.Cu")
		(net 77)
	)
	(segment
		(start 98.464527 74.346599)
		(end 98.81549 74.697562)
		(width 0.125)
		(layer "In2.Cu")
		(net 77)
	)
	(segment
		(start 62.55 102.5)
		(end 62.55 102.187499)
		(width 0.125)
		(layer "In2.Cu")
		(net 77)
	)
	(segment
		(start 101.5366 73.2125)
		(end 102.2534 73.2125)
		(width 0.125)
		(layer "In2.Cu")
		(net 77)
	)
	(segment
		(start 107.3534 73.8125)
		(end 107.9534 74.4125)
		(width 0.125)
		(layer "In2.Cu")
		(net 77)
	)
	(segment
		(start 124.8534 76.2125)
		(end 125.2534 76.2125)
		(width 0.125)
		(layer "In2.Cu")
		(net 77)
	)
	(segment
		(start 95.504082 74.4125)
		(end 95.614082 74.4125)
		(width 0.125)
		(layer "In2.Cu")
		(net 77)
	)
	(segment
		(start 122.260555 74.7625)
		(end 122.320555 74.7625)
		(width 0.125)
		(layer "In2.Cu")
		(net 77)
	)
	(segment
		(start 99.012533 73.646562)
		(end 99.090316 73.568782)
		(width 0.125)
		(layer "In2.Cu")
		(net 77)
	)
	(segment
		(start 97.064082 74.7625)
		(end 97.264082 74.7625)
		(width 0.125)
		(layer "In2.Cu")
		(net 77)
	)
	(segment
		(start 93.304082 74.4125)
		(end 93.414082 74.4125)
		(width 0.125)
		(layer "In2.Cu")
		(net 77)
	)
	(segment
		(start 87.338048 74.4125)
		(end 87.503844 74.4125)
		(width 0.125)
		(layer "In2.Cu")
		(net 77)
	)
	(segment
		(start 91.104082 74.4125)
		(end 91.214082 74.4125)
		(width 0.125)
		(layer "In2.Cu")
		(net 77)
	)
	(segment
		(start 101.2041 72.283664)
		(end 101.2041 72.88)
		(width 0.125)
		(layer "In2.Cu")
		(net 77)
	)
	(segment
		(start 62.312501 102.737499)
		(end 62.55 102.5)
		(width 0.125)
		(layer "In2.Cu")
		(net 77)
	)
	(segment
		(start 118.3534 72.9125)
		(end 119.8534 74.4125)
		(width 0.125)
		(layer "In2.Cu")
		(net 77)
	)
	(segment
		(start 81.6125 79.1466)
		(end 81.6125 77.7466)
		(width 0.125)
		(layer "In2.Cu")
		(net 77)
	)
	(segment
		(start 62.55 102.187499)
		(end 62.312501 101.95)
		(width 0.125)
		(layer "In2.Cu")
		(net 77)
	)
	(segment
		(start 123.6534 74.4125)
		(end 124.4875 75.2466)
		(width 0.125)
		(layer "In2.Cu")
		(net 77)
	)
	(segment
		(start 86.938048 74.646704)
		(end 87.103844 74.646704)
		(width 0.125)
		(layer "In2.Cu")
		(net 77)
	)
	(segment
		(start 87.823844 74.733605)
		(end 87.903844 74.733605)
		(width 0.125)
		(layer "In2.Cu")
		(net 77)
	)
	(segment
		(start 124.4875 75.2466)
		(end 124.4875 75.8466)
		(width 0.125)
		(layer "In2.Cu")
		(net 77)
	)
	(segment
		(start 97.614082 74.4125)
		(end 98.2466 74.4125)
		(width 0.125)
		(layer "In2.Cu")
		(net 77)
	)
	(segment
		(start 99.285716 74.697562)
		(end 99.363497 74.61978)
		(width 0.125)
		(layer "In2.Cu")
		(net 77)
	)
	(segment
		(start 62.312501 101.95)
		(end 62.3125 86.1466)
		(width 0.125)
		(layer "In2.Cu")
		(net 77)
	)
	(segment
		(start 125.468031 77.112501)
		(end 125.280532 77.3)
		(width 0.125)
		(layer "In2.Cu")
		(net 77)
	)
	(segment
		(start 93.196582 75.126447)
		(end 93.196582 74.52)
		(width 0.125)
		(layer "In2.Cu")
		(net 77)
	)
	(segment
		(start 96.527814 74.4125)
		(end 96.714082 74.4125)
		(width 0.125)
		(layer "In2.Cu")
		(net 77)
	)
	(segment
		(start 62.312501 104.125001)
		(end 62.312501 102.737499)
		(width 0.125)
		(layer "In2.Cu")
		(net 77)
	)
	(segment
		(start 124.4875 75.8466)
		(end 124.8534 76.2125)
		(width 0.125)
		(layer "In2.Cu")
		(net 77)
	)
	(segment
		(start 122.140555 74.5325)
		(end 122.140555 74.6425)
		(width 0.125)
		(layer "In2.Cu")
		(net 77)
	)
	(segment
		(start 90.996582 75.132346)
		(end 90.996582 74.52)
		(width 0.125)
		(layer "In2.Cu")
		(net 77)
	)
	(segment
		(start 93.521582 74.52)
		(end 93.521582 75.126447)
		(width 0.125)
		(layer "In2.Cu")
		(net 77)
	)
	(segment
		(start 90.221582 74.52)
		(end 90.221582 75.132346)
		(width 0.125)
		(layer "In2.Cu")
		(net 77)
	)
	(segment
		(start 88.063844 74.573605)
		(end 88.063844 74.5725)
		(width 0.125)
		(layer "In2.Cu")
		(net 77)
	)
	(arc
		(start 92.051582 74.475)
		(mid 92.069888 74.430806)
		(end 92.114082 74.4125)
		(width 0.125)
		(layer "In2.Cu")
		(net 77)
	)
	(arc
		(start 95.614082 74.4125)
		(mid 95.663131 74.432817)
		(end 95.683448 74.481866)
		(width 0.125)
		(layer "In2.Cu")
		(net 77)
	)
	(arc
		(start 93.521582 75.126447)
		(mid 93.618969 75.36156)
		(end 93.854082 75.458947)
		(width 0.125)
		(layer "In2.Cu")
		(net 77)
	)
	(arc
		(start 91.276582 74.475)
		(mid 91.360789 74.678293)
		(end 91.564082 74.7625)
		(width 0.125)
		(layer "In2.Cu")
		(net 77)
	)
	(arc
		(start 101.0966 72.176164)
		(mid 101.172614 72.20765)
		(end 101.2041 72.283664)
		(width 0.125)
		(layer "In2.Cu")
		(net 77)
	)
	(arc
		(start 87.663844 74.573605)
		(mid 87.710707 74.686742)
		(end 87.823844 74.733605)
		(width 0.125)
		(layer "In2.Cu")
		(net 77)
	)
	(arc
		(start 96.776582 74.475)
		(mid 96.860789 74.678293)
		(end 97.064082 74.7625)
		(width 0.125)
		(layer "In2.Cu")
		(net 77)
	)
	(arc
		(start 90.664082 75.464846)
		(mid 90.899195 75.367459)
		(end 90.996582 75.132346)
		(width 0.125)
		(layer "In2.Cu")
		(net 77)
	)
	(arc
		(start 96.458448 74.481866)
		(mid 96.478765 74.432817)
		(end 96.527814 74.4125)
		(width 0.125)
		(layer "In2.Cu")
		(net 77)
	)
	(arc
		(start 90.996582 74.52)
		(mid 91.028068 74.443986)
		(end 91.104082 74.4125)
		(width 0.125)
		(layer "In2.Cu")
		(net 77)
	)
	(arc
		(start 92.314082 74.4125)
		(mid 92.390096 74.443986)
		(end 92.421582 74.52)
		(width 0.125)
		(layer "In2.Cu")
		(net 77)
	)
	(arc
		(start 122.140555 74.6425)
		(mid 122.175702 74.727353)
		(end 122.260555 74.7625)
		(width 0.125)
		(layer "In2.Cu")
		(net 77)
	)
	(arc
		(start 93.196582 74.52)
		(mid 93.228068 74.443986)
		(end 93.304082 74.4125)
		(width 0.125)
		(layer "In2.Cu")
		(net 77)
	)
	(arc
		(start 95.683448 74.481866)
		(mid 95.769666 74.690014)
		(end 95.977814 74.776232)
		(width 0.125)
		(layer "In2.Cu")
		(net 77)
	)
	(arc
		(start 87.503844 74.4125)
		(mid 87.616981 74.459363)
		(end 87.663844 74.5725)
		(width 0.125)
		(layer "In2.Cu")
		(net 77)
	)
	(arc
		(start 122.020555 74.4125)
		(mid 122.105408 74.447647)
		(end 122.140555 74.5325)
		(width 0.125)
		(layer "In2.Cu")
		(net 77)
	)
	(arc
		(start 89.564082 74.7625)
		(mid 89.767375 74.678293)
		(end 89.851582 74.475)
		(width 0.125)
		(layer "In2.Cu")
		(net 77)
	)
	(arc
		(start 93.414082 74.4125)
		(mid 93.490096 74.443986)
		(end 93.521582 74.52)
		(width 0.125)
		(layer "In2.Cu")
		(net 77)
	)
	(arc
		(start 94.621582 74.526449)
		(mid 94.718969 74.761562)
		(end 94.954082 74.858949)
		(width 0.125)
		(layer "In2.Cu")
		(net 77)
	)
	(arc
		(start 99.775875 72.883225)
		(mid 99.806416 72.809491)
		(end 99.88015 72.77895)
		(width 0.125)
		(layer "In2.Cu")
		(net 77)
	)
	(arc
		(start 98.81549 74.697562)
		(mid 99.050603 74.794949)
		(end 99.285716 74.697562)
		(width 0.125)
		(layer "In2.Cu")
		(net 77)
	)
	(arc
		(start 91.214082 74.4125)
		(mid 91.258276 74.430806)
		(end 91.276582 74.475)
		(width 0.125)
		(layer "In2.Cu")
		(net 77)
	)
	(arc
		(start 97.264082 74.7625)
		(mid 97.467375 74.678293)
		(end 97.551582 74.475)
		(width 0.125)
		(layer "In2.Cu")
		(net 77)
	)
	(arc
		(start 122.320555 74.7625)
		(mid 122.405408 74.727353)
		(end 122.440555 74.6425)
		(width 0.125)
		(layer "In2.Cu")
		(net 77)
	)
	(arc
		(start 92.421582 75.126447)
		(mid 92.518969 75.36156)
		(end 92.754082 75.458947)
		(width 0.125)
		(layer "In2.Cu")
		(net 77)
	)
	(arc
		(start 99.4466 73.2125)
		(mid 99.679433 73.116058)
		(end 99.775875 72.883225)
		(width 0.125)
		(layer "In2.Cu")
		(net 77)
	)
	(arc
		(start 100.5466 73.2125)
		(mid 100.781713 73.115113)
		(end 100.8791 72.88)
		(width 0.125)
		(layer "In2.Cu")
		(net 77)
	)
	(arc
		(start 86.703844 74.4125)
		(mid 86.786648 74.446798)
		(end 86.820946 74.529602)
		(width 0.125)
		(layer "In2.Cu")
		(net 77)
	)
	(arc
		(start 94.296582 73.473553)
		(mid 94.328068 73.397539)
		(end 94.404082 73.366053)
		(width 0.125)
		(layer "In2.Cu")
		(net 77)
	)
	(arc
		(start 100.8791 72.283664)
		(mid 100.910586 72.20765)
		(end 100.9866 72.176164)
		(width 0.125)
		(layer "In2.Cu")
		(net 77)
	)
	(arc
		(start 99.363497 74.61978)
		(mid 99.460884 74.384667)
		(end 99.363497 74.149554)
		(width 0.125)
		(layer "In2.Cu")
		(net 77)
	)
	(arc
		(start 96.164082 74.776232)
		(mid 96.37223 74.690014)
		(end 96.458448 74.481866)
		(width 0.125)
		(layer "In2.Cu")
		(net 77)
	)
	(arc
		(start 89.851582 74.475)
		(mid 89.869888 74.430806)
		(end 89.914082 74.4125)
		(width 0.125)
		(layer "In2.Cu")
		(net 77)
	)
	(arc
		(start 87.903844 74.733605)
		(mid 88.016981 74.686742)
		(end 88.063844 74.573605)
		(width 0.125)
		(layer "In2.Cu")
		(net 77)
	)
	(arc
		(start 94.514082 73.366053)
		(mid 94.590096 73.397539)
		(end 94.621582 73.473553)
		(width 0.125)
		(layer "In2.Cu")
		(net 77)
	)
	(arc
		(start 101.2041 72.88)
		(mid 101.301487 73.115113)
		(end 101.5366 73.2125)
		(width 0.125)
		(layer "In2.Cu")
		(net 77)
	)
	(arc
		(start 89.076582 74.475)
		(mid 89.160789 74.678293)
		(end 89.364082 74.7625)
		(width 0.125)
		(layer "In2.Cu")
		(net 77)
	)
	(arc
		(start 99.9966 72.77895)
		(mid 100.070334 72.809491)
		(end 100.100875 72.883225)
		(width 0.125)
		(layer "In2.Cu")
		(net 77)
	)
	(arc
		(start 86.820946 74.529602)
		(mid 86.855244 74.612406)
		(end 86.938048 74.646704)
		(width 0.125)
		(layer "In2.Cu")
		(net 77)
	)
	(arc
		(start 90.221582 75.132346)
		(mid 90.318969 75.367459)
		(end 90.554082 75.464846)
		(width 0.125)
		(layer "In2.Cu")
		(net 77)
	)
	(arc
		(start 97.551582 74.475)
		(mid 97.569888 74.430806)
		(end 97.614082 74.4125)
		(width 0.125)
		(layer "In2.Cu")
		(net 77)
	)
	(arc
		(start 122.440555 74.5325)
		(mid 122.475702 74.447647)
		(end 122.560555 74.4125)
		(width 0.125)
		(layer "In2.Cu")
		(net 77)
	)
	(arc
		(start 93.964082 75.458947)
		(mid 94.199195 75.36156)
		(end 94.296582 75.126447)
		(width 0.125)
		(layer "In2.Cu")
		(net 77)
	)
	(arc
		(start 90.114082 74.4125)
		(mid 90.190096 74.443986)
		(end 90.221582 74.52)
		(width 0.125)
		(layer "In2.Cu")
		(net 77)
	)
	(arc
		(start 87.220946 74.529602)
		(mid 87.255244 74.446798)
		(end 87.338048 74.4125)
		(width 0.125)
		(layer "In2.Cu")
		(net 77)
	)
	(arc
		(start 99.012533 73.79859)
		(mid 98.981047 73.722576)
		(end 99.012533 73.646562)
		(width 0.125)
		(layer "In2.Cu")
		(net 77)
	)
	(arc
		(start 98.312499 74.346599)
		(mid 98.388513 74.315113)
		(end 98.464527 74.346599)
		(width 0.125)
		(layer "In2.Cu")
		(net 77)
	)
	(arc
		(start 100.100875 72.883225)
		(mid 100.197317 73.116058)
		(end 100.43015 73.2125)
		(width 0.125)
		(layer "In2.Cu")
		(net 77)
	)
	(arc
		(start 95.396582 74.52)
		(mid 95.428068 74.443986)
		(end 95.504082 74.4125)
		(width 0.125)
		(layer "In2.Cu")
		(net 77)
	)
	(arc
		(start 95.064082 74.858949)
		(mid 95.299195 74.761562)
		(end 95.396582 74.526449)
		(width 0.125)
		(layer "In2.Cu")
		(net 77)
	)
	(arc
		(start 92.864082 75.458947)
		(mid 93.099195 75.36156)
		(end 93.196582 75.126447)
		(width 0.125)
		(layer "In2.Cu")
		(net 77)
	)
	(arc
		(start 91.764082 74.7625)
		(mid 91.967375 74.678293)
		(end 92.051582 74.475)
		(width 0.125)
		(layer "In2.Cu")
		(net 77)
	)
	(arc
		(start 88.063844 74.5725)
		(mid 88.110707 74.459363)
		(end 88.223844 74.4125)
		(width 0.125)
		(layer "In2.Cu")
		(net 77)
	)
	(arc
		(start 87.103844 74.646704)
		(mid 87.186648 74.612406)
		(end 87.220946 74.529602)
		(width 0.125)
		(layer "In2.Cu")
		(net 77)
	)
	(arc
		(start 96.714082 74.4125)
		(mid 96.758276 74.430806)
		(end 96.776582 74.475)
		(width 0.125)
		(layer "In2.Cu")
		(net 77)
	)
	(arc
		(start 89.014082 74.4125)
		(mid 89.058276 74.430806)
		(end 89.076582 74.475)
		(width 0.125)
		(layer "In2.Cu")
		(net 77)
	)
	(segment
		(start 230.495532 126.32)
		(end 230.495532 126.1)
		(width 0.19)
		(layer "F.Cu")
		(net 78)
	)
	(segment
		(start 230.485 125.815)
		(end 230.37 125.7)
		(width 0.19)
		(layer "F.Cu")
		(net 78)
	)
	(segment
		(start 221.717501 132.508)
		(end 222.785 132.508)
		(width 0.19)
		(layer "F.Cu")
		(net 78)
	)
	(segment
		(start 219.747908 132.4975)
		(end 219.6325 132.4975)
		(width 0.19)
		(layer "F.Cu")
		(net 78)
	)
	(segment
		(start 230.430532 127.0725)
		(end 230.430532 126.385)
		(width 0.19)
		(layer "F.Cu")
		(net 78)
	)
	(segment
		(start 219.305 132.825)
		(end 219.28 132.825)
		(width 0.19)
		(layer "F.Cu")
		(net 78)
	)
	(segment
		(start 222.785 132.508)
		(end 222.9 132.623)
		(width 0.19)
		(layer "F.Cu")
		(net 78)
	)
	(segment
		(start 219.990499 132.508)
		(end 219.758408 132.508)
		(width 0.19)
		(layer "F.Cu")
		(net 78)
	)
	(segment
		(start 221.652501 132.573)
		(end 221.717501 132.508)
		(width 0.19)
		(layer "F.Cu")
		(net 78)
	)
	(segment
		(start 220.055499 132.573)
		(end 219.990499 132.508)
		(width 0.19)
		(layer "F.Cu")
		(net 78)
	)
	(segment
		(start 230.485 126.089468)
		(end 230.485 125.815)
		(width 0.19)
		(layer "F.Cu")
		(net 78)
	)
	(segment
		(start 219.758408 132.508)
		(end 219.747908 132.4975)
		(width 0.19)
		(layer "F.Cu")
		(net 78)
	)
	(segment
		(start 219.6325 132.4975)
		(end 219.305 132.825)
		(width 0.19)
		(layer "F.Cu")
		(net 78)
	)
	(segment
		(start 230.430532 126.385)
		(end 230.495532 126.32)
		(width 0.19)
		(layer "F.Cu")
		(net 78)
	)
	(segment
		(start 221.24 132.573)
		(end 221.652501 132.573)
		(width 0.19)
		(layer "F.Cu")
		(net 78)
	)
	(segment
		(start 220.468 132.573)
		(end 220.055499 132.573)
		(width 0.19)
		(layer "F.Cu")
		(net 78)
	)
	(segment
		(start 230.495532 126.1)
		(end 230.485 126.089468)
		(width 0.19)
		(layer "F.Cu")
		(net 78)
	)
	(segment
		(start 221.24 132.573)
		(end 220.468 132.573)
		(width 0.19)
		(layer "F.Cu")
		(net 78)
	)
	(via
		(at 222.9 132.623)
		(size 0.45)
		(drill 0.1)
		(layers "F.Cu" "B.Cu")
		(net 78)
	)
	(via
		(at 230.37 125.7)
		(size 0.45)
		(drill 0.1)
		(layers "F.Cu" "B.Cu")
		(net 78)
	)
	(segment
		(start 225.956956 129.5625)
		(end 225.356956 128.9625)
		(width 0.15)
		(layer "In7.Cu")
		(net 78)
	)
	(segment
		(start 221.866044 132.4605)
		(end 222.7375 132.4605)
		(width 0.15)
		(layer "In7.Cu")
		(net 78)
	)
	(segment
		(start 221.4625 132.056956)
		(end 221.866044 132.4605)
		(width 0.15)
		(layer "In7.Cu")
		(net 78)
	)
	(segment
		(start 222.443044 128.9625)
		(end 221.4625 129.943044)
		(width 0.15)
		(layer "In7.Cu")
		(net 78)
	)
	(segment
		(start 230.37 125.7)
		(end 230.5125 125.8425)
		(width 0.19)
		(layer "In7.Cu")
		(net 78)
	)
	(segment
		(start 222.7375 132.4605)
		(end 222.9 132.623)
		(width 0.15)
		(layer "In7.Cu")
		(net 78)
	)
	(segment
		(start 230.5125 129.01476)
		(end 229.98863 129.53863)
		(width 0.19)
		(layer "In7.Cu")
		(net 78)
	)
	(segment
		(start 230.5125 125.8425)
		(end 230.5125 129.01476)
		(width 0.19)
		(layer "In7.Cu")
		(net 78)
	)
	(segment
		(start 221.4625 129.943044)
		(end 221.4625 132.056956)
		(width 0.15)
		(layer "In7.Cu")
		(net 78)
	)
	(segment
		(start 229.98863 129.53863)
		(end 229.96476 129.5625)
		(width 0.15)
		(layer "In7.Cu")
		(net 78)
	)
	(segment
		(start 229.96476 129.5625)
		(end 225.956956 129.5625)
		(width 0.15)
		(layer "In7.Cu")
		(net 78)
	)
	(segment
		(start 225.356956 128.9625)
		(end 222.443044 128.9625)
		(width 0.15)
		(layer "In7.Cu")
		(net 78)
	)
	(segment
		(start 128.930532 81.15)
		(end 129.205532 80.875)
		(width 0.17)
		(layer "F.Cu")
		(net 79)
	)
	(segment
		(start 129.205532 80.525)
		(end 129.080532 80.4)
		(width 0.17)
		(layer "F.Cu")
		(net 79)
	)
	(segment
		(start 129.205532 80.875)
		(end 129.205532 80.525)
		(width 0.17)
		(layer "F.Cu")
		(net 79)
	)
	(via
		(at 193.3 68.3875)
		(size 0.45)
		(drill 0.1)
		(layers "F.Cu" "B.Cu")
		(net 79)
	)
	(via
		(at 129.080532 80.4)
		(size 0.45)
		(drill 0.1)
		(layers "F.Cu" "B.Cu")
		(net 79)
	)
	(segment
		(start 192.022488 69.075)
		(end 189.927512 69.075)
		(width 0.17)
		(layer "B.Cu")
		(net 79)
	)
	(segment
		(start 193.658 58.84)
		(end 193.658 58.39)
		(width 0.17)
		(layer "B.Cu")
		(net 79)
	)
	(segment
		(start 189.927512 69.075)
		(end 188.225 67.372488)
		(width 0.17)
		(layer "B.Cu")
		(net 79)
	)
	(segment
		(start 193.733 59.119512)
		(end 193.733 58.915)
		(width 0.17)
		(layer "B.Cu")
		(net 79)
	)
	(segment
		(start 188.225 61.427512)
		(end 189.927512 59.725)
		(width 0.17)
		(layer "B.Cu")
		(net 79)
	)
	(segment
		(start 193.127512 59.725)
		(end 193.733 59.119512)
		(width 0.17)
		(layer "B.Cu")
		(net 79)
	)
	(segment
		(start 192.822488 68.275)
		(end 192.022488 69.075)
		(width 0.17)
		(layer "B.Cu")
		(net 79)
	)
	(segment
		(start 193.1875 68.275)
		(end 192.822488 68.275)
		(width 0.17)
		(layer "B.Cu")
		(net 79)
	)
	(segment
		(start 193.733 58.915)
		(end 193.658 58.84)
		(width 0.17)
		(layer "B.Cu")
		(net 79)
	)
	(segment
		(start 188.225 67.372488)
		(end 188.225 61.427512)
		(width 0.17)
		(layer "B.Cu")
		(net 79)
	)
	(segment
		(start 189.927512 59.725)
		(end 193.127512 59.725)
		(width 0.17)
		(layer "B.Cu")
		(net 79)
	)
	(segment
		(start 193.3 68.3875)
		(end 193.1875 68.275)
		(width 0.17)
		(layer "B.Cu")
		(net 79)
	)
	(segment
		(start 168.829407 80.406483)
		(end 169.31628 79.919612)
		(width 0.125)
		(layer "In2.Cu")
		(net 79)
	)
	(segment
		(start 129.268031 81.677131)
		(end 129.5534 81.9625)
		(width 0.125)
		(layer "In2.Cu")
		(net 79)
	)
	(segment
		(start 164.826186 82.7225)
		(end 164.826186 82.09)
		(width 0.125)
		(layer "In2.Cu")
		(net 79)
	)
	(segment
		(start 181.023391 68.212501)
		(end 193.125001 68.212501)
		(width 0.125)
		(layer "In2.Cu")
		(net 79)
	)
	(segment
		(start 168.72334 80.512547)
		(end 168.829407 80.406483)
		(width 0.125)
		(layer "In2.Cu")
		(net 79)
	)
	(segment
		(start 164.353686 83.075)
		(end 164.473686 83.075)
		(width 0.125)
		(layer "In2.Cu")
		(net 79)
	)
	(segment
		(start 169.31628 79.919612)
		(end 181.023391 68.212501)
		(width 0.125)
		(layer "In2.Cu")
		(net 79)
	)
	(segment
		(start 129.080532 80.4)
		(end 129.268031 80.587499)
		(width 0.125)
		(layer "In2.Cu")
		(net 79)
	)
	(segment
		(start 193.125001 68.212501)
		(end 193.3 68.3875)
		(width 0.125)
		(layer "In2.Cu")
		(net 79)
	)
	(segment
		(start 132.5466 81.7625)
		(end 133.1534 81.7625)
		(width 0.125)
		(layer "In2.Cu")
		(net 79)
	)
	(segment
		(start 164.953686 81.4)
		(end 165.073686 81.4)
		(width 0.125)
		(layer "In2.Cu")
		(net 79)
	)
	(segment
		(start 129.5534 81.9625)
		(end 132.3466 81.9625)
		(width 0.125)
		(layer "In2.Cu")
		(net 79)
	)
	(segment
		(start 168.812566 80.866938)
		(end 168.72334 80.777712)
		(width 0.125)
		(layer "In2.Cu")
		(net 79)
	)
	(segment
		(start 133.1534 81.7625)
		(end 133.3534 81.9625)
		(width 0.125)
		(layer "In2.Cu")
		(net 79)
	)
	(segment
		(start 164.826186 81.7375)
		(end 164.826186 81.5275)
		(width 0.125)
		(layer "In2.Cu")
		(net 79)
	)
	(segment
		(start 165.201186 82.09)
		(end 165.201186 82.7225)
		(width 0.125)
		(layer "In2.Cu")
		(net 79)
	)
	(segment
		(start 164.826186 82.09)
		(end 164.826186 81.7375)
		(width 0.125)
		(layer "In2.Cu")
		(net 79)
	)
	(segment
		(start 165.553686 83.075)
		(end 165.673686 83.075)
		(width 0.125)
		(layer "In2.Cu")
		(net 79)
	)
	(segment
		(start 166.273686 81.9625)
		(end 166.84 81.9625)
		(width 0.125)
		(layer "In2.Cu")
		(net 79)
	)
	(segment
		(start 167.273392 81.9625)
		(end 167.768748 81.467144)
		(width 0.125)
		(layer "In2.Cu")
		(net 79)
	)
	(segment
		(start 132.3466 81.9625)
		(end 132.5466 81.7625)
		(width 0.125)
		(layer "In2.Cu")
		(net 79)
	)
	(segment
		(start 166.026186 82.7225)
		(end 166.026186 82.09)
		(width 0.125)
		(layer "In2.Cu")
		(net 79)
	)
	(segment
		(start 168.033912 81.467143)
		(end 168.123137 81.556368)
		(width 0.125)
		(layer "In2.Cu")
		(net 79)
	)
	(segment
		(start 133.3534 81.9625)
		(end 163.873686 81.9625)
		(width 0.125)
		(layer "In2.Cu")
		(net 79)
	)
	(segment
		(start 167.768748 81.467144)
		(end 167.768747 81.467143)
		(width 0.125)
		(layer "In2.Cu")
		(net 79)
	)
	(segment
		(start 166.153686 81.9625)
		(end 166.273686 81.9625)
		(width 0.125)
		(layer "In2.Cu")
		(net 79)
	)
	(segment
		(start 168.7065 81.556368)
		(end 168.812566 81.450301)
		(width 0.125)
		(layer "In2.Cu")
		(net 79)
	)
	(segment
		(start 129.268031 80.587499)
		(end 129.268031 81.677131)
		(width 0.125)
		(layer "In2.Cu")
		(net 79)
	)
	(segment
		(start 164.001186 82.09)
		(end 164.001186 82.7225)
		(width 0.125)
		(layer "In2.Cu")
		(net 79)
	)
	(segment
		(start 165.201186 81.5275)
		(end 165.201186 81.7375)
		(width 0.125)
		(layer "In2.Cu")
		(net 79)
	)
	(segment
		(start 166.84 81.9625)
		(end 167.273392 81.9625)
		(width 0.125)
		(layer "In2.Cu")
		(net 79)
	)
	(segment
		(start 165.201186 81.7375)
		(end 165.201186 82.09)
		(width 0.125)
		(layer "In2.Cu")
		(net 79)
	)
	(arc
		(start 168.72334 80.777712)
		(mid 168.668422 80.64513)
		(end 168.72334 80.512547)
		(width 0.125)
		(layer "In2.Cu")
		(net 79)
	)
	(arc
		(start 165.673686 83.075)
		(mid 165.922941 82.971755)
		(end 166.026186 82.7225)
		(width 0.125)
		(layer "In2.Cu")
		(net 79)
	)
	(arc
		(start 163.873686 81.9625)
		(mid 163.963842 81.999844)
		(end 164.001186 82.09)
		(width 0.125)
		(layer "In2.Cu")
		(net 79)
	)
	(arc
		(start 168.123137 81.556368)
		(mid 168.414819 81.677186)
		(end 168.7065 81.556368)
		(width 0.125)
		(layer "In2.Cu")
		(net 79)
	)
	(arc
		(start 164.826186 81.5275)
		(mid 164.86353 81.437344)
		(end 164.953686 81.4)
		(width 0.125)
		(layer "In2.Cu")
		(net 79)
	)
	(arc
		(start 164.473686 83.075)
		(mid 164.722941 82.971755)
		(end 164.826186 82.7225)
		(width 0.125)
		(layer "In2.Cu")
		(net 79)
	)
	(arc
		(start 165.201186 82.7225)
		(mid 165.304431 82.971755)
		(end 165.553686 83.075)
		(width 0.125)
		(layer "In2.Cu")
		(net 79)
	)
	(arc
		(start 165.073686 81.4)
		(mid 165.163842 81.437344)
		(end 165.201186 81.5275)
		(width 0.125)
		(layer "In2.Cu")
		(net 79)
	)
	(arc
		(start 167.768747 81.467143)
		(mid 167.901329 81.412226)
		(end 168.033912 81.467143)
		(width 0.125)
		(layer "In2.Cu")
		(net 79)
	)
	(arc
		(start 168.812566 81.450301)
		(mid 168.933385 81.158619)
		(end 168.812566 80.866938)
		(width 0.125)
		(layer "In2.Cu")
		(net 79)
	)
	(arc
		(start 166.026186 82.09)
		(mid 166.06353 81.999844)
		(end 166.153686 81.9625)
		(width 0.125)
		(layer "In2.Cu")
		(net 79)
	)
	(arc
		(start 164.001186 82.7225)
		(mid 164.104431 82.971755)
		(end 164.353686 83.075)
		(width 0.125)
		(layer "In2.Cu")
		(net 79)
	)
	(segment
		(start 221.652501 126.425)
		(end 221.717501 126.36)
		(width 0.19)
		(layer "F.Cu")
		(net 80)
	)
	(segment
		(start 219.685 126.375)
		(end 219.505 126.375)
		(width 0.19)
		(layer "F.Cu")
		(net 80)
	)
	(segment
		(start 234.865532 131.666098)
		(end 234.865532 130.631251)
		(width 0.19)
		(layer "F.Cu")
		(net 80)
	)
	(segment
		(start 224.815 127.27663)
		(end 224.815 132.17663)
		(width 0.19)
		(layer "F.Cu")
		(net 80)
	)
	(segment
		(start 224.815 132.17663)
		(end 226.12337 133.485)
		(width 0.19)
		(layer "F.Cu")
		(net 80)
	)
	(segment
		(start 220.468 126.425)
		(end 220.055499 126.425)
		(width 0.19)
		(layer "F.Cu")
		(net 80)
	)
	(segment
		(start 219.505 126.375)
		(end 219.18 126.7)
		(width 0.19)
		(layer "F.Cu")
		(net 80)
	)
	(segment
		(start 221.717501 126.36)
		(end 223.89837 126.36)
		(width 0.19)
		(layer "F.Cu")
		(net 80)
	)
	(segment
		(start 220.055499 126.425)
		(end 219.990499 126.36)
		(width 0.19)
		(layer "F.Cu")
		(net 80)
	)
	(segment
		(start 220.468 126.425)
		(end 221.24 126.425)
		(width 0.19)
		(layer "F.Cu")
		(net 80)
	)
	(segment
		(start 219.7 126.36)
		(end 219.685 126.375)
		(width 0.19)
		(layer "F.Cu")
		(net 80)
	)
	(segment
		(start 221.24 126.425)
		(end 221.652501 126.425)
		(width 0.19)
		(layer "F.Cu")
		(net 80)
	)
	(segment
		(start 226.12337 133.485)
		(end 233.04663 133.485)
		(width 0.19)
		(layer "F.Cu")
		(net 80)
	)
	(segment
		(start 223.89837 126.36)
		(end 224.815 127.27663)
		(width 0.19)
		(layer "F.Cu")
		(net 80)
	)
	(segment
		(start 234.930532 130.566251)
		(end 234.930532 129.3475)
		(width 0.19)
		(layer "F.Cu")
		(net 80)
	)
	(segment
		(start 233.04663 133.485)
		(end 234.865532 131.666098)
		(width 0.19)
		(layer "F.Cu")
		(net 80)
	)
	(segment
		(start 234.865532 130.631251)
		(end 234.930532 130.566251)
		(width 0.19)
		(layer "F.Cu")
		(net 80)
	)
	(segment
		(start 219.990499 126.36)
		(end 219.7 126.36)
		(width 0.19)
		(layer "F.Cu")
		(net 80)
	)
	(segment
		(start 121.25 75.15)
		(end 120.9 74.8)
		(width 0.1)
		(layer "F.Cu")
		(net 81)
	)
	(segment
		(start 121.330532 75.15)
		(end 121.25 75.15)
		(width 0.1)
		(layer "F.Cu")
		(net 81)
	)
	(via
		(at 120.9 74.8)
		(size 0.45)
		(drill 0.1)
		(layers "F.Cu" "B.Cu")
		(net 81)
	)
	(via
		(at 86.7 109.05)
		(size 0.45)
		(drill 0.1)
		(layers "F.Cu" "B.Cu")
		(net 81)
	)
	(segment
		(start 75 99.603554)
		(end 75 92.139468)
		(width 0.1)
		(layer "B.Cu")
		(net 81)
	)
	(segment
		(start 75.436073 100.039627)
		(end 75 99.603554)
		(width 0.1)
		(layer "B.Cu")
		(net 81)
	)
	(segment
		(start 78.85 109.5)
		(end 78.85 100.253554)
		(width 0.1)
		(layer "B.Cu")
		(net 81)
	)
	(segment
		(start 86.7 109.05)
		(end 86.7 109.45)
		(width 0.1)
		(layer "B.Cu")
		(net 81)
	)
	(segment
		(start 78.636073 100.039627)
		(end 75.436073 100.039627)
		(width 0.1)
		(layer "B.Cu")
		(net 81)
	)
	(segment
		(start 86.2 109.95)
		(end 79.3 109.95)
		(width 0.1)
		(layer "B.Cu")
		(net 81)
	)
	(segment
		(start 78.85 100.253554)
		(end 78.636073 100.039627)
		(width 0.1)
		(layer "B.Cu")
		(net 81)
	)
	(segment
		(start 75 92.139468)
		(end 74.505532 91.645)
		(width 0.1)
		(layer "B.Cu")
		(net 81)
	)
	(segment
		(start 86.7 109.45)
		(end 86.2 109.95)
		(width 0.1)
		(layer "B.Cu")
		(net 81)
	)
	(segment
		(start 79.3 109.95)
		(end 78.85 109.5)
		(width 0.1)
		(layer "B.Cu")
		(net 81)
	)
	(segment
		(start 124.9 76.825)
		(end 124.000737 77.724263)
		(width 0.1)
		(layer "In5.Cu")
		(net 81)
	)
	(segment
		(start 119.049263 80.449263)
		(end 119.049263 81.200737)
		(width 0.1)
		(layer "In5.Cu")
		(net 81)
	)
	(segment
		(start 86.7 109.775738)
		(end 86.7 109.05)
		(width 0.1)
		(layer "In5.Cu")
		(net 81)
	)
	(segment
		(start 91.4 114.8)
		(end 90.699999 114.099999)
		(width 0.1)
		(layer "In5.Cu")
		(net 81)
	)
	(segment
		(start 119.049263 81.200737)
		(end 118.600737 81.649263)
		(width 0.1)
		(layer "In5.Cu")
		(net 81)
	)
	(segment
		(start 93.15 114.8)
		(end 91.4 114.8)
		(width 0.1)
		(layer "In5.Cu")
		(net 81)
	)
	(segment
		(start 110.675 86.875)
		(end 103.047367 94.502633)
		(width 0.1)
		(layer "In5.Cu")
		(net 81)
	)
	(segment
		(start 124.000737 77.724263)
		(end 121.774263 77.724263)
		(width 0.1)
		(layer "In5.Cu")
		(net 81)
	)
	(segment
		(start 85.150002 111.325736)
		(end 86.7 109.775738)
		(width 0.1)
		(layer "In5.Cu")
		(net 81)
	)
	(segment
		(start 96.9 109.624262)
		(end 96.699631 109.824631)
		(width 0.1)
		(layer "In5.Cu")
		(net 81)
	)
	(segment
		(start 85.150002 113.574264)
		(end 85.150002 111.325736)
		(width 0.1)
		(layer "In5.Cu")
		(net 81)
	)
	(segment
		(start 121.3 74.8)
		(end 122.1 75.6)
		(width 0.1)
		(layer "In5.Cu")
		(net 81)
	)
	(segment
		(start 96.9 103.1)
		(end 96.9 109.624262)
		(width 0.1)
		(layer "In5.Cu")
		(net 81)
	)
	(segment
		(start 99.4 100.6)
		(end 96.9 103.1)
		(width 0.1)
		(layer "In5.Cu")
		(net 81)
	)
	(segment
		(start 124.9 75.996823)
		(end 124.9 76.825)
		(width 0.1)
		(layer "In5.Cu")
		(net 81)
	)
	(segment
		(start 122.1 75.6)
		(end 124.503177 75.6)
		(width 0.1)
		(layer "In5.Cu")
		(net 81)
	)
	(segment
		(start 111.825 86.875)
		(end 110.675 86.875)
		(width 0.1)
		(layer "In5.Cu")
		(net 81)
	)
	(segment
		(start 114.375 84.775)
		(end 113.7 84.775)
		(width 0.1)
		(layer "In5.Cu")
		(net 81)
	)
	(segment
		(start 121.774263 77.724263)
		(end 120.974263 78.524263)
		(width 0.1)
		(layer "In5.Cu")
		(net 81)
	)
	(segment
		(start 113.7 84.775)
		(end 112.95 85.525)
		(width 0.1)
		(layer "In5.Cu")
		(net 81)
	)
	(segment
		(start 124.503177 75.6)
		(end 124.9 75.996823)
		(width 0.1)
		(layer "In5.Cu")
		(net 81)
	)
	(segment
		(start 119.449263 80.049263)
		(end 119.049263 80.449263)
		(width 0.1)
		(layer "In5.Cu")
		(net 81)
	)
	(segment
		(start 120.9 74.8)
		(end 121.3 74.8)
		(width 0.1)
		(layer "In5.Cu")
		(net 81)
	)
	(segment
		(start 120.974263 78.524263)
		(end 120.974263 79.725737)
		(width 0.1)
		(layer "In5.Cu")
		(net 81)
	)
	(segment
		(start 114.85 84.3)
		(end 114.375 84.775)
		(width 0.1)
		(layer "In5.Cu")
		(net 81)
	)
	(segment
		(start 118.600737 81.649263)
		(end 116.499263 81.649263)
		(width 0.1)
		(layer "In5.Cu")
		(net 81)
	)
	(segment
		(start 116.499263 81.649263)
		(end 114.85 83.298526)
		(width 0.1)
		(layer "In5.Cu")
		(net 81)
	)
	(segment
		(start 103.047367 94.502633)
		(end 99.847367 94.502633)
		(width 0.1)
		(layer "In5.Cu")
		(net 81)
	)
	(segment
		(start 99.4 94.95)
		(end 99.4 100.6)
		(width 0.1)
		(layer "In5.Cu")
		(net 81)
	)
	(segment
		(start 120.650737 80.049263)
		(end 119.449263 80.049263)
		(width 0.1)
		(layer "In5.Cu")
		(net 81)
	)
	(segment
		(start 120.974263 79.725737)
		(end 120.650737 80.049263)
		(width 0.1)
		(layer "In5.Cu")
		(net 81)
	)
	(segment
		(start 99.847367 94.502633)
		(end 99.4 94.95)
		(width 0.1)
		(layer "In5.Cu")
		(net 81)
	)
	(segment
		(start 114.85 83.298526)
		(end 114.85 84.3)
		(width 0.1)
		(layer "In5.Cu")
		(net 81)
	)
	(segment
		(start 85.675737 114.099999)
		(end 85.150002 113.574264)
		(width 0.1)
		(layer "In5.Cu")
		(net 81)
	)
	(segment
		(start 90.699999 114.099999)
		(end 85.675737 114.099999)
		(width 0.1)
		(layer "In5.Cu")
		(net 81)
	)
	(segment
		(start 96.699631 109.824631)
		(end 96.699631 111.250369)
		(width 0.1)
		(layer "In5.Cu")
		(net 81)
	)
	(segment
		(start 112.95 85.525)
		(end 112.95 85.75)
		(width 0.1)
		(layer "In5.Cu")
		(net 81)
	)
	(segment
		(start 112.95 85.75)
		(end 111.825 86.875)
		(width 0.1)
		(layer "In5.Cu")
		(net 81)
	)
	(segment
		(start 96.699631 111.250369)
		(end 93.15 114.8)
		(width 0.1)
		(layer "In5.Cu")
		(net 81)
	)
	(segment
		(start 128.5 100.6)
		(end 129.8 100.6)
		(width 0.1)
		(layer "F.Cu")
		(net 82)
	)
	(segment
		(start 130.2 101)
		(end 131.8 101)
		(width 0.1)
		(layer "F.Cu")
		(net 82)
	)
	(segment
		(start 129.8 100.6)
		(end 130.2 101)
		(width 0.1)
		(layer "F.Cu")
		(net 82)
	)
	(via
		(at 128.5 100.6)
		(size 0.45)
		(drill 0.1)
		(layers "F.Cu" "B.Cu")
		(net 82)
	)
	(via
		(at 131.8 101)
		(size 0.45)
		(drill 0.1)
		(layers "F.Cu" "B.Cu")
		(net 82)
	)
	(via
		(at 79.585532 87.835)
		(size 0.45)
		(drill 0.1)
		(layers "F.Cu" "B.Cu")
		(net 82)
	)
	(via
		(at 140.430532 76.65)
		(size 0.45)
		(drill 0.1)
		(layers "F.Cu" "B.Cu")
		(net 82)
	)
	(segment
		(start 144.45 77.05)
		(end 143.8 77.7)
		(width 0.1)
		(layer "In5.Cu")
		(net 82)
	)
	(segment
		(start 140.430532 76.65)
		(end 139.3 75.519468)
		(width 0.1)
		(layer "In5.Cu")
		(net 82)
	)
	(segment
		(start 142.875 82.375)
		(end 142.75 82.5)
		(width 0.1)
		(layer "In5.Cu")
		(net 82)
	)
	(segment
		(start 139.3 74.55)
		(end 140 73.85)
		(width 0.1)
		(layer "In5.Cu")
		(net 82)
	)
	(segment
		(start 87.250003 116.599997)
		(end 94.900003 116.599997)
		(width 0.1)
		(layer "In5.Cu")
		(net 82)
	)
	(segment
		(start 143.8 75.7)
		(end 144.45 76.35)
		(width 0.1)
		(layer "In5.Cu")
		(net 82)
	)
	(segment
		(start 144.45 76.35)
		(end 144.45 77.05)
		(width 0.1)
		(layer "In5.Cu")
		(net 82)
	)
	(segment
		(start 143.8 77.7)
		(end 143.8 78.475)
		(width 0.1)
		(layer "In5.Cu")
		(net 82)
	)
	(segment
		(start 79.585532 87.835)
		(end 79 88.420532)
		(width 0.1)
		(layer "In5.Cu")
		(net 82)
	)
	(segment
		(start 135.5 94.734314)
		(end 135.5 99.7)
		(width 0.1)
		(layer "In5.Cu")
		(net 82)
	)
	(segment
		(start 140.6 70.65)
		(end 141.75 71.8)
		(width 0.1)
		(layer "In5.Cu")
		(net 82)
	)
	(segment
		(start 143.8 74.85)
		(end 143.8 75.7)
		(width 0.1)
		(layer "In5.Cu")
		(net 82)
	)
	(segment
		(start 78.725 103.675)
		(end 79.05 104)
		(width 0.1)
		(layer "In5.Cu")
		(net 82)
	)
	(segment
		(start 140.1 70.65)
		(end 140.6 70.65)
		(width 0.1)
		(layer "In5.Cu")
		(net 82)
	)
	(segment
		(start 78.725 102.925)
		(end 78.725 103.675)
		(width 0.1)
		(layer "In5.Cu")
		(net 82)
	)
	(segment
		(start 139.3 75.519468)
		(end 139.3 74.55)
		(width 0.1)
		(layer "In5.Cu")
		(net 82)
	)
	(segment
		(start 143.325 78.95)
		(end 142.1 78.95)
		(width 0.1)
		(layer "In5.Cu")
		(net 82)
	)
	(segment
		(start 142.75 82.5)
		(end 142.75 83.3)
		(width 0.1)
		(layer "In5.Cu")
		(net 82)
	)
	(segment
		(start 77.7 102.2)
		(end 78.05 102.55)
		(width 0.1)
		(layer "In5.Cu")
		(net 82)
	)
	(segment
		(start 139.4 71.35)
		(end 140.1 70.65)
		(width 0.1)
		(layer "In5.Cu")
		(net 82)
	)
	(segment
		(start 100.33137 104)
		(end 120.59705 104)
		(width 0.1)
		(layer "In5.Cu")
		(net 82)
	)
	(segment
		(start 123.99705 100.6)
		(end 128.5 100.6)
		(width 0.1)
		(layer "In5.Cu")
		(net 82)
	)
	(segment
		(start 142.1 74.05)
		(end 142.45 74.05)
		(width 0.1)
		(layer "In5.Cu")
		(net 82)
	)
	(segment
		(start 142.875 80.824799)
		(end 142.875 82.375)
		(width 0.1)
		(layer "In5.Cu")
		(net 82)
	)
	(segment
		(start 142.45 74.05)
		(end 142.95 74.55)
		(width 0.1)
		(layer "In5.Cu")
		(net 82)
	)
	(segment
		(start 141.75 71.8)
		(end 141.75 73.7)
		(width 0.1)
		(layer "In5.Cu")
		(net 82)
	)
	(segment
		(start 143.5 74.55)
		(end 143.8 74.85)
		(width 0.1)
		(layer "In5.Cu")
		(net 82)
	)
	(segment
		(start 79 94.2)
		(end 77.7 95.5)
		(width 0.1)
		(layer "In5.Cu")
		(net 82)
	)
	(segment
		(start 79.05 104)
		(end 79.05 104.35)
		(width 0.1)
		(layer "In5.Cu")
		(net 82)
	)
	(segment
		(start 139.4 72.65)
		(end 139.4 71.35)
		(width 0.1)
		(layer "In5.Cu")
		(net 82)
	)
	(segment
		(start 81.5 117.05)
		(end 81.9 117.45)
		(width 0.1)
		(layer "In5.Cu")
		(net 82)
	)
	(segment
		(start 140 73.25)
		(end 139.4 72.65)
		(width 0.1)
		(layer "In5.Cu")
		(net 82)
	)
	(segment
		(start 143.8 78.475)
		(end 143.325 78.95)
		(width 0.1)
		(layer "In5.Cu")
		(net 82)
	)
	(segment
		(start 142.1 78.95)
		(end 141.8 79.25)
		(width 0.1)
		(layer "In5.Cu")
		(net 82)
	)
	(segment
		(start 142.75 83.3)
		(end 141.9 84.15)
		(width 0.1)
		(layer "In5.Cu")
		(net 82)
	)
	(segment
		(start 141.8 79.25)
		(end 141.8 79.749799)
		(width 0.1)
		(layer "In5.Cu")
		(net 82)
	)
	(segment
		(start 135.5 99.7)
		(end 134.2 101)
		(width 0.1)
		(layer "In5.Cu")
		(net 82)
	)
	(segment
		(start 81.5 106.8)
		(end 81.5 117.05)
		(width 0.1)
		(layer "In5.Cu")
		(net 82)
	)
	(segment
		(start 81.9 117.45)
		(end 86.4 117.45)
		(width 0.1)
		(layer "In5.Cu")
		(net 82)
	)
	(segment
		(start 79 88.420532)
		(end 79 94.2)
		(width 0.1)
		(layer "In5.Cu")
		(net 82)
	)
	(segment
		(start 77.7 95.5)
		(end 77.7 102.2)
		(width 0.1)
		(layer "In5.Cu")
		(net 82)
	)
	(segment
		(start 100.099999 104.231371)
		(end 100.33137 104)
		(width 0.1)
		(layer "In5.Cu")
		(net 82)
	)
	(segment
		(start 86.4 117.45)
		(end 87.250003 116.599997)
		(width 0.1)
		(layer "In5.Cu")
		(net 82)
	)
	(segment
		(start 141.75 73.7)
		(end 142.1 74.05)
		(width 0.1)
		(layer "In5.Cu")
		(net 82)
	)
	(segment
		(start 141.9 88.334314)
		(end 135.5 94.734314)
		(width 0.1)
		(layer "In5.Cu")
		(net 82)
	)
	(segment
		(start 142.95 74.55)
		(end 143.5 74.55)
		(width 0.1)
		(layer "In5.Cu")
		(net 82)
	)
	(segment
		(start 94.900003 116.599997)
		(end 100.099999 111.400001)
		(width 0.1)
		(layer "In5.Cu")
		(net 82)
	)
	(segment
		(start 134.2 101)
		(end 131.8 101)
		(width 0.1)
		(layer "In5.Cu")
		(net 82)
	)
	(segment
		(start 78.35 102.55)
		(end 78.725 102.925)
		(width 0.1)
		(layer "In5.Cu")
		(net 82)
	)
	(segment
		(start 79.05 104.35)
		(end 81.5 106.8)
		(width 0.1)
		(layer "In5.Cu")
		(net 82)
	)
	(segment
		(start 141.9 84.15)
		(end 141.9 88.334314)
		(width 0.1)
		(layer "In5.Cu")
		(net 82)
	)
	(segment
		(start 100.099999 111.400001)
		(end 100.099999 104.231371)
		(width 0.1)
		(layer "In5.Cu")
		(net 82)
	)
	(segment
		(start 120.59705 104)
		(end 123.99705 100.6)
		(width 0.1)
		(layer "In5.Cu")
		(net 82)
	)
	(segment
		(start 141.8 79.749799)
		(end 142.875 80.824799)
		(width 0.1)
		(layer "In5.Cu")
		(net 82)
	)
	(segment
		(start 140 73.85)
		(end 140 73.25)
		(width 0.1)
		(layer "In5.Cu")
		(net 82)
	)
	(segment
		(start 78.05 102.55)
		(end 78.35 102.55)
		(width 0.1)
		(layer "In5.Cu")
		(net 82)
	)
	(via
		(at 192.4 64.999999)
		(size 0.45)
		(drill 0.1)
		(layers "F.Cu" "B.Cu")
		(net 84)
	)
	(via
		(at 132.530532 78.15)
		(size 0.45)
		(drill 0.1)
		(layers "F.Cu" "B.Cu")
		(net 84)
	)
	(segment
		(start 192.5125 65.112499)
		(end 194.640013 65.112499)
		(width 0.17)
		(layer "B.Cu")
		(net 84)
	)
	(segment
		(start 194.640013 65.112499)
		(end 195.037553 64.714959)
		(width 0.17)
		(layer "B.Cu")
		(net 84)
	)
	(segment
		(start 194.862156 63.973878)
		(end 194.932869 63.903166)
		(width 0.17)
		(layer "B.Cu")
		(net 84)
	)
	(segment
		(start 195.673951 64.078565)
		(end 195.744661 64.007852)
		(width 0.17)
		(layer "B.Cu")
		(net 84)
	)
	(segment
		(start 198.233 59.365001)
		(end 198.158 59.290001)
		(width 0.17)
		(layer "B.Cu")
		(net 84)
	)
	(segment
		(start 198.233 61.519512)
		(end 198.233 59.365001)
		(width 0.17)
		(layer "B.Cu")
		(net 84)
	)
	(segment
		(start 195.215711 63.903167)
		(end 195.391109 64.078565)
		(width 0.17)
		(layer "B.Cu")
		(net 84)
	)
	(segment
		(start 198.158 59.290001)
		(end 198.158 58.39)
		(width 0.17)
		(layer "B.Cu")
		(net 84)
	)
	(segment
		(start 192.4 64.999999)
		(end 192.5125 65.112499)
		(width 0.17)
		(layer "B.Cu")
		(net 84)
	)
	(segment
		(start 195.744661 64.007852)
		(end 198.233 61.519512)
		(width 0.17)
		(layer "B.Cu")
		(net 84)
	)
	(segment
		(start 195.037553 64.432117)
		(end 194.862156 64.25672)
		(width 0.17)
		(layer "B.Cu")
		(net 84)
	)
	(arc
		(start 194.932869 63.903166)
		(mid 195.07429 63.844588)
		(end 195.215711 63.903167)
		(width 0.17)
		(layer "B.Cu")
		(net 84)
	)
	(arc
		(start 195.391109 64.078565)
		(mid 195.532531 64.137142)
		(end 195.673951 64.078565)
		(width 0.17)
		(layer "B.Cu")
		(net 84)
	)
	(arc
		(start 195.037553 64.714959)
		(mid 195.096132 64.573537)
		(end 195.037553 64.432117)
		(width 0.17)
		(layer "B.Cu")
		(net 84)
	)
	(arc
		(start 194.862156 64.25672)
		(mid 194.803579 64.115298)
		(end 194.862156 63.973878)
		(width 0.17)
		(layer "B.Cu")
		(net 84)
	)
	(segment
		(start 132.193033 78.487499)
		(end 132.193033 78.633933)
		(width 0.125)
		(layer "In2.Cu")
		(net 84)
	)
	(segment
		(start 166.544154 78.502125)
		(end 167.004911 78.962882)
		(width 0.125)
		(layer "In2.Cu")
		(net 84)
	)
	(segment
		(start 170.305813 74.485606)
		(end 170.433246 74.613039)
		(width 0.125)
		(layer "In2.Cu")
		(net 84)
	)
	(segment
		(start 171.083633 73.29382)
		(end 171.217674 73.15978)
		(width 0.125)
		(layer "In2.Cu")
		(net 84)
	)
	(segment
		(start 165 79.759108)
		(end 165.11 79.759108)
		(width 0.125)
		(layer "In2.Cu")
		(net 84)
	)
	(segment
		(start 168.520378 76.271062)
		(end 168.647801 76.398485)
		(width 0.125)
		(layer "In2.Cu")
		(net 84)
	)
	(segment
		(start 171.211062 73.835218)
		(end 171.211064 73.835221)
		(width 0.125)
		(layer "In2.Cu")
		(net 84)
	)
	(segment
		(start 170.981254 74.065029)
		(end 171.44201 74.525785)
		(width 0.125)
		(layer "In2.Cu")
		(net 84)
	)
	(segment
		(start 170.433244 74.613036)
		(end 170.894007 75.073799)
		(width 0.125)
		(layer "In2.Cu")
		(net 84)
	)
	(segment
		(start 170.038408 76.081427)
		(end 170.116189 76.003645)
		(width 0.125)
		(layer "In2.Cu")
		(net 84)
	)
	(segment
		(start 170.433244 74.613036)
		(end 170.433246 74.613039)
		(width 0.125)
		(layer "In2.Cu")
		(net 84)
	)
	(segment
		(start 171.211062 73.835218)
		(end 171.671819 74.295975)
		(width 0.125)
		(layer "In2.Cu")
		(net 84)
	)
	(segment
		(start 167.092164 77.954119)
		(end 167.55292 78.414875)
		(width 0.125)
		(layer "In2.Cu")
		(net 84)
	)
	(segment
		(start 172.144444 72.742738)
		(end 172.222227 72.664957)
		(width 0.125)
		(layer "In2.Cu")
		(net 84)
	)
	(segment
		(start 167.972369 76.81907)
		(end 168.099792 76.946493)
		(width 0.125)
		(layer "In2.Cu")
		(net 84)
	)
	(segment
		(start 167.97237 76.405126)
		(end 168.106436 76.271061)
		(width 0.125)
		(layer "In2.Cu")
		(net 84)
	)
	(segment
		(start 132.193033 78.633933)
		(end 132.4466 78.8875)
		(width 0.125)
		(layer "In2.Cu")
		(net 84)
	)
	(segment
		(start 168.6478 76.398483)
		(end 169.108538 76.859221)
		(width 0.125)
		(layer "In2.Cu")
		(net 84)
	)
	(segment
		(start 167.869982 77.176301)
		(end 168.330714 77.637033)
		(width 0.125)
		(layer "In2.Cu")
		(net 84)
	)
	(segment
		(start 192.225001 65.174998)
		(end 192.4 64.999999)
		(width 0.125)
		(layer "In2.Cu")
		(net 84)
	)
	(segment
		(start 165.55 78.8875)
		(end 165.999684 78.8875)
		(width 0.125)
		(layer "In2.Cu")
		(net 84)
	)
	(segment
		(start 169.425618 75.620665)
		(end 169.88638 76.081427)
		(width 0.125)
		(layer "In2.Cu")
		(net 84)
	)
	(segment
		(start 168.750174 75.627266)
		(end 168.884212 75.493229)
		(width 0.125)
		(layer "In2.Cu")
		(net 84)
	)
	(segment
		(start 169.425619 75.620667)
		(end 169.425618 75.620665)
		(width 0.125)
		(layer "In2.Cu")
		(net 84)
	)
	(segment
		(start 170.816226 75.303609)
		(end 170.894007 75.225827)
		(width 0.125)
		(layer "In2.Cu")
		(net 84)
	)
	(segment
		(start 172.449613 73.518133)
		(end 172.144444 73.212964)
		(width 0.125)
		(layer "In2.Cu")
		(net 84)
	)
	(segment
		(start 172.222227 72.664957)
		(end 179.712185 65.174999)
		(width 0.125)
		(layer "In2.Cu")
		(net 84)
	)
	(segment
		(start 166.964732 77.826688)
		(end 167.092166 77.954122)
		(width 0.125)
		(layer "In2.Cu")
		(net 84)
	)
	(segment
		(start 166.416723 78.374696)
		(end 166.544156 78.502129)
		(width 0.125)
		(layer "In2.Cu")
		(net 84)
	)
	(segment
		(start 169.527997 74.849456)
		(end 169.662038 74.715416)
		(width 0.125)
		(layer "In2.Cu")
		(net 84)
	)
	(segment
		(start 171.759072 73.287211)
		(end 172.219804 73.747943)
		(width 0.125)
		(layer "In2.Cu")
		(net 84)
	)
	(segment
		(start 167.869984 77.176304)
		(end 167.869982 77.176301)
		(width 0.125)
		(layer "In2.Cu")
		(net 84)
	)
	(segment
		(start 169.298182 75.49323)
		(end 169.425619 75.620667)
		(width 0.125)
		(layer "In2.Cu")
		(net 84)
	)
	(segment
		(start 167.321972 77.724308)
		(end 167.782729 78.185065)
		(width 0.125)
		(layer "In2.Cu")
		(net 84)
	)
	(segment
		(start 168.09979 76.94649)
		(end 168.099792 76.946493)
		(width 0.125)
		(layer "In2.Cu")
		(net 84)
	)
	(segment
		(start 168.09979 76.94649)
		(end 168.560523 77.407223)
		(width 0.125)
		(layer "In2.Cu")
		(net 84)
	)
	(segment
		(start 165.2175 79.651608)
		(end 165.2175 79.22)
		(width 0.125)
		(layer "In2.Cu")
		(net 84)
	)
	(segment
		(start 167.194541 77.596878)
		(end 167.321974 77.724311)
		(width 0.125)
		(layer "In2.Cu")
		(net 84)
	)
	(segment
		(start 171.63164 73.15978)
		(end 171.759074 73.287214)
		(width 0.125)
		(layer "In2.Cu")
		(net 84)
	)
	(segment
		(start 166.544154 78.502125)
		(end 166.544156 78.502129)
		(width 0.125)
		(layer "In2.Cu")
		(net 84)
	)
	(segment
		(start 172.371832 73.747943)
		(end 172.449613 73.670161)
		(width 0.125)
		(layer "In2.Cu")
		(net 84)
	)
	(segment
		(start 171.083631 73.707788)
		(end 171.211064 73.835221)
		(width 0.125)
		(layer "In2.Cu")
		(net 84)
	)
	(segment
		(start 170.853822 73.937598)
		(end 170.981256 74.065032)
		(width 0.125)
		(layer "In2.Cu")
		(net 84)
	)
	(segment
		(start 169.527995 75.263424)
		(end 169.655428 75.390857)
		(width 0.125)
		(layer "In2.Cu")
		(net 84)
	)
	(segment
		(start 170.203436 74.842847)
		(end 170.664198 75.303609)
		(width 0.125)
		(layer "In2.Cu")
		(net 84)
	)
	(segment
		(start 132.4466 78.8875)
		(end 164.56 78.8875)
		(width 0.125)
		(layer "In2.Cu")
		(net 84)
	)
	(segment
		(start 171.759074 73.287214)
		(end 171.759072 73.287211)
		(width 0.125)
		(layer "In2.Cu")
		(net 84)
	)
	(segment
		(start 179.712185 65.174999)
		(end 192.225001 65.174998)
		(width 0.125)
		(layer "In2.Cu")
		(net 84)
	)
	(segment
		(start 169.655426 75.390854)
		(end 170.116189 75.851617)
		(width 0.125)
		(layer "In2.Cu")
		(net 84)
	)
	(segment
		(start 164.8925 79.22)
		(end 164.8925 79.651608)
		(width 0.125)
		(layer "In2.Cu")
		(net 84)
	)
	(segment
		(start 170.981256 74.065032)
		(end 170.981254 74.065029)
		(width 0.125)
		(layer "In2.Cu")
		(net 84)
	)
	(segment
		(start 170.203438 74.84285)
		(end 170.203436 74.842847)
		(width 0.125)
		(layer "In2.Cu")
		(net 84)
	)
	(segment
		(start 168.750173 76.041238)
		(end 168.87761 76.168675)
		(width 0.125)
		(layer "In2.Cu")
		(net 84)
	)
	(segment
		(start 167.74255 77.04887)
		(end 167.869984 77.176304)
		(width 0.125)
		(layer "In2.Cu")
		(net 84)
	)
	(segment
		(start 168.877608 76.168672)
		(end 169.338347 76.629411)
		(width 0.125)
		(layer "In2.Cu")
		(net 84)
	)
	(segment
		(start 167.092166 77.954122)
		(end 167.092164 77.954119)
		(width 0.125)
		(layer "In2.Cu")
		(net 84)
	)
	(segment
		(start 171.594038 74.525785)
		(end 171.671819 74.448003)
		(width 0.125)
		(layer "In2.Cu")
		(net 84)
	)
	(segment
		(start 168.877608 76.168672)
		(end 168.87761 76.168675)
		(width 0.125)
		(layer "In2.Cu")
		(net 84)
	)
	(segment
		(start 167.704948 78.414875)
		(end 167.782729 78.337093)
		(width 0.125)
		(layer "In2.Cu")
		(net 84)
	)
	(segment
		(start 170.076004 74.715416)
		(end 170.203438 74.84285)
		(width 0.125)
		(layer "In2.Cu")
		(net 84)
	)
	(segment
		(start 166.416725 77.960728)
		(end 166.550766 77.826688)
		(width 0.125)
		(layer "In2.Cu")
		(net 84)
	)
	(segment
		(start 170.305815 74.071638)
		(end 170.439856 73.937598)
		(width 0.125)
		(layer "In2.Cu")
		(net 84)
	)
	(segment
		(start 169.655426 75.390854)
		(end 169.655428 75.390857)
		(width 0.125)
		(layer "In2.Cu")
		(net 84)
	)
	(segment
		(start 167.194543 77.18291)
		(end 167.328584 77.04887)
		(width 0.125)
		(layer "In2.Cu")
		(net 84)
	)
	(segment
		(start 167.321972 77.724308)
		(end 167.321974 77.724311)
		(width 0.125)
		(layer "In2.Cu")
		(net 84)
	)
	(segment
		(start 169.260566 76.859221)
		(end 169.338347 76.781439)
		(width 0.125)
		(layer "In2.Cu")
		(net 84)
	)
	(segment
		(start 168.647801 76.398485)
		(end 168.6478 76.398483)
		(width 0.125)
		(layer "In2.Cu")
		(net 84)
	)
	(segment
		(start 166.92713 79.192692)
		(end 167.004911 79.11491)
		(width 0.125)
		(layer "In2.Cu")
		(net 84)
	)
	(segment
		(start 132.530532 78.15)
		(end 132.193033 78.487499)
		(width 0.125)
		(layer "In2.Cu")
		(net 84)
	)
	(segment
		(start 166.46991 78.8875)
		(end 166.775102 79.192692)
		(width 0.125)
		(layer "In2.Cu")
		(net 84)
	)
	(segment
		(start 168.482742 77.637033)
		(end 168.560523 77.559251)
		(width 0.125)
		(layer "In2.Cu")
		(net 84)
	)
	(arc
		(start 172.449613 73.670161)
		(mid 172.481099 73.594147)
		(end 172.449613 73.518133)
		(width 0.125)
		(layer "In2.Cu")
		(net 84)
	)
	(arc
		(start 165.2175 79.22)
		(mid 165.314887 78.984887)
		(end 165.55 78.8875)
		(width 0.125)
		(layer "In2.Cu")
		(net 84)
	)
	(arc
		(start 165.11 79.759108)
		(mid 165.186014 79.727622)
		(end 165.2175 79.651608)
		(width 0.125)
		(layer "In2.Cu")
		(net 84)
	)
	(arc
		(start 168.750173 76.041238)
		(mid 168.664437 75.834252)
		(end 168.750174 75.627266)
		(width 0.125)
		(layer "In2.Cu")
		(net 84)
	)
	(arc
		(start 169.108538 76.859221)
		(mid 169.184552 76.890707)
		(end 169.260566 76.859221)
		(width 0.125)
		(layer "In2.Cu")
		(net 84)
	)
	(arc
		(start 168.884212 75.493229)
		(mid 169.091198 75.407493)
		(end 169.298182 75.49323)
		(width 0.125)
		(layer "In2.Cu")
		(net 84)
	)
	(arc
		(start 168.106436 76.271061)
		(mid 168.313407 76.185331)
		(end 168.520378 76.271062)
		(width 0.125)
		(layer "In2.Cu")
		(net 84)
	)
	(arc
		(start 172.219804 73.747943)
		(mid 172.295818 73.779429)
		(end 172.371832 73.747943)
		(width 0.125)
		(layer "In2.Cu")
		(net 84)
	)
	(arc
		(start 164.56 78.8875)
		(mid 164.795113 78.984887)
		(end 164.8925 79.22)
		(width 0.125)
		(layer "In2.Cu")
		(net 84)
	)
	(arc
		(start 171.44201 74.525785)
		(mid 171.518024 74.557271)
		(end 171.594038 74.525785)
		(width 0.125)
		(layer "In2.Cu")
		(net 84)
	)
	(arc
		(start 169.662038 74.715416)
		(mid 169.869021 74.629681)
		(end 170.076004 74.715416)
		(width 0.125)
		(layer "In2.Cu")
		(net 84)
	)
	(arc
		(start 166.775102 79.192692)
		(mid 166.851116 79.224178)
		(end 166.92713 79.192692)
		(width 0.125)
		(layer "In2.Cu")
		(net 84)
	)
	(arc
		(start 171.217674 73.15978)
		(mid 171.424657 73.074045)
		(end 171.63164 73.15978)
		(width 0.125)
		(layer "In2.Cu")
		(net 84)
	)
	(arc
		(start 171.671819 74.448003)
		(mid 171.703305 74.371989)
		(end 171.671819 74.295975)
		(width 0.125)
		(layer "In2.Cu")
		(net 84)
	)
	(arc
		(start 167.55292 78.414875)
		(mid 167.628934 78.446361)
		(end 167.704948 78.414875)
		(width 0.125)
		(layer "In2.Cu")
		(net 84)
	)
	(arc
		(start 170.894007 75.225827)
		(mid 170.925493 75.149813)
		(end 170.894007 75.073799)
		(width 0.125)
		(layer "In2.Cu")
		(net 84)
	)
	(arc
		(start 167.004911 79.11491)
		(mid 167.036397 79.038896)
		(end 167.004911 78.962882)
		(width 0.125)
		(layer "In2.Cu")
		(net 84)
	)
	(arc
		(start 165.999684 78.8875)
		(mid 166.234797 78.790113)
		(end 166.46991 78.8875)
		(width 0.125)
		(layer "In2.Cu")
		(net 84)
	)
	(arc
		(start 167.782729 78.337093)
		(mid 167.814215 78.261079)
		(end 167.782729 78.185065)
		(width 0.125)
		(layer "In2.Cu")
		(net 84)
	)
	(arc
		(start 170.664198 75.303609)
		(mid 170.740212 75.335095)
		(end 170.816226 75.303609)
		(width 0.125)
		(layer "In2.Cu")
		(net 84)
	)
	(arc
		(start 168.560523 77.559251)
		(mid 168.592009 77.483237)
		(end 168.560523 77.407223)
		(width 0.125)
		(layer "In2.Cu")
		(net 84)
	)
	(arc
		(start 166.550766 77.826688)
		(mid 166.757749 77.740953)
		(end 166.964732 77.826688)
		(width 0.125)
		(layer "In2.Cu")
		(net 84)
	)
	(arc
		(start 170.116189 76.003645)
		(mid 170.147675 75.927631)
		(end 170.116189 75.851617)
		(width 0.125)
		(layer "In2.Cu")
		(net 84)
	)
	(arc
		(start 168.330714 77.637033)
		(mid 168.406728 77.668519)
		(end 168.482742 77.637033)
		(width 0.125)
		(layer "In2.Cu")
		(net 84)
	)
	(arc
		(start 164.8925 79.651608)
		(mid 164.923986 79.727622)
		(end 165 79.759108)
		(width 0.125)
		(layer "In2.Cu")
		(net 84)
	)
	(arc
		(start 167.972369 76.81907)
		(mid 167.886639 76.612098)
		(end 167.97237 76.405126)
		(width 0.125)
		(layer "In2.Cu")
		(net 84)
	)
	(arc
		(start 170.439856 73.937598)
		(mid 170.646839 73.851863)
		(end 170.853822 73.937598)
		(width 0.125)
		(layer "In2.Cu")
		(net 84)
	)
	(arc
		(start 169.338347 76.781439)
		(mid 169.369833 76.705425)
		(end 169.338347 76.629411)
		(width 0.125)
		(layer "In2.Cu")
		(net 84)
	)
	(arc
		(start 170.305813 74.485606)
		(mid 170.220078 74.278623)
		(end 170.305815 74.071638)
		(width 0.125)
		(layer "In2.Cu")
		(net 84)
	)
	(arc
		(start 167.194541 77.596878)
		(mid 167.108806 77.389895)
		(end 167.194543 77.18291)
		(width 0.125)
		(layer "In2.Cu")
		(net 84)
	)
	(arc
		(start 172.144444 73.212964)
		(mid 172.047057 72.977851)
		(end 172.144444 72.742738)
		(width 0.125)
		(layer "In2.Cu")
		(net 84)
	)
	(arc
		(start 166.416723 78.374696)
		(mid 166.330988 78.167713)
		(end 166.416725 77.960728)
		(width 0.125)
		(layer "In2.Cu")
		(net 84)
	)
	(arc
		(start 167.328584 77.04887)
		(mid 167.535567 76.963135)
		(end 167.74255 77.04887)
		(width 0.125)
		(layer "In2.Cu")
		(net 84)
	)
	(arc
		(start 169.88638 76.081427)
		(mid 169.962394 76.112913)
		(end 170.038408 76.081427)
		(width 0.125)
		(layer "In2.Cu")
		(net 84)
	)
	(arc
		(start 169.527995 75.263424)
		(mid 169.44226 75.056441)
		(end 169.527997 74.849456)
		(width 0.125)
		(layer "In2.Cu")
		(net 84)
	)
	(arc
		(start 171.083631 73.707788)
		(mid 170.997896 73.500805)
		(end 171.083633 73.29382)
		(width 0.125)
		(layer "In2.Cu")
		(net 84)
	)
	(segment
		(start 86.6 59.4)
		(end 87.42 59.4)
		(width 0.1)
		(layer "F.Cu")
		(net 85)
	)
	(segment
		(start 143.130532 70.65)
		(end 143.130532 70.369468)
		(width 0.1)
		(layer "F.Cu")
		(net 85)
	)
	(segment
		(start 87.42 59.4)
		(end 87.52 59.5)
		(width 0.1)
		(layer "F.Cu")
		(net 85)
	)
	(segment
		(start 143.130532 70.369468)
		(end 143.8 69.7)
		(width 0.1)
		(layer "F.Cu")
		(net 85)
	)
	(via
		(at 86.6 59.4)
		(size 0.45)
		(drill 0.1)
		(layers "F.Cu" "B.Cu")
		(net 85)
	)
	(via
		(at 143.8 69.7)
		(size 0.45)
		(drill 0.1)
		(layers "F.Cu" "B.Cu")
		(net 85)
	)
	(via
		(at 88.7 70)
		(size 0.45)
		(drill 0.1)
		(layers "F.Cu" "B.Cu")
		(net 85)
	)
	(segment
		(start 88.2 61)
		(end 86.6 59.4)
		(width 0.1)
		(layer "B.Cu")
		(net 85)
	)
	(segment
		(start 88.7 70)
		(end 88.7 64.6)
		(width 0.1)
		(layer "B.Cu")
		(net 85)
	)
	(segment
		(start 88.2 64.1)
		(end 88.2 61)
		(width 0.1)
		(layer "B.Cu")
		(net 85)
	)
	(segment
		(start 143.5 70)
		(end 143.8 69.7)
		(width 0.1)
		(layer "B.Cu")
		(net 85)
	)
	(segment
		(start 88.7 64.6)
		(end 88.2 64.1)
		(width 0.1)
		(layer "B.Cu")
		(net 85)
	)
	(segment
		(start 142.65 70)
		(end 143.5 70)
		(width 0.1)
		(layer "B.Cu")
		(net 85)
	)
	(segment
		(start 88.9 70.2)
		(end 88.7 70)
		(width 0.1)
		(layer "In2.Cu")
		(net 85)
	)
	(segment
		(start 142.6 71.7)
		(end 135.7 71.7)
		(width 0.1)
		(layer "In2.Cu")
		(net 85)
	)
	(segment
		(start 129.9 70.2)
		(end 123.7 70.2)
		(width 0.1)
		(layer "In2.Cu")
		(net 85)
	)
	(segment
		(start 123.7 70.2)
		(end 123.3 69.8)
		(width 0.1)
		(layer "In2.Cu")
		(net 85)
	)
	(segment
		(start 135.2 71.2)
		(end 135.2 70.9)
		(width 0.1)
		(layer "In2.Cu")
		(net 85)
	)
	(segment
		(start 119.6 69.8)
		(end 118.5 68.7)
		(width 0.1)
		(layer "In2.Cu")
		(net 85)
	)
	(segment
		(start 104.1 69.4)
		(end 103.3 70.2)
		(width 0.1)
		(layer "In2.Cu")
		(net 85)
	)
	(segment
		(start 143.8 69.7)
		(end 143.8 70.5)
		(width 0.1)
		(layer "In2.Cu")
		(net 85)
	)
	(segment
		(start 143.8 70.5)
		(end 142.6 71.7)
		(width 0.1)
		(layer "In2.Cu")
		(net 85)
	)
	(segment
		(start 106.1 70.2)
		(end 105.3 69.4)
		(width 0.1)
		(layer "In2.Cu")
		(net 85)
	)
	(segment
		(start 135.2 70.9)
		(end 134.9 70.6)
		(width 0.1)
		(layer "In2.Cu")
		(net 85)
	)
	(segment
		(start 123.3 69.8)
		(end 119.6 69.8)
		(width 0.1)
		(layer "In2.Cu")
		(net 85)
	)
	(segment
		(start 103.3 70.2)
		(end 88.9 70.2)
		(width 0.1)
		(layer "In2.Cu")
		(net 85)
	)
	(segment
		(start 105.3 69.4)
		(end 104.1 69.4)
		(width 0.1)
		(layer "In2.Cu")
		(net 85)
	)
	(segment
		(start 118.5 68.7)
		(end 115 68.7)
		(width 0.1)
		(layer "In2.Cu")
		(net 85)
	)
	(segment
		(start 130.3 70.6)
		(end 129.9 70.2)
		(width 0.1)
		(layer "In2.Cu")
		(net 85)
	)
	(segment
		(start 113.5 70.2)
		(end 106.1 70.2)
		(width 0.1)
		(layer "In2.Cu")
		(net 85)
	)
	(segment
		(start 135.7 71.7)
		(end 135.2 71.2)
		(width 0.1)
		(layer "In2.Cu")
		(net 85)
	)
	(segment
		(start 134.9 70.6)
		(end 130.3 70.6)
		(width 0.1)
		(layer "In2.Cu")
		(net 85)
	)
	(segment
		(start 115 68.7)
		(end 113.5 70.2)
		(width 0.1)
		(layer "In2.Cu")
		(net 85)
	)
	(via
		(at 200.296706 62.996706)
		(size 0.45)
		(drill 0.1)
		(layers "F.Cu" "B.Cu")
		(net 86)
	)
	(via
		(at 131.430532 82.65)
		(size 0.45)
		(drill 0.1)
		(layers "F.Cu" "B.Cu")
		(net 86)
	)
	(segment
		(start 202.658 58.39)
		(end 202.658 58.84)
		(width 0.17)
		(layer "B.Cu")
		(net 86)
	)
	(segment
		(start 202.733 58.915)
		(end 202.733 59.219512)
		(width 0.17)
		(layer "B.Cu")
		(net 86)
	)
	(segment
		(start 200.625 61.327512)
		(end 200.625 62.827512)
		(width 0.17)
		(layer "B.Cu")
		(net 86)
	)
	(segment
		(start 200.625 62.827512)
		(end 200.455806 62.996706)
		(width 0.17)
		(layer "B.Cu")
		(net 86)
	)
	(segment
		(start 202.658 58.84)
		(end 202.733 58.915)
		(width 0.17)
		(layer "B.Cu")
		(net 86)
	)
	(segment
		(start 202.733 59.219512)
		(end 200.625 61.327512)
		(width 0.17)
		(layer "B.Cu")
		(net 86)
	)
	(segment
		(start 200.455806 62.996706)
		(end 200.296706 62.996706)
		(width 0.17)
		(layer "B.Cu")
		(net 86)
	)
	(segment
		(start 131.3466 83.3875)
		(end 131.093033 83.133933)
		(width 0.125)
		(layer "In2.Cu")
		(net 86)
	)
	(segment
		(start 131.3466 83.3875)
		(end 132.762076 83.3875)
		(width 0.125)
		(layer "In2.Cu")
		(net 86)
	)
	(segment
		(start 159.906537 83.3875)
		(end 159.906537 83.6125)
		(width 0.125)
		(layer "In2.Cu")
		(net 86)
	)
	(segment
		(start 160.231537 83.6125)
		(end 160.231537 83.28)
		(width 0.125)
		(layer "In2.Cu")
		(net 86)
	)
	(segment
		(start 133.112076 83.072071)
		(end 133.042076 83.072071)
		(width 0.125)
		(layer "In2.Cu")
		(net 86)
	)
	(segment
		(start 156.931537 83.28)
		(end 156.931537 82.701278)
		(width 0.125)
		(layer "In2.Cu")
		(net 86)
	)
	(segment
		(start 158.806537 83.28)
		(end 158.806537 83.6125)
		(width 0.125)
		(layer "In2.Cu")
		(net 86)
	)
	(segment
		(start 159.906537 83.6125)
		(end 159.906537 84.098703)
		(width 0.125)
		(layer "In2.Cu")
		(net 86)
	)
	(segment
		(start 157.706537 82.701278)
		(end 157.706537 83.28)
		(width 0.125)
		(layer "In2.Cu")
		(net 86)
	)
	(segment
		(start 159.131537 84.098703)
		(end 159.131537 83.6125)
		(width 0.125)
		(layer "In2.Cu")
		(net 86)
	)
	(segment
		(start 196.1534 63.3875)
		(end 198.520071 63.3875)
		(width 0.125)
		(layer "In2.Cu")
		(net 86)
	)
	(segment
		(start 159.906537 82.701278)
		(end 159.906537 83.3875)
		(width 0.125)
		(layer "In2.Cu")
		(net 86)
	)
	(segment
		(start 160.014037 84.206203)
		(end 160.124037 84.206203)
		(width 0.125)
		(layer "In2.Cu")
		(net 86)
	)
	(segment
		(start 200.296706 63.244194)
		(end 200.1534 63.3875)
		(width 0.125)
		(layer "In2.Cu")
		(net 86)
	)
	(segment
		(start 158.364037 82.368778)
		(end 158.474037 82.368778)
		(width 0.125)
		(layer "In2.Cu")
		(net 86)
	)
	(segment
		(start 194.5875 68.9534)
		(end 194.5875 64.9534)
		(width 0.125)
		(layer "In2.Cu")
		(net 86)
	)
	(segment
		(start 161.114037 83.3875)
		(end 161.224037 83.3875)
		(width 0.125)
		(layer "In2.Cu")
		(net 86)
	)
	(segment
		(start 158.806537 82.701278)
		(end 158.806537 83.28)
		(width 0.125)
		(layer "In2.Cu")
		(net 86)
	)
	(segment
		(start 161.224037 83.3875)
		(end 167.56207 83.3875)
		(width 0.125)
		(layer "In2.Cu")
		(net 86)
	)
	(segment
		(start 157.264037 82.368778)
		(end 157.374037 82.368778)
		(width 0.125)
		(layer "In2.Cu")
		(net 86)
	)
	(segment
		(start 161.006537 82.701278)
		(end 161.006537 83.28)
		(width 0.125)
		(layer "In2.Cu")
		(net 86)
	)
	(segment
		(start 132.902076 83.212071)
		(end 132.902076 83.2475)
		(width 0.125)
		(layer "In2.Cu")
		(net 86)
	)
	(segment
		(start 157.814037 83.3875)
		(end 157.924037 83.3875)
		(width 0.125)
		(layer "In2.Cu")
		(net 86)
	)
	(segment
		(start 200.296706 62.996706)
		(end 200.296706 63.244194)
		(width 0.125)
		(layer "In2.Cu")
		(net 86)
	)
	(segment
		(start 158.031537 83.28)
		(end 158.031537 82.701278)
		(width 0.125)
		(layer "In2.Cu")
		(net 86)
	)
	(segment
		(start 167.863646 83.3875)
		(end 181.576146 69.675)
		(width 0.125)
		(layer "In2.Cu")
		(net 86)
	)
	(segment
		(start 181.576146 69.675)
		(end 193.8659 69.675)
		(width 0.125)
		(layer "In2.Cu")
		(net 86)
	)
	(segment
		(start 198.870071 63.0375)
		(end 198.800071 63.0375)
		(width 0.125)
		(layer "In2.Cu")
		(net 86)
	)
	(segment
		(start 159.131537 83.3875)
		(end 159.131537 82.701278)
		(width 0.125)
		(layer "In2.Cu")
		(net 86)
	)
	(segment
		(start 160.564037 82.368778)
		(end 160.674037 82.368778)
		(width 0.125)
		(layer "In2.Cu")
		(net 86)
	)
	(segment
		(start 131.093033 83.133933)
		(end 131.093033 82.987499)
		(width 0.125)
		(layer "In2.Cu")
		(net 86)
	)
	(segment
		(start 158.914037 84.206203)
		(end 159.024037 84.206203)
		(width 0.125)
		(layer "In2.Cu")
		(net 86)
	)
	(segment
		(start 193.8659 69.675)
		(end 194.5875 68.9534)
		(width 0.125)
		(layer "In2.Cu")
		(net 86)
	)
	(segment
		(start 160.231537 83.28)
		(end 160.231537 82.701278)
		(width 0.125)
		(layer "In2.Cu")
		(net 86)
	)
	(segment
		(start 159.131537 83.6125)
		(end 159.131537 83.3875)
		(width 0.125)
		(layer "In2.Cu")
		(net 86)
	)
	(segment
		(start 167.56207 83.3875)
		(end 167.863646 83.3875)
		(width 0.125)
		(layer "In2.Cu")
		(net 86)
	)
	(segment
		(start 133.252076 83.2475)
		(end 133.252076 83.212071)
		(width 0.125)
		(layer "In2.Cu")
		(net 86)
	)
	(segment
		(start 158.806537 83.6125)
		(end 158.806537 84.098703)
		(width 0.125)
		(layer "In2.Cu")
		(net 86)
	)
	(segment
		(start 199.010071 63.2475)
		(end 199.010071 63.1775)
		(width 0.125)
		(layer "In2.Cu")
		(net 86)
	)
	(segment
		(start 131.093033 82.987499)
		(end 131.430532 82.65)
		(width 0.125)
		(layer "In2.Cu")
		(net 86)
	)
	(segment
		(start 198.660071 63.1775)
		(end 198.660071 63.2475)
		(width 0.125)
		(layer "In2.Cu")
		(net 86)
	)
	(segment
		(start 159.464037 82.368778)
		(end 159.574037 82.368778)
		(width 0.125)
		(layer "In2.Cu")
		(net 86)
	)
	(segment
		(start 160.231537 84.098703)
		(end 160.231537 83.6125)
		(width 0.125)
		(layer "In2.Cu")
		(net 86)
	)
	(segment
		(start 133.392076 83.3875)
		(end 156.824037 83.3875)
		(width 0.125)
		(layer "In2.Cu")
		(net 86)
	)
	(segment
		(start 200.1534 63.3875)
		(end 199.150071 63.3875)
		(width 0.125)
		(layer "In2.Cu")
		(net 86)
	)
	(segment
		(start 194.5875 64.9534)
		(end 196.1534 63.3875)
		(width 0.125)
		(layer "In2.Cu")
		(net 86)
	)
	(arc
		(start 198.800071 63.0375)
		(mid 198.701076 63.078505)
		(end 198.660071 63.1775)
		(width 0.125)
		(layer "In2.Cu")
		(net 86)
	)
	(arc
		(start 199.010071 63.1775)
		(mid 198.969066 63.078505)
		(end 198.870071 63.0375)
		(width 0.125)
		(layer "In2.Cu")
		(net 86)
	)
	(arc
		(start 160.674037 82.368778)
		(mid 160.90915 82.466165)
		(end 161.006537 82.701278)
		(width 0.125)
		(layer "In2.Cu")
		(net 86)
	)
	(arc
		(start 161.006537 83.28)
		(mid 161.038023 83.356014)
		(end 161.114037 83.3875)
		(width 0.125)
		(layer "In2.Cu")
		(net 86)
	)
	(arc
		(start 158.031537 82.701278)
		(mid 158.128924 82.466165)
		(end 158.364037 82.368778)
		(width 0.125)
		(layer "In2.Cu")
		(net 86)
	)
	(arc
		(start 156.931537 82.701278)
		(mid 157.028924 82.466165)
		(end 157.264037 82.368778)
		(width 0.125)
		(layer "In2.Cu")
		(net 86)
	)
	(arc
		(start 157.924037 83.3875)
		(mid 158.000051 83.356014)
		(end 158.031537 83.28)
		(width 0.125)
		(layer "In2.Cu")
		(net 86)
	)
	(arc
		(start 157.374037 82.368778)
		(mid 157.60915 82.466165)
		(end 157.706537 82.701278)
		(width 0.125)
		(layer "In2.Cu")
		(net 86)
	)
	(arc
		(start 133.392076 83.3875)
		(mid 133.293081 83.346495)
		(end 133.252076 83.2475)
		(width 0.125)
		(layer "In2.Cu")
		(net 86)
	)
	(arc
		(start 157.706537 83.28)
		(mid 157.738023 83.356014)
		(end 157.814037 83.3875)
		(width 0.125)
		(layer "In2.Cu")
		(net 86)
	)
	(arc
		(start 159.906537 84.098703)
		(mid 159.938023 84.174717)
		(end 160.014037 84.206203)
		(width 0.125)
		(layer "In2.Cu")
		(net 86)
	)
	(arc
		(start 159.024037 84.206203)
		(mid 159.100051 84.174717)
		(end 159.131537 84.098703)
		(width 0.125)
		(layer "In2.Cu")
		(net 86)
	)
	(arc
		(start 159.131537 82.701278)
		(mid 159.228924 82.466165)
		(end 159.464037 82.368778)
		(width 0.125)
		(layer "In2.Cu")
		(net 86)
	)
	(arc
		(start 158.474037 82.368778)
		(mid 158.70915 82.466165)
		(end 158.806537 82.701278)
		(width 0.125)
		(layer "In2.Cu")
		(net 86)
	)
	(arc
		(start 159.574037 82.368778)
		(mid 159.80915 82.466165)
		(end 159.906537 82.701278)
		(width 0.125)
		(layer "In2.Cu")
		(net 86)
	)
	(arc
		(start 160.124037 84.206203)
		(mid 160.200051 84.174717)
		(end 160.231537 84.098703)
		(width 0.125)
		(layer "In2.Cu")
		(net 86)
	)
	(arc
		(start 160.231537 82.701278)
		(mid 160.328924 82.466165)
		(end 160.564037 82.368778)
		(width 0.125)
		(layer "In2.Cu")
		(net 86)
	)
	(arc
		(start 198.660071 63.2475)
		(mid 198.619066 63.346495)
		(end 198.520071 63.3875)
		(width 0.125)
		(layer "In2.Cu")
		(net 86)
	)
	(arc
		(start 199.150071 63.3875)
		(mid 199.051076 63.346495)
		(end 199.010071 63.2475)
		(width 0.125)
		(layer "In2.Cu")
		(net 86)
	)
	(arc
		(start 158.806537 84.098703)
		(mid 158.838023 84.174717)
		(end 158.914037 84.206203)
		(width 0.125)
		(layer "In2.Cu")
		(net 86)
	)
	(arc
		(start 133.042076 83.072071)
		(mid 132.943081 83.113076)
		(end 132.902076 83.212071)
		(width 0.125)
		(layer "In2.Cu")
		(net 86)
	)
	(arc
		(start 133.252076 83.212071)
		(mid 133.211071 83.113076)
		(end 133.112076 83.072071)
		(width 0.125)
		(layer "In2.Cu")
		(net 86)
	)
	(arc
		(start 132.902076 83.2475)
		(mid 132.861071 83.346495)
		(end 132.762076 83.3875)
		(width 0.125)
		(layer "In2.Cu")
		(net 86)
	)
	(arc
		(start 156.824037 83.3875)
		(mid 156.900051 83.356014)
		(end 156.931537 83.28)
		(width 0.125)
		(layer "In2.Cu")
		(net 86)
	)
	(via
		(at 191.153294 66.203294)
		(size 0.45)
		(drill 0.1)
		(layers "F.Cu" "B.Cu")
		(net 87)
	)
	(via
		(at 130.530532 79.65)
		(size 0.45)
		(drill 0.1)
		(layers "F.Cu" "B.Cu")
		(net 87)
	)
	(segment
		(start 191.475 65.722488)
		(end 191.475 64.677512)
		(width 0.17)
		(layer "B.Cu")
		(net 87)
	)
	(segment
		(start 191.153294 66.203294)
		(end 191.153294 66.044194)
		(width 0.17)
		(layer "B.Cu")
		(net 87)
	)
	(segment
		(start 196.083 60.364488)
		(end 196.083 59.365001)
		(width 0.17)
		(layer "B.Cu")
		(net 87)
	)
	(segment
		(start 191.475 64.677512)
		(end 190.975 64.177512)
		(width 0.17)
		(layer "B.Cu")
		(net 87)
	)
	(segment
		(start 196.083 59.365001)
		(end 196.158 59.290001)
		(width 0.17)
		(layer "B.Cu")
		(net 87)
	)
	(segment
		(start 190.975 64.177512)
		(end 190.975 62.672488)
		(width 0.17)
		(layer "B.Cu")
		(net 87)
	)
	(segment
		(start 196.158 59.290001)
		(end 196.158 58.39)
		(width 0.17)
		(layer "B.Cu")
		(net 87)
	)
	(segment
		(start 190.975 62.672488)
		(end 191.272488 62.375)
		(width 0.17)
		(layer "B.Cu")
		(net 87)
	)
	(segment
		(start 191.272488 62.375)
		(end 194.072488 62.375)
		(width 0.17)
		(layer "B.Cu")
		(net 87)
	)
	(segment
		(start 194.072488 62.375)
		(end 196.083 60.364488)
		(width 0.17)
		(layer "B.Cu")
		(net 87)
	)
	(segment
		(start 191.153294 66.044194)
		(end 191.475 65.722488)
		(width 0.17)
		(layer "B.Cu")
		(net 87)
	)
	(segment
		(start 156.714574 79.634251)
		(end 156.824574 79.634251)
		(width 0.125)
		(layer "In2.Cu")
		(net 87)
	)
	(segment
		(start 155.832074 79.741749)
		(end 155.832074 80.2875)
		(width 0.125)
		(layer "In2.Cu")
		(net 87)
	)
	(segment
		(start 130.530532 79.65)
		(end 130.868031 79.987499)
		(width 0.125)
		(layer "In2.Cu")
		(net 87)
	)
	(segment
		(start 154.732074 80.62)
		(end 154.732074 81.10825)
		(width 0.125)
		(layer "In2.Cu")
		(net 87)
	)
	(segment
		(start 165.19 80.5125)
		(end 166.672782 80.5125)
		(width 0.125)
		(layer "In2.Cu")
		(net 87)
	)
	(segment
		(start 159.132074 80.2875)
		(end 159.132074 80.5125)
		(width 0.125)
		(layer "In2.Cu")
		(net 87)
	)
	(segment
		(start 158.807074 81.108251)
		(end 158.807074 80.5125)
		(width 0.125)
		(layer "In2.Cu")
		(net 87)
	)
	(segment
		(start 156.164574 81.440751)
		(end 156.274574 81.440751)
		(width 0.125)
		(layer "In2.Cu")
		(net 87)
	)
	(segment
		(start 158.032074 80.2875)
		(end 158.032074 80.5125)
		(width 0.125)
		(layer "In2.Cu")
		(net 87)
	)
	(segment
		(start 157.814574 79.634251)
		(end 157.924574 79.634251)
		(width 0.125)
		(layer "In2.Cu")
		(net 87)
	)
	(segment
		(start 159.132074 80.5125)
		(end 159.132074 81.108251)
		(width 0.125)
		(layer "In2.Cu")
		(net 87)
	)
	(segment
		(start 156.932074 80.2875)
		(end 156.932074 80.5125)
		(width 0.125)
		(layer "In2.Cu")
		(net 87)
	)
	(segment
		(start 160.232074 80.2875)
		(end 160.232074 80.62)
		(width 0.125)
		(layer "In2.Cu")
		(net 87)
	)
	(segment
		(start 158.807074 80.2875)
		(end 158.807074 80.187482)
		(width 0.125)
		(layer "In2.Cu")
		(net 87)
	)
	(segment
		(start 159.907074 80.2875)
		(end 159.907074 79.741751)
		(width 0.125)
		(layer "In2.Cu")
		(net 87)
	)
	(segment
		(start 159.907074 81.108251)
		(end 159.907074 80.5125)
		(width 0.125)
		(layer "In2.Cu")
		(net 87)
	)
	(segment
		(start 159.907074 80.5125)
		(end 159.907074 80.2875)
		(width 0.125)
		(layer "In2.Cu")
		(net 87)
	)
	(segment
		(start 160.232074 79.741751)
		(end 160.232074 80.2875)
		(width 0.125)
		(layer "In2.Cu")
		(net 87)
	)
	(segment
		(start 156.607074 80.2875)
		(end 156.607074 79.741751)
		(width 0.125)
		(layer "In2.Cu")
		(net 87)
	)
	(segment
		(start 155.507074 80.62)
		(end 155.507074 80.2875)
		(width 0.125)
		(layer "In2.Cu")
		(net 87)
	)
	(segment
		(start 180.385282 66.8)
		(end 190.3091 66.8)
		(width 0.125)
		(layer "In2.Cu")
		(net 87)
	)
	(segment
		(start 130.868031 79.987499)
		(end 130.868031 80.227131)
		(width 0.125)
		(layer "In2.Cu")
		(net 87)
	)
	(segment
		(start 155.507074 80.2875)
		(end 155.507074 79.741749)
		(width 0.125)
		(layer "In2.Cu")
		(net 87)
	)
	(segment
		(start 155.832074 80.5125)
		(end 155.832074 81.108251)
		(width 0.125)
		(layer "In2.Cu")
		(net 87)
	)
	(segment
		(start 157.707074 80.2875)
		(end 157.707074 79.741751)
		(width 0.125)
		(layer "In2.Cu")
		(net 87)
	)
	(segment
		(start 155.832074 80.2875)
		(end 155.832074 80.5125)
		(width 0.125)
		(layer "In2.Cu")
		(net 87)
	)
	(segment
		(start 156.607074 80.5125)
		(end 156.607074 80.2875)
		(width 0.125)
		(layer "In2.Cu")
		(net 87)
	)
	(segment
		(start 155.614574 79.634249)
		(end 155.724574 79.634249)
		(width 0.125)
		(layer "In2.Cu")
		(net 87)
	)
	(segment
		(start 190.3091 66.8)
		(end 190.905806 66.203294)
		(width 0.125)
		(layer "In2.Cu")
		(net 87)
	)
	(segment
		(start 190.905806 66.203294)
		(end 191.153294 66.203294)
		(width 0.125)
		(layer "In2.Cu")
		(net 87)
	)
	(segment
		(start 160.564574 81.440754)
		(end 160.674574 81.440754)
		(width 0.125)
		(layer "In2.Cu")
		(net 87)
	)
	(segment
		(start 157.264574 81.440751)
		(end 157.374574 81.440751)
		(width 0.125)
		(layer "In2.Cu")
		(net 87)
	)
	(segment
		(start 156.607074 81.108251)
		(end 156.607074 80.5125)
		(width 0.125)
		(layer "In2.Cu")
		(net 87)
	)
	(segment
		(start 166.672782 80.5125)
		(end 180.385282 66.8)
		(width 0.125)
		(layer "In2.Cu")
		(net 87)
	)
	(segment
		(start 160.014574 79.634251)
		(end 160.124574 79.634251)
		(width 0.125)
		(layer "In2.Cu")
		(net 87)
	)
	(segment
		(start 131.1534 80.5125)
		(end 154.624574 80.5125)
		(width 0.125)
		(layer "In2.Cu")
		(net 87)
	)
	(segment
		(start 157.707074 81.108251)
		(end 157.707074 80.5125)
		(width 0.125)
		(layer "In2.Cu")
		(net 87)
	)
	(segment
		(start 159.132074 80.187482)
		(end 159.132074 80.2875)
		(width 0.125)
		(layer "In2.Cu")
		(net 87)
	)
	(segment
		(start 161.224574 80.5125)
		(end 165.19 80.5125)
		(width 0.125)
		(layer "In2.Cu")
		(net 87)
	)
	(segment
		(start 155.064574 81.44075)
		(end 155.174574 81.44075)
		(width 0.125)
		(layer "In2.Cu")
		(net 87)
	)
	(segment
		(start 158.032074 80.5125)
		(end 158.032074 81.108251)
		(width 0.125)
		(layer "In2.Cu")
		(net 87)
	)
	(segment
		(start 161.007074 81.108254)
		(end 161.007074 80.62)
		(width 0.125)
		(layer "In2.Cu")
		(net 87)
	)
	(segment
		(start 158.364574 81.440751)
		(end 158.474574 81.440751)
		(width 0.125)
		(layer "In2.Cu")
		(net 87)
	)
	(segment
		(start 161.114574 80.5125)
		(end 161.224574 80.5125)
		(width 0.125)
		(layer "In2.Cu")
		(net 87)
	)
	(segment
		(start 130.868031 80.227131)
		(end 131.1534 80.5125)
		(width 0.125)
		(layer "In2.Cu")
		(net 87)
	)
	(segment
		(start 157.707074 80.5125)
		(end 157.707074 80.2875)
		(width 0.125)
		(layer "In2.Cu")
		(net 87)
	)
	(segment
		(start 156.932074 80.5125)
		(end 156.932074 81.108251)
		(width 0.125)
		(layer "In2.Cu")
		(net 87)
	)
	(segment
		(start 155.507074 81.10825)
		(end 155.507074 80.62)
		(width 0.125)
		(layer "In2.Cu")
		(net 87)
	)
	(segment
		(start 158.032074 79.741751)
		(end 158.032074 80.2875)
		(width 0.125)
		(layer "In2.Cu")
		(net 87)
	)
	(segment
		(start 156.932074 79.741751)
		(end 156.932074 80.2875)
		(width 0.125)
		(layer "In2.Cu")
		(net 87)
	)
	(segment
		(start 160.232074 80.62)
		(end 160.232074 81.108254)
		(width 0.125)
		(layer "In2.Cu")
		(net 87)
	)
	(segment
		(start 159.464574 81.440751)
		(end 159.574574 81.440751)
		(width 0.125)
		(layer "In2.Cu")
		(net 87)
	)
	(segment
		(start 158.807074 80.5125)
		(end 158.807074 80.2875)
		(width 0.125)
		(layer "In2.Cu")
		(net 87)
	)
	(segment
		(start 158.907091 80.087465)
		(end 159.032057 80.087465)
		(width 0.125)
		(layer "In2.Cu")
		(net 87)
	)
	(arc
		(start 157.707074 79.741751)
		(mid 157.73856 79.665737)
		(end 157.814574 79.634251)
		(width 0.125)
		(layer "In2.Cu")
		(net 87)
	)
	(arc
		(start 158.807074 80.187482)
		(mid 158.836368 80.116759)
		(end 158.907091 80.087465)
		(width 0.125)
		(layer "In2.Cu")
		(net 87)
	)
	(arc
		(start 157.924574 79.634251)
		(mid 158.000588 79.665737)
		(end 158.032074 79.741751)
		(width 0.125)
		(layer "In2.Cu")
		(net 87)
	)
	(arc
		(start 155.507074 79.741749)
		(mid 155.53856 79.665735)
		(end 155.614574 79.634249)
		(width 0.125)
		(layer "In2.Cu")
		(net 87)
	)
	(arc
		(start 161.007074 80.62)
		(mid 161.03856 80.543986)
		(end 161.114574 80.5125)
		(width 0.125)
		(layer "In2.Cu")
		(net 87)
	)
	(arc
		(start 160.674574 81.440754)
		(mid 160.909687 81.343367)
		(end 161.007074 81.108254)
		(width 0.125)
		(layer "In2.Cu")
		(net 87)
	)
	(arc
		(start 159.132074 81.108251)
		(mid 159.229461 81.343364)
		(end 159.464574 81.440751)
		(width 0.125)
		(layer "In2.Cu")
		(net 87)
	)
	(arc
		(start 155.832074 81.108251)
		(mid 155.929461 81.343364)
		(end 156.164574 81.440751)
		(width 0.125)
		(layer "In2.Cu")
		(net 87)
	)
	(arc
		(start 156.824574 79.634251)
		(mid 156.900588 79.665737)
		(end 156.932074 79.741751)
		(width 0.125)
		(layer "In2.Cu")
		(net 87)
	)
	(arc
		(start 160.232074 81.108254)
		(mid 160.329461 81.343367)
		(end 160.564574 81.440754)
		(width 0.125)
		(layer "In2.Cu")
		(net 87)
	)
	(arc
		(start 160.124574 79.634251)
		(mid 160.200588 79.665737)
		(end 160.232074 79.741751)
		(width 0.125)
		(layer "In2.Cu")
		(net 87)
	)
	(arc
		(start 155.724574 79.634249)
		(mid 155.800588 79.665735)
		(end 155.832074 79.741749)
		(width 0.125)
		(layer "In2.Cu")
		(net 87)
	)
	(arc
		(start 158.032074 81.108251)
		(mid 158.129461 81.343364)
		(end 158.364574 81.440751)
		(width 0.125)
		(layer "In2.Cu")
		(net 87)
	)
	(arc
		(start 158.474574 81.440751)
		(mid 158.709687 81.343364)
		(end 158.807074 81.108251)
		(width 0.125)
		(layer "In2.Cu")
		(net 87)
	)
	(arc
		(start 155.174574 81.44075)
		(mid 155.409687 81.343363)
		(end 155.507074 81.10825)
		(width 0.125)
		(layer "In2.Cu")
		(net 87)
	)
	(arc
		(start 159.907074 79.741751)
		(mid 159.93856 79.665737)
		(end 160.014574 79.634251)
		(width 0.125)
		(layer "In2.Cu")
		(net 87)
	)
	(arc
		(start 156.932074 81.108251)
		(mid 157.029461 81.343364)
		(end 157.264574 81.440751)
		(width 0.125)
		(layer "In2.Cu")
		(net 87)
	)
	(arc
		(start 157.374574 81.440751)
		(mid 157.609687 81.343364)
		(end 157.707074 81.108251)
		(width 0.125)
		(layer "In2.Cu")
		(net 87)
	)
	(arc
		(start 159.574574 81.440751)
		(mid 159.809687 81.343364)
		(end 159.907074 81.108251)
		(width 0.125)
		(layer "In2.Cu")
		(net 87)
	)
	(arc
		(start 156.607074 79.741751)
		(mid 156.63856 79.665737)
		(end 156.714574 79.634251)
		(width 0.125)
		(layer "In2.Cu")
		(net 87)
	)
	(arc
		(start 159.032057 80.087465)
		(mid 159.10278 80.116759)
		(end 159.132074 80.187482)
		(width 0.125)
		(layer "In2.Cu")
		(net 87)
	)
	(arc
		(start 156.274574 81.440751)
		(mid 156.509687 81.343364)
		(end 156.607074 81.108251)
		(width 0.125)
		(layer "In2.Cu")
		(net 87)
	)
	(arc
		(start 154.732074 81.10825)
		(mid 154.829461 81.343363)
		(end 155.064574 81.44075)
		(width 0.125)
		(layer "In2.Cu")
		(net 87)
	)
	(arc
		(start 154.624574 80.5125)
		(mid 154.700588 80.543986)
		(end 154.732074 80.62)
		(width 0.125)
		(layer "In2.Cu")
		(net 87)
	)
	(segment
		(start 125.405532 85.925)
		(end 125.130532 85.65)
		(width 0.17)
		(layer "F.Cu")
		(net 88)
	)
	(segment
		(start 125.32 86.360532)
		(end 125.405532 86.275)
		(width 0.17)
		(layer "F.Cu")
		(net 88)
	)
	(segment
		(start 125.32 86.39)
		(end 125.32 86.360532)
		(width 0.17)
		(layer "F.Cu")
		(net 88)
	)
	(segment
		(start 125.405532 86.275)
		(end 125.405532 85.925)
		(width 0.17)
		(layer "F.Cu")
		(net 88)
	)
	(via
		(at 65.9 112.4125)
		(size 0.45)
		(drill 0.1)
		(layers "F.Cu" "B.Cu")
		(net 88)
	)
	(via
		(at 125.32 86.39)
		(size 0.45)
		(drill 0.1)
		(layers "F.Cu" "B.Cu")
		(net 88)
	)
	(segment
		(start 65.7875 112.525)
		(end 65.9 112.4125)
		(width 0.17)
		(layer "B.Cu")
		(net 88)
	)
	(segment
		(start 65.04 112.46)
		(end 65.115 112.535)
		(width 0.17)
		(layer "B.Cu")
		(net 88)
	)
	(segment
		(start 65.115 112.535)
		(end 65.5 112.535)
		(width 0.17)
		(layer "B.Cu")
		(net 88)
	)
	(segment
		(start 65.51 112.525)
		(end 65.7875 112.525)
		(width 0.17)
		(layer "B.Cu")
		(net 88)
	)
	(segment
		(start 64.59 112.46)
		(end 65.04 112.46)
		(width 0.17)
		(layer "B.Cu")
		(net 88)
	)
	(segment
		(start 65.5 112.535)
		(end 65.51 112.525)
		(width 0.17)
		(layer "B.Cu")
		(net 88)
	)
	(segment
		(start 95.410799 86.555101)
		(end 95.648401 86.555101)
		(width 0.125)
		(layer "In2.Cu")
		(net 88)
	)
	(segment
		(start 98.6571 87.368)
		(end 98.6571 87.881577)
		(width 0.125)
		(layer "In2.Cu")
		(net 88)
	)
	(segment
		(start 107.7534 87.8875)
		(end 108.5534 87.0875)
		(width 0.125)
		(layer "In2.Cu")
		(net 88)
	)
	(segment
		(start 78.226 88.833746)
		(end 78.36 88.833746)
		(width 0.125)
		(layer "In2.Cu")
		(net 88)
	)
	(segment
		(start 90.375769 88.924235)
		(end 90.375766 88.924233)
		(width 0.125)
		(layer "In2.Cu")
		(net 88)
	)
	(segment
		(start 67.136592 112.420945)
		(end 67.136592 112.447499)
		(width 0.125)
		(layer "In2.Cu")
		(net 88)
	)
	(segment
		(start 125.468031 86.587499)
		(end 125.32 86.439468)
		(width 0.125)
		(layer "In2.Cu")
		(net 88)
	)
	(segment
		(start 92.7826 85.937947)
		(end 92.9166 85.937947)
		(width 0.125)
		(layer "In2.Cu")
		(net 88)
	)
	(segment
		(start 80.16725 89.968)
		(end 80.16725 90.081553)
		(width 0.125)
		(layer "In2.Cu")
		(net 88)
	)
	(segment
		(start 97.3171 87.368)
		(end 97.3171 87.881553)
		(width 0.125)
		(layer "In2.Cu")
		(net 88)
	)
	(segment
		(start 125.32 86.439468)
		(end 125.32 86.39)
		(width 0.125)
		(layer "In2.Cu")
		(net 88)
	)
	(segment
		(start 93.7421 87.881553)
		(end 93.7421 86.318423)
		(width 0.125)
		(layer "In2.Cu")
		(net 88)
	)
	(segment
		(start 96.4221 87.78156)
		(end 96.4221 87.368)
		(width 0.125)
		(layer "In2.Cu")
		(net 88)
	)
	(segment
		(start 125.468031 86.872869)
		(end 125.468031 86.587499)
		(width 0.125)
		(layer "In2.Cu")
		(net 88)
	)
	(segment
		(start 78.803 89.9375)
		(end 79.123 89.9375)
		(width 0.125)
		(layer "In2.Cu")
		(net 88)
	)
	(segment
		(start 72.4875 90.1534)
		(end 73.0534 89.5875)
		(width 0.125)
		(layer "In2.Cu")
		(net 88)
	)
	(segment
		(start 79.473 89.5875)
		(end 79.78675 89.5875)
		(width 0.125)
		(layer "In2.Cu")
		(net 88)
	)
	(segment
		(start 67.276592 112.587499)
		(end 71.953401 112.587499)
		(width 0.125)
		(layer "In2.Cu")
		(net 88)
	)
	(segment
		(start 71.953401 112.587499)
		(end 72.4875 112.0534)
		(width 0.125)
		(layer "In2.Cu")
		(net 88)
	)
	(segment
		(start 97.7621 87.881553)
		(end 97.7621 87.368)
		(width 0.125)
		(layer "In2.Cu")
		(net 88)
	)
	(segment
		(start 78.7405 89.214246)
		(end 78.7405 89.875)
		(width 0.125)
		(layer "In2.Cu")
		(net 88)
	)
	(segment
		(start 91.353698 87.787205)
		(end 92.1534 86.9875)
		(width 0.125)
		(layer "In2.Cu")
		(net 88)
	)
	(segment
		(start 77.1755 90.485754)
		(end 77.1755 89.968)
		(width 0.125)
		(layer "In2.Cu")
		(net 88)
	)
	(segment
		(start 99.4826 86.9875)
		(end 104.6466 86.9875)
		(width 0.125)
		(layer "In2.Cu")
		(net 88)
	)
	(segment
		(start 90.420615 88.339758)
		(end 90.690429 88.609572)
		(width 0.125)
		(layer "In2.Cu")
		(net 88)
	)
	(segment
		(start 98.8126 88.037077)
		(end 98.9466 88.037077)
		(width 0.125)
		(layer "In2.Cu")
		(net 88)
	)
	(segment
		(start 89.473101 88.74918)
		(end 89.567854 88.654428)
		(width 0.125)
		(layer "In2.Cu")
		(net 88)
	)
	(segment
		(start 90.375766 88.924233)
		(end 90.928424 89.476891)
		(width 0.125)
		(layer "In2.Cu")
		(net 88)
	)
	(segment
		(start 91.053478 87.706895)
		(end 91.133788 87.787205)
		(width 0.125)
		(layer "In2.Cu")
		(net 88)
	)
	(segment
		(start 92.1534 86.9875)
		(end 92.2466 86.9875)
		(width 0.125)
		(layer "In2.Cu")
		(net 88)
	)
	(segment
		(start 76.886 90.641254)
		(end 77.02 90.641254)
		(width 0.125)
		(layer "In2.Cu")
		(net 88)
	)
	(segment
		(start 77.8455 89.432)
		(end 77.8455 89.214246)
		(width 0.125)
		(layer "In2.Cu")
		(net 88)
	)
	(segment
		(start 89.553401 89.367591)
		(end 89.4731 89.28729)
		(width 0.125)
		(layer "In2.Cu")
		(net 88)
	)
	(segment
		(start 93.2971 86.318447)
		(end 93.2971 87.881553)
		(width 0.125)
		(layer "In2.Cu")
		(net 88)
	)
	(segment
		(start 98.1426 86.9875)
		(end 98.2766 86.9875)
		(width 0.125)
		(layer "In2.Cu")
		(net 88)
	)
	(segment
		(start 76.7305 89.968)
		(end 76.7305 90.485754)
		(width 0.125)
		(layer "In2.Cu")
		(net 88)
	)
	(segment
		(start 65.9 112.4125)
		(end 66.074999 112.587499)
		(width 0.125)
		(layer "In2.Cu")
		(net 88)
	)
	(segment
		(start 77.556 89.5875)
		(end 77.69 89.5875)
		(width 0.125)
		(layer "In2.Cu")
		(net 88)
	)
	(segment
		(start 66.786592 112.447499)
		(end 66.786592 112.420945)
		(width 0.125)
		(layer "In2.Cu")
		(net 88)
	)
	(segment
		(start 104.6466 86.9875)
		(end 105.5466 87.8875)
		(width 0.125)
		(layer "In2.Cu")
		(net 88)
	)
	(segment
		(start 90.105962 88.654428)
		(end 90.375769 88.924235)
		(width 0.125)
		(layer "In2.Cu")
		(net 88)
	)
	(segment
		(start 97.4726 88.037053)
		(end 97.6066 88.037053)
		(width 0.125)
		(layer "In2.Cu")
		(net 88)
	)
	(segment
		(start 94.1226 85.937923)
		(end 94.2566 85.937923)
		(width 0.125)
		(layer "In2.Cu")
		(net 88)
	)
	(segment
		(start 66.926592 112.280945)
		(end 66.996592 112.280945)
		(width 0.125)
		(layer "In2.Cu")
		(net 88)
	)
	(segment
		(start 94.6371 86.318423)
		(end 94.6371 87.831571)
		(width 0.125)
		(layer "In2.Cu")
		(net 88)
	)
	(segment
		(start 90.420616 87.801648)
		(end 90.51537 87.706895)
		(width 0.125)
		(layer "In2.Cu")
		(net 88)
	)
	(segment
		(start 125.2534 87.0875)
		(end 125.468031 86.872869)
		(width 0.125)
		(layer "In2.Cu")
		(net 88)
	)
	(segment
		(start 90.690429 88.609568)
		(end 90.690429 88.609572)
		(width 0.125)
		(layer "In2.Cu")
		(net 88)
	)
	(segment
		(start 105.5466 87.8875)
		(end 107.7534 87.8875)
		(width 0.125)
		(layer "In2.Cu")
		(net 88)
	)
	(segment
		(start 72.4875 112.0534)
		(end 72.4875 90.1534)
		(width 0.125)
		(layer "In2.Cu")
		(net 88)
	)
	(segment
		(start 80.99275 89.5875)
		(end 89.553401 89.587501)
		(width 0.125)
		(layer "In2.Cu")
		(net 88)
	)
	(segment
		(start 95.9771 86.8838)
		(end 95.9771 87.78156)
		(width 0.125)
		(layer "In2.Cu")
		(net 88)
	)
	(segment
		(start 80.32275 90.237053)
		(end 80.45675 90.237053)
		(width 0.125)
		(layer "In2.Cu")
		(net 88)
	)
	(segment
		(start 80.61225 90.081553)
		(end 80.61225 89.968)
		(width 0.125)
		(layer "In2.Cu")
		(net 88)
	)
	(segment
		(start 90.690429 88.609568)
		(end 91.243088 89.162227)
		(width 0.125)
		(layer "In2.Cu")
		(net 88)
	)
	(segment
		(start 94.7926 87.987071)
		(end 94.9266 87.987071)
		(width 0.125)
		(layer "In2.Cu")
		(net 88)
	)
	(segment
		(start 108.5534 87.0875)
		(end 125.2534 87.0875)
		(width 0.125)
		(layer "In2.Cu")
		(net 88)
	)
	(segment
		(start 95.0821 87.831571)
		(end 95.0821 86.8838)
		(width 0.125)
		(layer "In2.Cu")
		(net 88)
	)
	(segment
		(start 96.1326 87.93706)
		(end 96.2666 87.93706)
		(width 0.125)
		(layer "In2.Cu")
		(net 88)
	)
	(segment
		(start 91.148335 89.476891)
		(end 91.243088 89.382137)
		(width 0.125)
		(layer "In2.Cu")
		(net 88)
	)
	(segment
		(start 66.074999 112.587499)
		(end 66.646592 112.587499)
		(width 0.125)
		(layer "In2.Cu")
		(net 88)
	)
	(segment
		(start 92.4021 86.832)
		(end 92.4021 86.318447)
		(width 0.125)
		(layer "In2.Cu")
		(net 88)
	)
	(segment
		(start 73.0534 89.5875)
		(end 76.35 89.5875)
		(width 0.125)
		(layer "In2.Cu")
		(net 88)
	)
	(segment
		(start 93.4526 88.037053)
		(end 93.5866 88.037053)
		(width 0.125)
		(layer "In2.Cu")
		(net 88)
	)
	(segment
		(start 96.8026 86.9875)
		(end 96.9366 86.9875)
		(width 0.125)
		(layer "In2.Cu")
		(net 88)
	)
	(segment
		(start 99.1021 87.881577)
		(end 99.1021 87.368)
		(width 0.125)
		(layer "In2.Cu")
		(net 88)
	)
	(arc
		(start 66.786592 112.420945)
		(mid 66.827597 112.32195)
		(end 66.926592 112.280945)
		(width 0.125)
		(layer "In2.Cu")
		(net 88)
	)
	(arc
		(start 76.35 89.5875)
		(mid 76.619054 89.698946)
		(end 76.7305 89.968)
		(width 0.125)
		(layer "In2.Cu")
		(net 88)
	)
	(arc
		(start 80.61225 89.968)
		(mid 80.723696 89.698946)
		(end 80.99275 89.5875)
		(width 0.125)
		(layer "In2.Cu")
		(net 88)
	)
	(arc
		(start 77.69 89.5875)
		(mid 77.799955 89.541955)
		(end 77.8455 89.432)
		(width 0.125)
		(layer "In2.Cu")
		(net 88)
	)
	(arc
		(start 89.567854 88.654428)
		(mid 89.836908 88.542982)
		(end 90.105962 88.654428)
		(width 0.125)
		(layer "In2.Cu")
		(net 88)
	)
	(arc
		(start 94.9266 87.987071)
		(mid 95.036555 87.941526)
		(end 95.0821 87.831571)
		(width 0.125)
		(layer "In2.Cu")
		(net 88)
	)
	(arc
		(start 92.2466 86.9875)
		(mid 92.356555 86.941955)
		(end 92.4021 86.832)
		(width 0.125)
		(layer "In2.Cu")
		(net 88)
	)
	(arc
		(start 98.6571 87.881577)
		(mid 98.702645 87.991532)
		(end 98.8126 88.037077)
		(width 0.125)
		(layer "In2.Cu")
		(net 88)
	)
	(arc
		(start 79.1855 89.875)
		(mid 79.269707 89.671707)
		(end 79.473 89.5875)
		(width 0.125)
		(layer "In2.Cu")
		(net 88)
	)
	(arc
		(start 97.3171 87.881553)
		(mid 97.362645 87.991508)
		(end 97.4726 88.037053)
		(width 0.125)
		(layer "In2.Cu")
		(net 88)
	)
	(arc
		(start 96.9366 86.9875)
		(mid 97.205654 87.098946)
		(end 97.3171 87.368)
		(width 0.125)
		(layer "In2.Cu")
		(net 88)
	)
	(arc
		(start 93.5866 88.037053)
		(mid 93.696555 87.991508)
		(end 93.7421 87.881553)
		(width 0.125)
		(layer "In2.Cu")
		(net 88)
	)
	(arc
		(start 77.1755 89.968)
		(mid 77.286946 89.698946)
		(end 77.556 89.5875)
		(width 0.125)
		(layer "In2.Cu")
		(net 88)
	)
	(arc
		(start 93.7421 86.318423)
		(mid 93.853546 86.049369)
		(end 94.1226 85.937923)
		(width 0.125)
		(layer "In2.Cu")
		(net 88)
	)
	(arc
		(start 76.7305 90.485754)
		(mid 76.776045 90.595709)
		(end 76.886 90.641254)
		(width 0.125)
		(layer "In2.Cu")
		(net 88)
	)
	(arc
		(start 94.6371 87.831571)
		(mid 94.682645 87.941526)
		(end 94.7926 87.987071)
		(width 0.125)
		(layer "In2.Cu")
		(net 88)
	)
	(arc
		(start 77.8455 89.214246)
		(mid 77.956946 88.945192)
		(end 78.226 88.833746)
		(width 0.125)
		(layer "In2.Cu")
		(net 88)
	)
	(arc
		(start 78.36 88.833746)
		(mid 78.629054 88.945192)
		(end 78.7405 89.214246)
		(width 0.125)
		(layer "In2.Cu")
		(net 88)
	)
	(arc
		(start 95.0821 86.8838)
		(mid 95.178374 86.651375)
		(end 95.410799 86.555101)
		(width 0.125)
		(layer "In2.Cu")
		(net 88)
	)
	(arc
		(start 97.6066 88.037053)
		(mid 97.716555 87.991508)
		(end 97.7621 87.881553)
		(width 0.125)
		(layer "In2.Cu")
		(net 88)
	)
	(arc
		(start 99.1021 87.368)
		(mid 99.213546 87.098946)
		(end 99.4826 86.9875)
		(width 0.125)
		(layer "In2.Cu")
		(net 88)
	)
	(arc
		(start 79.123 89.9375)
		(mid 79.167194 89.919194)
		(end 79.1855 89.875)
		(width 0.125)
		(layer "In2.Cu")
		(net 88)
	)
	(arc
		(start 80.16725 90.081553)
		(mid 80.212795 90.191508)
		(end 80.32275 90.237053)
		(width 0.125)
		(layer "In2.Cu")
		(net 88)
	)
	(arc
		(start 89.4731 89.28729)
		(mid 89.361655 89.018234)
		(end 89.473101 88.74918)
		(width 0.125)
		(layer "In2.Cu")
		(net 88)
	)
	(arc
		(start 91.243088 89.382137)
		(mid 91.288633 89.272182)
		(end 91.243088 89.162227)
		(width 0.125)
		(layer "In2.Cu")
		(net 88)
	)
	(arc
		(start 78.7405 89.875)
		(mid 78.758806 89.919194)
		(end 78.803 89.9375)
		(width 0.125)
		(layer "In2.Cu")
		(net 88)
	)
	(arc
		(start 79.78675 89.5875)
		(mid 80.055804 89.698946)
		(end 80.16725 89.968)
		(width 0.125)
		(layer "In2.Cu")
		(net 88)
	)
	(arc
		(start 92.4021 86.318447)
		(mid 92.513546 86.049393)
		(end 92.7826 85.937947)
		(width 0.125)
		(layer "In2.Cu")
		(net 88)
	)
	(arc
		(start 98.2766 86.9875)
		(mid 98.545654 87.098946)
		(end 98.6571 87.368)
		(width 0.125)
		(layer "In2.Cu")
		(net 88)
	)
	(arc
		(start 97.7621 87.368)
		(mid 97.873546 87.098946)
		(end 98.1426 86.9875)
		(width 0.125)
		(layer "In2.Cu")
		(net 88)
	)
	(arc
		(start 90.420615 88.339758)
		(mid 90.30917 88.070702)
		(end 90.420616 87.801648)
		(width 0.125)
		(layer "In2.Cu")
		(net 88)
	)
	(arc
		(start 91.133788 87.787205)
		(mid 91.243743 87.83275)
		(end 91.353698 87.787205)
		(width 0.125)
		(layer "In2.Cu")
		(net 88)
	)
	(arc
		(start 67.136592 112.447499)
		(mid 67.177597 112.546494)
		(end 67.276592 112.587499)
		(width 0.125)
		(layer "In2.Cu")
		(net 88)
	)
	(arc
		(start 77.02 90.641254)
		(mid 77.129955 90.595709)
		(end 77.1755 90.485754)
		(width 0.125)
		(layer "In2.Cu")
		(net 88)
	)
	(arc
		(start 66.996592 112.280945)
		(mid 67.095587 112.32195)
		(end 67.136592 112.420945)
		(width 0.125)
		(layer "In2.Cu")
		(net 88)
	)
	(arc
		(start 89.553401 89.587501)
		(mid 89.598946 89.477546)
		(end 89.553401 89.367591)
		(width 0.125)
		(layer "In2.Cu")
		(net 88)
	)
	(arc
		(start 90.928424 89.476891)
		(mid 91.03838 89.522436)
		(end 91.148335 89.476891)
		(width 0.125)
		(layer "In2.Cu")
		(net 88)
	)
	(arc
		(start 90.51537 87.706895)
		(mid 90.784424 87.595449)
		(end 91.053478 87.706895)
		(width 0.125)
		(layer "In2.Cu")
		(net 88)
	)
	(arc
		(start 93.2971 87.881553)
		(mid 93.342645 87.991508)
		(end 93.4526 88.037053)
		(width 0.125)
		(layer "In2.Cu")
		(net 88)
	)
	(arc
		(start 96.4221 87.368)
		(mid 96.533546 87.098946)
		(end 96.8026 86.9875)
		(width 0.125)
		(layer "In2.Cu")
		(net 88)
	)
	(arc
		(start 94.2566 85.937923)
		(mid 94.525654 86.049369)
		(end 94.6371 86.318423)
		(width 0.125)
		(layer "In2.Cu")
		(net 88)
	)
	(arc
		(start 96.2666 87.93706)
		(mid 96.376555 87.891515)
		(end 96.4221 87.78156)
		(width 0.125)
		(layer "In2.Cu")
		(net 88)
	)
	(arc
		(start 98.9466 88.037077)
		(mid 99.056555 87.991532)
		(end 99.1021 87.881577)
		(width 0.125)
		(layer "In2.Cu")
		(net 88)
	)
	(arc
		(start 92.9166 85.937947)
		(mid 93.185654 86.049393)
		(end 93.2971 86.318447)
		(width 0.125)
		(layer "In2.Cu")
		(net 88)
	)
	(arc
		(start 95.648401 86.555101)
		(mid 95.880826 86.651375)
		(end 95.9771 86.8838)
		(width 0.125)
		(layer "In2.Cu")
		(net 88)
	)
	(arc
		(start 80.45675 90.237053)
		(mid 80.566705 90.191508)
		(end 80.61225 90.081553)
		(width 0.125)
		(layer "In2.Cu")
		(net 88)
	)
	(arc
		(start 66.646592 112.587499)
		(mid 66.745587 112.546494)
		(end 66.786592 112.447499)
		(width 0.125)
		(layer "In2.Cu")
		(net 88)
	)
	(arc
		(start 95.9771 87.78156)
		(mid 96.022645 87.891515)
		(end 96.1326 87.93706)
		(width 0.125)
		(layer "In2.Cu")
		(net 88)
	)
	(segment
		(start 126.030532 82.65)
		(end 125.755532 82.925)
		(width 0.17)
		(layer "F.Cu")
		(net 89)
	)
	(segment
		(start 125.755532 83.075)
		(end 125.880532 83.2)
		(width 0.17)
		(layer "F.Cu")
		(net 89)
	)
	(segment
		(start 125.755532 82.925)
		(end 125.755532 83.075)
		(width 0.17)
		(layer "F.Cu")
		(net 89)
	)
	(via
		(at 63.3 113.4125)
		(size 0.45)
		(drill 0.1)
		(layers "F.Cu" "B.Cu")
		(net 89)
	)
	(via
		(at 125.880532 83.2)
		(size 0.45)
		(drill 0.1)
		(layers "F.Cu" "B.Cu")
		(net 89)
	)
	(segment
		(start 64.14 113.46)
		(end 64.065 113.535)
		(width 0.17)
		(layer "B.Cu")
		(net 89)
	)
	(segment
		(start 63.4125 113.525)
		(end 63.3 113.4125)
		(width 0.17)
		(layer "B.Cu")
		(net 89)
	)
	(segment
		(start 64.065 113.535)
		(end 63.7 113.535)
		(width 0.17)
		(layer "B.Cu")
		(net 89)
	)
	(segment
		(start 63.69 113.525)
		(end 63.4125 113.525)
		(width 0.17)
		(layer "B.Cu")
		(net 89)
	)
	(segment
		(start 63.7 113.535)
		(end 63.69 113.525)
		(width 0.17)
		(layer "B.Cu")
		(net 89)
	)
	(segment
		(start 64.59 113.46)
		(end 64.14 113.46)
		(width 0.17)
		(layer "B.Cu")
		(net 89)
	)
	(segment
		(start 93.77 84.501748)
		(end 93.89 84.501748)
		(width 0.125)
		(layer "In2.Cu")
		(net 89)
	)
	(segment
		(start 97.8425 84.247646)
		(end 97.8425 83.225)
		(width 0.125)
		(layer "In2.Cu")
		(net 89)
	)
	(segment
		(start 100.07625 83.64)
		(end 100.07625 84.2449)
		(width 0.125)
		(layer "In2.Cu")
		(net 89)
	)
	(segment
		(start 109.6534 84.6125)
		(end 109.9534 84.9125)
		(width 0.125)
		(layer "In2.Cu")
		(net 89)
	)
	(segment
		(start 101.512776 83.876526)
		(end 101.74875 83.876526)
		(width 0.125)
		(layer "In2.Cu")
		(net 89)
	)
	(segment
		(start 87.3466 87.3125)
		(end 91.1466 83.5125)
		(width 0.125)
		(layer "In2.Cu")
		(net 89)
	)
	(segment
		(start 97.0175 83.18457)
		(end 97.0175 84.247646)
		(width 0.125)
		(layer "In2.Cu")
		(net 89)
	)
	(segment
		(start 93.4175 83.64)
		(end 93.4175 84.149248)
		(width 0.125)
		(layer "In2.Cu")
		(net 89)
	)
	(segment
		(start 62.4466 110.1125)
		(end 69.7466 110.1125)
		(width 0.125)
		(layer "In2.Cu")
		(net 89)
	)
	(segment
		(start 104.931757 85.320314)
		(end 105.123943 85.320314)
		(width 0.125)
		(layer "In2.Cu")
		(net 89)
	)
	(segment
		(start 96.745429 83.081641)
		(end 96.914571 83.081641)
		(width 0.125)
		(layer "In2.Cu")
		(net 89)
	)
	(segment
		(start 99.10125 83.16)
		(end 99.10125 82.955113)
		(width 0.125)
		(layer "In2.Cu")
		(net 89)
	)
	(segment
		(start 62.440931 112.649369)
		(end 62.490428 112.698866)
		(width 0.125)
		(layer "In2.Cu")
		(net 89)
	)
	(segment
		(start 62.472187 113.113088)
		(end 62.946599 113.587499)
		(width 0.125)
		(layer "In2.Cu")
		(net 89)
	)
	(segment
		(start 62.026711 112.667611)
		(end 61.8125 112.4534)
		(width 0.125)
		(layer "In2.Cu")
		(net 89)
	)
	(segment
		(start 100.42875 84.5974)
		(end 100.54875 84.5974)
		(width 0.125)
		(layer "In2.Cu")
		(net 89)
	)
	(segment
		(start 105.531757 84.9125)
		(end 107.8466 84.9125)
		(width 0.125)
		(layer "In2.Cu")
		(net 89)
	)
	(segment
		(start 98.505 83.5125)
		(end 98.74875 83.5125)
		(width 0.125)
		(layer "In2.Cu")
		(net 89)
	)
	(segment
		(start 109.9534 84.9125)
		(end 125.5466 84.9125)
		(width 0.125)
		(layer "In2.Cu")
		(net 89)
	)
	(segment
		(start 94.84 83.8625)
		(end 95.09 83.8625)
		(width 0.125)
		(layer "In2.Cu")
		(net 89)
	)
	(segment
		(start 104.36785 84.037116)
		(end 104.48785 84.037116)
		(width 0.125)
		(layer "In2.Cu")
		(net 89)
	)
	(segment
		(start 102.112776 83.5125)
		(end 102.4534 83.5125)
		(width 0.125)
		(layer "In2.Cu")
		(net 89)
	)
	(segment
		(start 107.8466 84.9125)
		(end 108.1466 84.6125)
		(width 0.125)
		(layer "In2.Cu")
		(net 89)
	)
	(segment
		(start 94.2425 84.149248)
		(end 94.2425 83.64)
		(width 0.125)
		(layer "In2.Cu")
		(net 89)
	)
	(segment
		(start 125.693033 83.433933)
		(end 125.693033 83.387499)
		(width 0.125)
		(layer "In2.Cu")
		(net 89)
	)
	(segment
		(start 103.2534 84.9125)
		(end 103.3466 84.9125)
		(width 0.125)
		(layer "In2.Cu")
		(net 89)
	)
	(segment
		(start 91.1466 83.5125)
		(end 93.29 83.5125)
		(width 0.125)
		(layer "In2.Cu")
		(net 89)
	)
	(segment
		(start 126.0125 84.4466)
		(end 126.0125 83.7534)
		(width 0.125)
		(layer "In2.Cu")
		(net 89)
	)
	(segment
		(start 102.6875 84.3466)
		(end 103.2534 84.9125)
		(width 0.125)
		(layer "In2.Cu")
		(net 89)
	)
	(segment
		(start 94.37 83.5125)
		(end 94.49 83.5125)
		(width 0.125)
		(layer "In2.Cu")
		(net 89)
	)
	(segment
		(start 104.24035 84.975)
		(end 104.24035 84.164616)
		(width 0.125)
		(layer "In2.Cu")
		(net 89)
	)
	(segment
		(start 70.1125 109.7466)
		(end 70.1125 87.8466)
		(width 0.125)
		(layer "In2.Cu")
		(net 89)
	)
	(segment
		(start 104.61535 84.164616)
		(end 104.61535 85.003907)
		(width 0.125)
		(layer "In2.Cu")
		(net 89)
	)
	(segment
		(start 99.82875 83.5125)
		(end 99.94875 83.5125)
		(width 0.125)
		(layer "In2.Cu")
		(net 89)
	)
	(segment
		(start 96.6425 83.747633)
		(end 96.6425 83.18457)
		(width 0.125)
		(layer "In2.Cu")
		(net 89)
	)
	(segment
		(start 95.8175 83.64)
		(end 95.8175 83.747633)
		(width 0.125)
		(layer "In2.Cu")
		(net 89)
	)
	(segment
		(start 100.90125 84.2449)
		(end 100.90125 83.64)
		(width 0.125)
		(layer "In2.Cu")
		(net 89)
	)
	(segment
		(start 96.17 84.100133)
		(end 96.29 84.100133)
		(width 0.125)
		(layer "In2.Cu")
		(net 89)
	)
	(segment
		(start 97.905 83.1625)
		(end 98.155 83.1625)
		(width 0.125)
		(layer "In2.Cu")
		(net 89)
	)
	(segment
		(start 99.22875 82.827613)
		(end 99.34875 82.827613)
		(width 0.125)
		(layer "In2.Cu")
		(net 89)
	)
	(segment
		(start 102.4534 83.5125)
		(end 102.6875 83.7466)
		(width 0.125)
		(layer "In2.Cu")
		(net 89)
	)
	(segment
		(start 62.946599 113.587499)
		(end 63.125001 113.587499)
		(width 0.125)
		(layer "In2.Cu")
		(net 89)
	)
	(segment
		(start 125.693033 83.387499)
		(end 125.880532 83.2)
		(width 0.125)
		(layer "In2.Cu")
		(net 89)
	)
	(segment
		(start 101.02875 83.5125)
		(end 101.14875 83.5125)
		(width 0.125)
		(layer "In2.Cu")
		(net 89)
	)
	(segment
		(start 108.1466 84.6125)
		(end 109.6534 84.6125)
		(width 0.125)
		(layer "In2.Cu")
		(net 89)
	)
	(segment
		(start 63.125001 113.587499)
		(end 63.3 113.4125)
		(width 0.125)
		(layer "In2.Cu")
		(net 89)
	)
	(segment
		(start 99.47625 82.955113)
		(end 99.47625 83.16)
		(width 0.125)
		(layer "In2.Cu")
		(net 89)
	)
	(segment
		(start 62.224701 112.667612)
		(end 62.242941 112.649369)
		(width 0.125)
		(layer "In2.Cu")
		(net 89)
	)
	(segment
		(start 70.6466 87.3125)
		(end 87.3466 87.3125)
		(width 0.125)
		(layer "In2.Cu")
		(net 89)
	)
	(segment
		(start 62.490428 112.896856)
		(end 62.472187 112.915098)
		(width 0.125)
		(layer "In2.Cu")
		(net 89)
	)
	(segment
		(start 70.1125 87.8466)
		(end 70.6466 87.3125)
		(width 0.125)
		(layer "In2.Cu")
		(net 89)
	)
	(segment
		(start 103.6966 85.2625)
		(end 103.95285 85.2625)
		(width 0.125)
		(layer "In2.Cu")
		(net 89)
	)
	(segment
		(start 126.0125 83.7534)
		(end 125.693033 83.433933)
		(width 0.125)
		(layer "In2.Cu")
		(net 89)
	)
	(segment
		(start 61.8125 110.7466)
		(end 62.4466 110.1125)
		(width 0.125)
		(layer "In2.Cu")
		(net 89)
	)
	(segment
		(start 61.8125 112.4534)
		(end 61.8125 110.7466)
		(width 0.125)
		(layer "In2.Cu")
		(net 89)
	)
	(segment
		(start 125.5466 84.9125)
		(end 126.0125 84.4466)
		(width 0.125)
		(layer "In2.Cu")
		(net 89)
	)
	(segment
		(start 69.7466 110.1125)
		(end 70.1125 109.7466)
		(width 0.125)
		(layer "In2.Cu")
		(net 89)
	)
	(segment
		(start 95.44 83.5125)
		(end 95.69 83.5125)
		(width 0.125)
		(layer "In2.Cu")
		(net 89)
	)
	(segment
		(start 102.6875 83.7466)
		(end 102.6875 84.3466)
		(width 0.125)
		(layer "In2.Cu")
		(net 89)
	)
	(segment
		(start 97.37 84.600146)
		(end 97.49 84.600146)
		(width 0.125)
		(layer "In2.Cu")
		(net 89)
	)
	(arc
		(start 101.218263 83.582013)
		(mid 101.304524 83.790265)
		(end 101.512776 83.876526)
		(width 0.125)
		(layer "In2.Cu")
		(net 89)
	)
	(arc
		(start 101.74875 83.876526)
		(mid 101.957002 83.790265)
		(end 102.043263 83.582013)
		(width 0.125)
		(layer "In2.Cu")
		(net 89)
	)
	(arc
		(start 94.49 83.5125)
		(mid 94.534194 83.530806)
		(end 94.5525 83.575)
		(width 0.125)
		(layer "In2.Cu")
		(net 89)
	)
	(arc
		(start 103.3466 84.9125)
		(mid 103.390794 84.930806)
		(end 103.4091 84.975)
		(width 0.125)
		(layer "In2.Cu")
		(net 89)
	)
	(arc
		(start 93.89 84.501748)
		(mid 94.139255 84.398503)
		(end 94.2425 84.149248)
		(width 0.125)
		(layer "In2.Cu")
		(net 89)
	)
	(arc
		(start 101.14875 83.5125)
		(mid 101.197903 83.53286)
		(end 101.218263 83.582013)
		(width 0.125)
		(layer "In2.Cu")
		(net 89)
	)
	(arc
		(start 93.4175 84.149248)
		(mid 93.520745 84.398503)
		(end 93.77 84.501748)
		(width 0.125)
		(layer "In2.Cu")
		(net 89)
	)
	(arc
		(start 62.242941 112.649369)
		(mid 62.341936 112.608364)
		(end 62.440931 112.649369)
		(width 0.125)
		(layer "In2.Cu")
		(net 89)
	)
	(arc
		(start 95.09 83.8625)
		(mid 95.293293 83.778293)
		(end 95.3775 83.575)
		(width 0.125)
		(layer "In2.Cu")
		(net 89)
	)
	(arc
		(start 99.47625 83.16)
		(mid 99.579495 83.409255)
		(end 99.82875 83.5125)
		(width 0.125)
		(layer "In2.Cu")
		(net 89)
	)
	(arc
		(start 98.155 83.1625)
		(mid 98.199194 83.180806)
		(end 98.2175 83.225)
		(width 0.125)
		(layer "In2.Cu")
		(net 89)
	)
	(arc
		(start 93.29 83.5125)
		(mid 93.380156 83.549844)
		(end 93.4175 83.64)
		(width 0.125)
		(layer "In2.Cu")
		(net 89)
	)
	(arc
		(start 99.10125 82.955113)
		(mid 99.138594 82.864957)
		(end 99.22875 82.827613)
		(width 0.125)
		(layer "In2.Cu")
		(net 89)
	)
	(arc
		(start 97.49 84.600146)
		(mid 97.739255 84.496901)
		(end 97.8425 84.247646)
		(width 0.125)
		(layer "In2.Cu")
		(net 89)
	)
	(arc
		(start 100.90125 83.64)
		(mid 100.938594 83.549844)
		(end 101.02875 83.5125)
		(width 0.125)
		(layer "In2.Cu")
		(net 89)
	)
	(arc
		(start 94.2425 83.64)
		(mid 94.279844 83.549844)
		(end 94.37 83.5125)
		(width 0.125)
		(layer "In2.Cu")
		(net 89)
	)
	(arc
		(start 95.3775 83.575)
		(mid 95.395806 83.530806)
		(end 95.44 83.5125)
		(width 0.125)
		(layer "In2.Cu")
		(net 89)
	)
	(arc
		(start 62.026711 112.667611)
		(mid 62.125707 112.708616)
		(end 62.224701 112.667612)
		(width 0.125)
		(layer "In2.Cu")
		(net 89)
	)
	(arc
		(start 104.24035 84.164616)
		(mid 104.277694 84.07446)
		(end 104.36785 84.037116)
		(width 0.125)
		(layer "In2.Cu")
		(net 89)
	)
	(arc
		(start 96.914571 83.081641)
		(mid 96.987353 83.111788)
		(end 97.0175 83.18457)
		(width 0.125)
		(layer "In2.Cu")
		(net 89)
	)
	(arc
		(start 62.472187 112.915098)
		(mid 62.431182 113.014093)
		(end 62.472187 113.113088)
		(width 0.125)
		(layer "In2.Cu")
		(net 89)
	)
	(arc
		(start 94.5525 83.575)
		(mid 94.636707 83.778293)
		(end 94.84 83.8625)
		(width 0.125)
		(layer "In2.Cu")
		(net 89)
	)
	(arc
		(start 95.8175 83.747633)
		(mid 95.920745 83.996888)
		(end 96.17 84.100133)
		(width 0.125)
		(layer "In2.Cu")
		(net 89)
	)
	(arc
		(start 100.07625 84.2449)
		(mid 100.179495 84.494155)
		(end 100.42875 84.5974)
		(width 0.125)
		(layer "In2.Cu")
		(net 89)
	)
	(arc
		(start 98.74875 83.5125)
		(mid 98.998005 83.409255)
		(end 99.10125 83.16)
		(width 0.125)
		(layer "In2.Cu")
		(net 89)
	)
	(arc
		(start 62.490428 112.698866)
		(mid 62.531433 112.797861)
		(end 62.490428 112.896856)
		(width 0.125)
		(layer "In2.Cu")
		(net 89)
	)
	(arc
		(start 104.61535 85.003907)
		(mid 104.708023 85.227641)
		(end 104.931757 85.320314)
		(width 0.125)
		(layer "In2.Cu")
		(net 89)
	)
	(arc
		(start 97.0175 84.247646)
		(mid 97.120745 84.496901)
		(end 97.37 84.600146)
		(width 0.125)
		(layer "In2.Cu")
		(net 89)
	)
	(arc
		(start 103.4091 84.975)
		(mid 103.493307 85.178293)
		(end 103.6966 85.2625)
		(width 0.125)
		(layer "In2.Cu")
		(net 89)
	)
	(arc
		(start 99.34875 82.827613)
		(mid 99.438906 82.864957)
		(end 99.47625 82.955113)
		(width 0.125)
		(layer "In2.Cu")
		(net 89)
	)
	(arc
		(start 95.69 83.5125)
		(mid 95.780156 83.549844)
		(end 95.8175 83.64)
		(width 0.125)
		(layer "In2.Cu")
		(net 89)
	)
	(arc
		(start 103.95285 85.2625)
		(mid 104.156143 85.178293)
		(end 104.24035 84.975)
		(width 0.125)
		(layer "In2.Cu")
		(net 89)
	)
	(arc
		(start 104.48785 84.037116)
		(mid 104.578006 84.07446)
		(end 104.61535 84.164616)
		(width 0.125)
		(layer "In2.Cu")
		(net 89)
	)
	(arc
		(start 96.6425 83.18457)
		(mid 96.672647 83.111788)
		(end 96.745429 83.081641)
		(width 0.125)
		(layer "In2.Cu")
		(net 89)
	)
	(arc
		(start 105.44035 85.003907)
		(mid 105.467122 84.939272)
		(end 105.531757 84.9125)
		(width 0.125)
		(layer "In2.Cu")
		(net 89)
	)
	(arc
		(start 100.54875 84.5974)
		(mid 100.798005 84.494155)
		(end 100.90125 84.2449)
		(width 0.125)
		(layer "In2.Cu")
		(net 89)
	)
	(arc
		(start 97.8425 83.225)
		(mid 97.860806 83.180806)
		(end 97.905 83.1625)
		(width 0.125)
		(layer "In2.Cu")
		(net 89)
	)
	(arc
		(start 96.29 84.100133)
		(mid 96.539255 83.996888)
		(end 96.6425 83.747633)
		(width 0.125)
		(layer "In2.Cu")
		(net 89)
	)
	(arc
		(start 102.043263 83.582013)
		(mid 102.063623 83.53286)
		(end 102.112776 83.5125)
		(width 0.125)
		(layer "In2.Cu")
		(net 89)
	)
	(arc
		(start 99.94875 83.5125)
		(mid 100.038906 83.549844)
		(end 100.07625 83.64)
		(width 0.125)
		(layer "In2.Cu")
		(net 89)
	)
	(arc
		(start 98.2175 83.225)
		(mid 98.301707 83.428293)
		(end 98.505 83.5125)
		(width 0.125)
		(layer "In2.Cu")
		(net 89)
	)
	(arc
		(start 105.123943 85.320314)
		(mid 105.347677 85.227641)
		(end 105.44035 85.003907)
		(width 0.125)
		(layer "In2.Cu")
		(net 89)
	)
	(segment
		(start 141.1 113.1)
		(end 141.9 113.1)
		(width 0.1)
		(layer "F.Cu")
		(net 90)
	)
	(segment
		(start 140.7 112.2)
		(end 140.7 112.7)
		(width 0.1)
		(layer "F.Cu")
		(net 90)
	)
	(segment
		(start 140.7 112.7)
		(end 141.1 113.1)
		(width 0.1)
		(layer "F.Cu")
		(net 90)
	)
	(via
		(at 141.9 113.1)
		(size 0.45)
		(drill 0.1)
		(layers "F.Cu" "B.Cu")
		(net 90)
	)
	(via
		(at 148 69.6)
		(size 0.45)
		(drill 0.1)
		(layers "F.Cu" "B.Cu")
		(net 90)
	)
	(segment
		(start 148 69.6)
		(end 147.9 69.6)
		(width 0.1)
		(layer "B.Cu")
		(net 90)
	)
	(segment
		(start 142.225 67)
		(end 145.8 67)
		(width 0.1)
		(layer "B.Cu")
		(net 90)
	)
	(segment
		(start 139.475 64.775)
		(end 139.475 64.665)
		(width 0.1)
		(layer "B.Cu")
		(net 90)
	)
	(segment
		(start 144.554 64.674)
		(end 144.6 64.72)
		(width 0.1)
		(layer "B.Cu")
		(net 90)
	)
	(segment
		(start 139.475 64.775)
		(end 141.2 66.5)
		(width 0.1)
		(layer "B.Cu")
		(net 90)
	)
	(segment
		(start 136.8 64.72)
		(end 136.8 63.625)
		(width 0.1)
		(layer "B.Cu")
		(net 90)
	)
	(segment
		(start 144.554 63.379)
		(end 144.554 64.674)
		(width 0.1)
		(layer "B.Cu")
		(net 90)
	)
	(segment
		(start 139.42 64.72)
		(end 139.475 64.775)
		(width 0.1)
		(layer "B.Cu")
		(net 90)
	)
	(segment
		(start 139.42 64.72)
		(end 139.475 64.665)
		(width 0.1)
		(layer "B.Cu")
		(net 90)
	)
	(segment
		(start 145.8 67)
		(end 146.5 67)
		(width 0.1)
		(layer "B.Cu")
		(net 90)
	)
	(segment
		(start 141.2 66.5)
		(end 141.725 66.5)
		(width 0.1)
		(layer "B.Cu")
		(net 90)
	)
	(segment
		(start 146.5 67)
		(end 147.1 66.4)
		(width 0.1)
		(layer "B.Cu")
		(net 90)
	)
	(segment
		(start 140.2 63.94)
		(end 140.2 63.8)
		(width 0.1)
		(layer "B.Cu")
		(net 90)
	)
	(segment
		(start 147.9 69.6)
		(end 145.8 67.5)
		(width 0.1)
		(layer "B.Cu")
		(net 90)
	)
	(segment
		(start 137.8 64.72)
		(end 139.42 64.72)
		(width 0.1)
		(layer "B.Cu")
		(net 90)
	)
	(segment
		(start 139.475 64.665)
		(end 140.2 63.94)
		(width 0.1)
		(layer "B.Cu")
		(net 90)
	)
	(segment
		(start 146.72 64.72)
		(end 145.6 64.72)
		(width 0.1)
		(layer "B.Cu")
		(net 90)
	)
	(segment
		(start 144.6 64.72)
		(end 145.6 64.72)
		(width 0.1)
		(layer "B.Cu")
		(net 90)
	)
	(segment
		(start 147.1 65.1)
		(end 146.72 64.72)
		(width 0.1)
		(layer "B.Cu")
		(net 90)
	)
	(segment
		(start 147.1 66.4)
		(end 147.1 65.1)
		(width 0.1)
		(layer "B.Cu")
		(net 90)
	)
	(segment
		(start 141.725 66.5)
		(end 142.225 67)
		(width 0.1)
		(layer "B.Cu")
		(net 90)
	)
	(segment
		(start 145.8 67.5)
		(end 145.8 67)
		(width 0.1)
		(layer "B.Cu")
		(net 90)
	)
	(segment
		(start 136.8 64.72)
		(end 137.8 64.72)
		(width 0.1)
		(layer "B.Cu")
		(net 90)
	)
	(segment
		(start 136.8 63.625)
		(end 136.554 63.379)
		(width 0.1)
		(layer "B.Cu")
		(net 90)
	)
	(segment
		(start 149.925 69.6)
		(end 151.6 71.275)
		(width 0.1)
		(layer "In5.Cu")
		(net 90)
	)
	(segment
		(start 144.9 89.95)
		(end 141.9 92.95)
		(width 0.1)
		(layer "In5.Cu")
		(net 90)
	)
	(segment
		(start 141.9 92.95)
		(end 141.9 113.1)
		(width 0.1)
		(layer "In5.Cu")
		(net 90)
	)
	(segment
		(start 144.9 89.4)
		(end 144.9 89.95)
		(width 0.1)
		(layer "In5.Cu")
		(net 90)
	)
	(segment
		(start 151.6 82.7)
		(end 144.9 89.4)
		(width 0.1)
		(layer "In5.Cu")
		(net 90)
	)
	(segment
		(start 148 69.6)
		(end 149.925 69.6)
		(width 0.1)
		(layer "In5.Cu")
		(net 90)
	)
	(segment
		(start 151.6 71.275)
		(end 151.6 82.7)
		(width 0.1)
		(layer "In5.Cu")
		(net 90)
	)
	(segment
		(start 222.785 132.138)
		(end 222.9 132.023)
		(width 0.19)
		(layer "F.Cu")
		(net 91)
	)
	(segment
		(start 219.305 131.8)
		(end 219.28 131.8)
		(width 0.19)
		(layer "F.Cu")
		(net 91)
	)
	(segment
		(start 221.652501 132.073)
		(end 221.717501 132.138)
		(width 0.19)
		(layer "F.Cu")
		(net 91)
	)
	(segment
		(start 220.468 132.073)
		(end 221.24 132.073)
		(width 0.19)
		(layer "F.Cu")
		(net 91)
	)
	(segment
		(start 230.865532 126.32)
		(end 230.865532 125.958408)
		(width 0.19)
		(layer "F.Cu")
		(net 91)
	)
	(segment
		(start 219.990499 132.138)
		(end 219.9 132.138)
		(width 0.19)
		(layer "F.Cu")
		(net 91)
	)
	(segment
		(start 221.24 132.073)
		(end 221.652501 132.073)
		(width 0.19)
		(layer "F.Cu")
		(net 91)
	)
	(segment
		(start 219.8895 132.1275)
		(end 219.6325 132.1275)
		(width 0.19)
		(layer "F.Cu")
		(net 91)
	)
	(segment
		(start 230.855 125.947876)
		(end 230.855 125.815)
		(width 0.19)
		(layer "F.Cu")
		(net 91)
	)
	(segment
		(start 230.930532 126.385)
		(end 230.865532 126.32)
		(width 0.19)
		(layer "F.Cu")
		(net 91)
	)
	(segment
		(start 219.9 132.138)
		(end 219.8895 132.1275)
		(width 0.19)
		(layer "F.Cu")
		(net 91)
	)
	(segment
		(start 230.930532 127.0725)
		(end 230.930532 126.385)
		(width 0.19)
		(layer "F.Cu")
		(net 91)
	)
	(segment
		(start 220.055499 132.073)
		(end 219.990499 132.138)
		(width 0.19)
		(layer "F.Cu")
		(net 91)
	)
	(segment
		(start 220.468 132.073)
		(end 220.055499 132.073)
		(width 0.19)
		(layer "F.Cu")
		(net 91)
	)
	(segment
		(start 219.6325 132.1275)
		(end 219.305 131.8)
		(width 0.19)
		(layer "F.Cu")
		(net 91)
	)
	(segment
		(start 221.717501 132.138)
		(end 222.785 132.138)
		(width 0.19)
		(layer "F.Cu")
		(net 91)
	)
	(segment
		(start 230.865532 125.958408)
		(end 230.855 125.947876)
		(width 0.19)
		(layer "F.Cu")
		(net 91)
	)
	(segment
		(start 230.855 125.815)
		(end 230.97 125.7)
		(width 0.19)
		(layer "F.Cu")
		(net 91)
	)
	(via
		(at 230.97 125.7)
		(size 0.45)
		(drill 0.1)
		(layers "F.Cu" "B.Cu")
		(net 91)
	)
	(via
		(at 222.9 132.023)
		(size 0.45)
		(drill 0.1)
		(layers "F.Cu" "B.Cu")
		(net 91)
	)
	(segment
		(start 223.524134 129.2375)
		(end 225.243044 129.2375)
		(width 0.15)
		(layer "In7.Cu")
		(net 91)
	)
	(segment
		(start 221.979956 132.1855)
		(end 221.7375 131.943044)
		(width 0.15)
		(layer "In7.Cu")
		(net 91)
	)
	(segment
		(start 223.384134 129.445549)
		(end 223.384134 129.3775)
		(width 0.15)
		(layer "In7.Cu")
		(net 91)
	)
	(segment
		(start 223.174134 129.585549)
		(end 223.244134 129.585549)
		(width 0.15)
		(layer "In7.Cu")
		(net 91)
	)
	(segment
		(start 221.7375 130.056956)
		(end 222.556956 129.2375)
		(width 0.15)
		(layer "In7.Cu")
		(net 91)
	)
	(segment
		(start 221.7375 131.943044)
		(end 221.7375 130.056956)
		(width 0.15)
		(layer "In7.Cu")
		(net 91)
	)
	(segment
		(start 222.9 132.023)
		(end 222.7375 132.1855)
		(width 0.15)
		(layer "In7.Cu")
		(net 91)
	)
	(segment
		(start 230.8275 125.8425)
		(end 230.8275 129.14524)
		(width 0.19)
		(layer "In7.Cu")
		(net 91)
	)
	(segment
		(start 230.21137 129.76137)
		(end 230.13524 129.8375)
		(width 0.15)
		(layer "In7.Cu")
		(net 91)
	)
	(segment
		(start 222.556956 129.2375)
		(end 222.894134 129.2375)
		(width 0.15)
		(layer "In7.Cu")
		(net 91)
	)
	(segment
		(start 225.843044 129.8375)
		(end 225.243044 129.2375)
		(width 0.15)
		(layer "In7.Cu")
		(net 91)
	)
	(segment
		(start 222.7375 132.1855)
		(end 221.979956 132.1855)
		(width 0.15)
		(layer "In7.Cu")
		(net 91)
	)
	(segment
		(start 230.13524 129.8375)
		(end 225.843044 129.8375)
		(width 0.15)
		(layer "In7.Cu")
		(net 91)
	)
	(segment
		(start 230.97 125.7)
		(end 230.8275 125.8425)
		(width 0.19)
		(layer "In7.Cu")
		(net 91)
	)
	(segment
		(start 223.034134 129.3775)
		(end 223.034134 129.445549)
		(width 0.15)
		(layer "In7.Cu")
		(net 91)
	)
	(segment
		(start 230.8275 129.14524)
		(end 230.21137 129.76137)
		(width 0.19)
		(layer "In7.Cu")
		(net 91)
	)
	(arc
		(start 223.034134 129.445549)
		(mid 223.075139 129.544544)
		(end 223.174134 129.585549)
		(width 0.15)
		(layer "In7.Cu")
		(net 91)
	)
	(arc
		(start 223.384134 129.3775)
		(mid 223.425139 129.278505)
		(end 223.524134 129.2375)
		(width 0.15)
		(layer "In7.Cu")
		(net 91)
	)
	(arc
		(start 223.244134 129.585549)
		(mid 223.343129 129.544544)
		(end 223.384134 129.445549)
		(width 0.15)
		(layer "In7.Cu")
		(net 91)
	)
	(arc
		(start 222.894134 129.2375)
		(mid 222.993129 129.278505)
		(end 223.034134 129.3775)
		(width 0.15)
		(layer "In7.Cu")
		(net 91)
	)
	(segment
		(start 125.405532 74.175)
		(end 125.405532 73.925)
		(width 0.17)
		(layer "F.Cu")
		(net 93)
	)
	(segment
		(start 125.405532 73.925)
		(end 125.130532 73.65)
		(width 0.17)
		(layer "F.Cu")
		(net 93)
	)
	(segment
		(start 125.305532 74.275)
		(end 125.405532 74.175)
		(width 0.17)
		(layer "F.Cu")
		(net 93)
	)
	(segment
		(start 125.3 74.275)
		(end 125.305532 74.275)
		(width 0.17)
		(layer "F.Cu")
		(net 93)
	)
	(via
		(at 61.4875 105.2)
		(size 0.45)
		(drill 0.1)
		(layers "F.Cu" "B.Cu")
		(net 93)
	)
	(via
		(at 125.3 74.275)
		(size 0.45)
		(drill 0.1)
		(layers "F.Cu" "B.Cu")
		(net 93)
	)
	(segment
		(start 61.375 105.3125)
		(end 61.4875 105.2)
		(width 0.17)
		(layer "B.Cu")
		(net 93)
	)
	(segment
		(start 64.59 106.46)
		(end 63.689999 106.46)
		(width 0.17)
		(layer "B.Cu")
		(net 93)
	)
	(segment
		(start 63.614999 106.535)
		(end 61.982488 106.535)
		(width 0.17)
		(layer "B.Cu")
		(net 93)
	)
	(segment
		(start 61.375 105.927512)
		(end 61.375 105.3125)
		(width 0.17)
		(layer "B.Cu")
		(net 93)
	)
	(segment
		(start 63.689999 106.46)
		(end 63.614999 106.535)
		(width 0.17)
		(layer "B.Cu")
		(net 93)
	)
	(segment
		(start 61.982488 106.535)
		(end 61.375 105.927512)
		(width 0.17)
		(layer "B.Cu")
		(net 93)
	)
	(segment
		(start 117.8443 70.0125)
		(end 119.4443 71.6125)
		(width 0.125)
		(layer "In2.Cu")
		(net 93)
	)
	(segment
		(start 114.5366 71.6125)
		(end 115.0025 71.1466)
		(width 0.125)
		(layer "In2.Cu")
		(net 93)
	)
	(segment
		(start 122.301594 73.348408)
		(end 122.371594 73.348408)
		(width 0.125)
		(layer "In2.Cu")
		(net 93)
	)
	(segment
		(start 61.312501 102.50165)
		(end 61.312501 85.546599)
		(width 0.125)
		(layer "In2.Cu")
		(net 93)
	)
	(segment
		(start 94.96 71.6125)
		(end 114.5366 71.6125)
		(width 0.125)
		(layer "In2.Cu")
		(net 93)
	)
	(segment
		(start 125.468031 73.427131)
		(end 125.0534 73.0125)
		(width 0.125)
		(layer "In2.Cu")
		(net 93)
	)
	(segment
		(start 125.468031 74.112501)
		(end 125.468031 73.427131)
		(width 0.125)
		(layer "In2.Cu")
		(net 93)
	)
	(segment
		(start 61.742501 102.62165)
		(end 61.432501 102.62165)
		(width 0.125)
		(layer "In2.Cu")
		(net 93)
	)
	(segment
		(start 92.1025 71.764946)
		(end 92.1025 71.235054)
		(width 0.125)
		(layer "In2.Cu")
		(net 93)
	)
	(segment
		(start 93.86 72.247436)
		(end 93.97 72.247436)
		(width 0.125)
		(layer "In2.Cu")
		(net 93)
	)
	(segment
		(start 90.4525 72.364947)
		(end 90.4525 70.785054)
		(width 0.125)
		(layer "In2.Cu")
		(net 93)
	)
	(segment
		(start 125.3 74.275)
		(end 125.305532 74.275)
		(width 0.125)
		(layer "In2.Cu")
		(net 93)
	)
	(segment
		(start 92.76 71.6125)
		(end 92.87 71.6125)
		(width 0.125)
		(layer "In2.Cu")
		(net 93)
	)
	(segment
		(start 68.8466 78.0125)
		(end 79.6966 78.0125)
		(width 0.125)
		(layer "In2.Cu")
		(net 93)
	)
	(segment
		(start 115.3366 70.0125)
		(end 117.8443 70.0125)
		(width 0.125)
		(layer "In2.Cu")
		(net 93)
	)
	(segment
		(start 61.862501 102.80165)
		(end 61.862501 102.74165)
		(width 0.125)
		(layer "In2.Cu")
		(net 93)
	)
	(segment
		(start 125.305532 74.275)
		(end 125.468031 74.112501)
		(width 0.125)
		(layer "In2.Cu")
		(net 93)
	)
	(segment
		(start 93.2025 71.28)
		(end 93.2025 70.785054)
		(width 0.125)
		(layer "In2.Cu")
		(net 93)
	)
	(segment
		(start 94.6275 70.785054)
		(end 94.6275 71.28)
		(width 0.125)
		(layer "In2.Cu")
		(net 93)
	)
	(segment
		(start 93.5275 70.785054)
		(end 93.5275 71.914936)
		(width 0.125)
		(layer "In2.Cu")
		(net 93)
	)
	(segment
		(start 115.0025 70.3466)
		(end 115.3366 70.0125)
		(width 0.125)
		(layer "In2.Cu")
		(net 93)
	)
	(segment
		(start 61.312501 85.546599)
		(end 68.8466 78.0125)
		(width 0.125)
		(layer "In2.Cu")
		(net 93)
	)
	(segment
		(start 94.3025 71.914936)
		(end 94.3025 70.785054)
		(width 0.125)
		(layer "In2.Cu")
		(net 93)
	)
	(segment
		(start 89.46 70.677554)
		(end 89.57 70.677554)
		(width 0.125)
		(layer "In2.Cu")
		(net 93)
	)
	(segment
		(start 122.511594 73.208408)
		(end 122.511594 73.1525)
		(width 0.125)
		(layer "In2.Cu")
		(net 93)
	)
	(segment
		(start 91.3275 71.72)
		(end 91.3275 71.764946)
		(width 0.125)
		(layer "In2.Cu")
		(net 93)
	)
	(segment
		(start 122.161594 73.1525)
		(end 122.161594 73.208408)
		(width 0.125)
		(layer "In2.Cu")
		(net 93)
	)
	(segment
		(start 115.0025 71.1466)
		(end 115.0025 70.3466)
		(width 0.125)
		(layer "In2.Cu")
		(net 93)
	)
	(segment
		(start 61.4875 105.2)
		(end 61.312501 105.025001)
		(width 0.125)
		(layer "In2.Cu")
		(net 93)
	)
	(segment
		(start 92.21 71.127554)
		(end 92.32 71.127554)
		(width 0.125)
		(layer "In2.Cu")
		(net 93)
	)
	(segment
		(start 122.651594 73.0125)
		(end 125.0534 73.0125)
		(width 0.125)
		(layer "In2.Cu")
		(net 93)
	)
	(segment
		(start 121.3534 73.0125)
		(end 122.021594 73.0125)
		(width 0.125)
		(layer "In2.Cu")
		(net 93)
	)
	(segment
		(start 61.432501 102.92165)
		(end 61.742501 102.92165)
		(width 0.125)
		(layer "In2.Cu")
		(net 93)
	)
	(segment
		(start 79.6966 78.0125)
		(end 86.0966 71.6125)
		(width 0.125)
		(layer "In2.Cu")
		(net 93)
	)
	(segment
		(start 61.312501 105.025001)
		(end 61.312501 103.04165)
		(width 0.125)
		(layer "In2.Cu")
		(net 93)
	)
	(segment
		(start 89.6775 70.785054)
		(end 89.6775 72.364947)
		(width 0.125)
		(layer "In2.Cu")
		(net 93)
	)
	(segment
		(start 86.0966 71.6125)
		(end 89.02 71.6125)
		(width 0.125)
		(layer "In2.Cu")
		(net 93)
	)
	(segment
		(start 93.31 70.677554)
		(end 93.42 70.677554)
		(width 0.125)
		(layer "In2.Cu")
		(net 93)
	)
	(segment
		(start 90.7775 70.785054)
		(end 90.7775 71.28)
		(width 0.125)
		(layer "In2.Cu")
		(net 93)
	)
	(segment
		(start 119.4443 71.6125)
		(end 119.9534 71.6125)
		(width 0.125)
		(layer "In2.Cu")
		(net 93)
	)
	(segment
		(start 90.56 70.677554)
		(end 90.67 70.677554)
		(width 0.125)
		(layer "In2.Cu")
		(net 93)
	)
	(segment
		(start 89.3525 71.28)
		(end 89.3525 70.785054)
		(width 0.125)
		(layer "In2.Cu")
		(net 93)
	)
	(segment
		(start 90.01 72.697447)
		(end 90.12 72.697447)
		(width 0.125)
		(layer "In2.Cu")
		(net 93)
	)
	(segment
		(start 119.9534 71.6125)
		(end 121.3534 73.0125)
		(width 0.125)
		(layer "In2.Cu")
		(net 93)
	)
	(segment
		(start 92.4275 71.235054)
		(end 92.4275 71.28)
		(width 0.125)
		(layer "In2.Cu")
		(net 93)
	)
	(segment
		(start 94.41 70.677554)
		(end 94.52 70.677554)
		(width 0.125)
		(layer "In2.Cu")
		(net 93)
	)
	(segment
		(start 91.11 71.6125)
		(end 91.22 71.6125)
		(width 0.125)
		(layer "In2.Cu")
		(net 93)
	)
	(segment
		(start 91.66 72.097446)
		(end 91.77 72.097446)
		(width 0.125)
		(layer "In2.Cu")
		(net 93)
	)
	(arc
		(start 93.42 70.677554)
		(mid 93.496014 70.70904)
		(end 93.5275 70.785054)
		(width 0.125)
		(layer "In2.Cu")
		(net 93)
	)
	(arc
		(start 94.6275 71.28)
		(mid 94.724887 71.515113)
		(end 94.96 71.6125)
		(width 0.125)
		(layer "In2.Cu")
		(net 93)
	)
	(arc
		(start 61.742501 102.92165)
		(mid 61.827354 102.886503)
		(end 61.862501 102.80165)
		(width 0.125)
		(layer "In2.Cu")
		(net 93)
	)
	(arc
		(start 92.87 71.6125)
		(mid 93.105113 71.515113)
		(end 93.2025 71.28)
		(width 0.125)
		(layer "In2.Cu")
		(net 93)
	)
	(arc
		(start 93.97 72.247436)
		(mid 94.205113 72.150049)
		(end 94.3025 71.914936)
		(width 0.125)
		(layer "In2.Cu")
		(net 93)
	)
	(arc
		(start 89.3525 70.785054)
		(mid 89.383986 70.70904)
		(end 89.46 70.677554)
		(width 0.125)
		(layer "In2.Cu")
		(net 93)
	)
	(arc
		(start 94.3025 70.785054)
		(mid 94.333986 70.70904)
		(end 94.41 70.677554)
		(width 0.125)
		(layer "In2.Cu")
		(net 93)
	)
	(arc
		(start 61.432501 102.62165)
		(mid 61.347648 102.586503)
		(end 61.312501 102.50165)
		(width 0.125)
		(layer "In2.Cu")
		(net 93)
	)
	(arc
		(start 89.57 70.677554)
		(mid 89.646014 70.70904)
		(end 89.6775 70.785054)
		(width 0.125)
		(layer "In2.Cu")
		(net 93)
	)
	(arc
		(start 93.5275 71.914936)
		(mid 93.624887 72.150049)
		(end 93.86 72.247436)
		(width 0.125)
		(layer "In2.Cu")
		(net 93)
	)
	(arc
		(start 91.3275 71.764946)
		(mid 91.424887 72.000059)
		(end 91.66 72.097446)
		(width 0.125)
		(layer "In2.Cu")
		(net 93)
	)
	(arc
		(start 89.02 71.6125)
		(mid 89.255113 71.515113)
		(end 89.3525 71.28)
		(width 0.125)
		(layer "In2.Cu")
		(net 93)
	)
	(arc
		(start 91.77 72.097446)
		(mid 92.005113 72.000059)
		(end 92.1025 71.764946)
		(width 0.125)
		(layer "In2.Cu")
		(net 93)
	)
	(arc
		(start 93.2025 70.785054)
		(mid 93.233986 70.70904)
		(end 93.31 70.677554)
		(width 0.125)
		(layer "In2.Cu")
		(net 93)
	)
	(arc
		(start 92.32 71.127554)
		(mid 92.396014 71.15904)
		(end 92.4275 71.235054)
		(width 0.125)
		(layer "In2.Cu")
		(net 93)
	)
	(arc
		(start 90.4525 70.785054)
		(mid 90.483986 70.70904)
		(end 90.56 70.677554)
		(width 0.125)
		(layer "In2.Cu")
		(net 93)
	)
	(arc
		(start 92.1025 71.235054)
		(mid 92.133986 71.15904)
		(end 92.21 71.127554)
		(width 0.125)
		(layer "In2.Cu")
		(net 93)
	)
	(arc
		(start 91.22 71.6125)
		(mid 91.296014 71.643986)
		(end 91.3275 71.72)
		(width 0.125)
		(layer "In2.Cu")
		(net 93)
	)
	(arc
		(start 122.371594 73.348408)
		(mid 122.470589 73.307403)
		(end 122.511594 73.208408)
		(width 0.125)
		(layer "In2.Cu")
		(net 93)
	)
	(arc
		(start 61.312501 103.04165)
		(mid 61.347648 102.956797)
		(end 61.432501 102.92165)
		(width 0.125)
		(layer "In2.Cu")
		(net 93)
	)
	(arc
		(start 61.862501 102.74165)
		(mid 61.827354 102.656797)
		(end 61.742501 102.62165)
		(width 0.125)
		(layer "In2.Cu")
		(net 93)
	)
	(arc
		(start 122.511594 73.1525)
		(mid 122.552599 73.053505)
		(end 122.651594 73.0125)
		(width 0.125)
		(layer "In2.Cu")
		(net 93)
	)
	(arc
		(start 90.7775 71.28)
		(mid 90.874887 71.515113)
		(end 91.11 71.6125)
		(width 0.125)
		(layer "In2.Cu")
		(net 93)
	)
	(arc
		(start 94.52 70.677554)
		(mid 94.596014 70.70904)
		(end 94.6275 70.785054)
		(width 0.125)
		(layer "In2.Cu")
		(net 93)
	)
	(arc
		(start 92.4275 71.28)
		(mid 92.524887 71.515113)
		(end 92.76 71.6125)
		(width 0.125)
		(layer "In2.Cu")
		(net 93)
	)
	(arc
		(start 122.021594 73.0125)
		(mid 122.120589 73.053505)
		(end 122.161594 73.1525)
		(width 0.125)
		(layer "In2.Cu")
		(net 93)
	)
	(arc
		(start 122.161594 73.208408)
		(mid 122.202599 73.307403)
		(end 122.301594 73.348408)
		(width 0.125)
		(layer "In2.Cu")
		(net 93)
	)
	(arc
		(start 90.12 72.697447)
		(mid 90.355113 72.60006)
		(end 90.4525 72.364947)
		(width 0.125)
		(layer "In2.Cu")
		(net 93)
	)
	(arc
		(start 90.67 70.677554)
		(mid 90.746014 70.70904)
		(end 90.7775 70.785054)
		(width 0.125)
		(layer "In2.Cu")
		(net 93)
	)
	(arc
		(start 89.6775 72.364947)
		(mid 89.774887 72.60006)
		(end 90.01 72.697447)
		(width 0.125)
		(layer "In2.Cu")
		(net 93)
	)
	(segment
		(start 116.430532 84.15)
		(end 116.695532 83.885)
		(width 0.19)
		(layer "F.Cu")
		(net 94)
	)
	(segment
		(start 116.695532 83.885)
		(end 116.695532 83.265)
		(width 0.19)
		(layer "F.Cu")
		(net 94)
	)
	(segment
		(start 104.115 119.52337)
		(end 102.215 121.42337)
		(width 0.19)
		(layer "F.Cu")
		(net 94)
	)
	(segment
		(start 104.115 115.87663)
		(end 104.115 119.52337)
		(width 0.19)
		(layer "F.Cu")
		(net 94)
	)
	(segment
		(start 102.215 126.17663)
		(end 106.73337 130.695)
		(width 0.19)
		(layer "F.Cu")
		(net 94)
	)
	(segment
		(start 102.487868 105.287868)
		(end 102.487868 105.450502)
		(width 0.19)
		(layer "F.Cu")
		(net 94)
	)
	(segment
		(start 106.73337 130.695)
		(end 111.985 130.695)
		(width 0.19)
		(layer "F.Cu")
		(net 94)
	)
	(segment
		(start 116.695532 83.265)
		(end 116.580532 83.15)
		(width 0.19)
		(layer "F.Cu")
		(net 94)
	)
	(segment
		(start 111.985 130.695)
		(end 112.1 130.81)
		(width 0.19)
		(layer "F.Cu")
		(net 94)
	)
	(segment
		(start 102.215 113.97663)
		(end 104.115 115.87663)
		(width 0.19)
		(layer "F.Cu")
		(net 94)
	)
	(segment
		(start 102.215 121.42337)
		(end 102.215 126.17663)
		(width 0.19)
		(layer "F.Cu")
		(net 94)
	)
	(segment
		(start 102.487868 105.450502)
		(end 102.215 105.72337)
		(width 0.19)
		(layer "F.Cu")
		(net 94)
	)
	(segment
		(start 102.215 105.72337)
		(end 102.215 113.97663)
		(width 0.19)
		(layer "F.Cu")
		(net 94)
	)
	(via
		(at 116.580532 83.15)
		(size 0.45)
		(drill 0.1)
		(layers "F.Cu" "B.Cu")
		(net 94)
	)
	(via
		(at 112.1 130.81)
		(size 0.45)
		(drill 0.1)
		(layers "F.Cu" "B.Cu")
		(net 94)
	)
	(via
		(at 102.487868 105.287868)
		(size 0.45)
		(drill 0.1)
		(layers "F.Cu" "B.Cu")
		(net 94)
	)
	(segment
		(start 113.021 130.695)
		(end 112.215 130.695)
		(width 0.19)
		(layer "B.Cu")
		(net 94)
	)
	(segment
		(start 112.215 130.695)
		(end 112.1 130.81)
		(width 0.19)
		(layer "B.Cu")
		(net 94)
	)
	(segment
		(start 113.086 130.76)
		(end 113.021 130.695)
		(width 0.19)
		(layer "B.Cu")
		(net 94)
	)
	(segment
		(start 113.711 130.76)
		(end 113.086 130.76)
		(width 0.19)
		(layer "B.Cu")
		(net 94)
	)
	(segment
		(start 117.143044 84.0375)
		(end 116.743032 83.637488)
		(width 0.15)
		(layer "In7.Cu")
		(net 94)
	)
	(segment
		(start 102.717677 105.287868)
		(end 102.8625 105.143045)
		(width 0.15)
		(layer "In7.Cu")
		(net 94)
	)
	(segment
		(start 102.487868 105.287868)
		(end 102.717677 105.287868)
		(width 0.15)
		(layer "In7.Cu")
		(net 94)
	)
	(segment
		(start 102.8625 105.143045)
		(end 102.8625 91.543044)
		(width 0.15)
		(layer "In7.Cu")
		(net 94)
	)
	(segment
		(start 116.743032 83.637488)
		(end 116.743032 83.3125)
		(width 0.15)
		(layer "In7.Cu")
		(net 94)
	)
	(segment
		(start 118.2375 81.843044)
		(end 118.2375 83.356956)
		(width 0.15)
		(layer "In7.Cu")
		(net 94)
	)
	(segment
		(start 117.556956 84.0375)
		(end 117.143044 84.0375)
		(width 0.15)
		(layer "In7.Cu")
		(net 94)
	)
	(segment
		(start 114.6625 81.043044)
		(end 115.343044 80.3625)
		(width 0.15)
		(layer "In7.Cu")
		(net 94)
	)
	(segment
		(start 116.756956 80.3625)
		(end 118.2375 81.843044)
		(width 0.15)
		(layer "In7.Cu")
		(net 94)
	)
	(segment
		(start 108.043044 89.0625)
		(end 109.1625 87.943044)
		(width 0.15)
		(layer "In7.Cu")
		(net 94)
	)
	(segment
		(start 102.8625 91.543044)
		(end 105.343044 89.0625)
		(width 0.15)
		(layer "In7.Cu")
		(net 94)
	)
	(segment
		(start 116.743032 83.3125)
		(end 116.580532 83.15)
		(width 0.15)
		(layer "In7.Cu")
		(net 94)
	)
	(segment
		(start 114.6625 81.743044)
		(end 114.6625 81.043044)
		(width 0.15)
		(layer "In7.Cu")
		(net 94)
	)
	(segment
		(start 118.2375 83.356956)
		(end 117.556956 84.0375)
		(width 0.15)
		(layer "In7.Cu")
		(net 94)
	)
	(segment
		(start 109.1625 86.643044)
		(end 110.743044 85.0625)
		(width 0.15)
		(layer "In7.Cu")
		(net 94)
	)
	(segment
		(start 105.343044 89.0625)
		(end 108.043044 89.0625)
		(width 0.15)
		(layer "In7.Cu")
		(net 94)
	)
	(segment
		(start 110.743044 85.0625)
		(end 111.843044 85.0625)
		(width 0.15)
		(layer "In7.Cu")
		(net 94)
	)
	(segment
		(start 113.9625 82.943044)
		(end 113.9625 82.443044)
		(width 0.15)
		(layer "In7.Cu")
		(net 94)
	)
	(segment
		(start 115.343044 80.3625)
		(end 116.756956 80.3625)
		(width 0.15)
		(layer "In7.Cu")
		(net 94)
	)
	(segment
		(start 109.1625 87.943044)
		(end 109.1625 86.643044)
		(width 0.15)
		(layer "In7.Cu")
		(net 94)
	)
	(segment
		(start 111.843044 85.0625)
		(end 113.9625 82.943044)
		(width 0.15)
		(layer "In7.Cu")
		(net 94)
	)
	(segment
		(start 113.9625 82.443044)
		(end 114.6625 81.743044)
		(width 0.15)
		(layer "In7.Cu")
		(net 94)
	)
	(segment
		(start 219.9 118.56)
		(end 219.8775 118.5825)
		(width 0.19)
		(layer "F.Cu")
		(net 95)
	)
	(segment
		(start 219.952499 118.56)
		(end 219.9 118.56)
		(width 0.19)
		(layer "F.Cu")
		(net 95)
	)
	(segment
		(start 230.865532 112.735)
		(end 230.980532 112.62)
		(width 0.19)
		(layer "F.Cu")
		(net 95)
	)
	(segment
		(start 220.43 118.625)
		(end 220.017499 118.625)
		(width 0.19)
		(layer "F.Cu")
		(net 95)
	)
	(segment
		(start 222.685 118.56)
		(end 222.8 118.675)
		(width 0.19)
		(layer "F.Cu")
		(net 95)
	)
	(segment
		(start 221.202 118.625)
		(end 221.614501 118.625)
		(width 0.19)
		(layer "F.Cu")
		(net 95)
	)
	(segment
		(start 221.614501 118.625)
		(end 221.679501 118.56)
		(width 0.19)
		(layer "F.Cu")
		(net 95)
	)
	(segment
		(start 220.017499 118.625)
		(end 219.952499 118.56)
		(width 0.19)
		(layer "F.Cu")
		(net 95)
	)
	(segment
		(start 230.930531 114.0725)
		(end 230.930531 113.385)
		(width 0.19)
		(layer "F.Cu")
		(net 95)
	)
	(segment
		(start 230.930531 113.385)
		(end 230.865532 113.32)
		(width 0.19)
		(layer "F.Cu")
		(net 95)
	)
	(segment
		(start 219.5925 118.5825)
		(end 219.275 118.9)
		(width 0.19)
		(layer "F.Cu")
		(net 95)
	)
	(segment
		(start 221.679501 118.56)
		(end 222.685 118.56)
		(width 0.19)
		(layer "F.Cu")
		(net 95)
	)
	(segment
		(start 230.865532 113.32)
		(end 230.865532 112.735)
		(width 0.19)
		(layer "F.Cu")
		(net 95)
	)
	(segment
		(start 220.43 118.625)
		(end 221.202 118.625)
		(width 0.19)
		(layer "F.Cu")
		(net 95)
	)
	(segment
		(start 219.8775 118.5825)
		(end 219.5925 118.5825)
		(width 0.19)
		(layer "F.Cu")
		(net 95)
	)
	(via
		(at 230.980532 112.62)
		(size 0.45)
		(drill 0.1)
		(layers "F.Cu" "B.Cu")
		(net 95)
	)
	(via
		(at 222.8 118.675)
		(size 0.45)
		(drill 0.1)
		(layers "F.Cu" "B.Cu")
		(net 95)
	)
	(segment
		(start 221.4625 117.656956)
		(end 222.318044 118.5125)
		(width 0.15)
		(layer "In7.Cu")
		(net 95)
	)
	(segment
		(start 230.818032 112.4575)
		(end 230.818032 111.553576)
		(width 0.15)
		(layer "In7.Cu")
		(net 95)
	)
	(segment
		(start 223.343044 110.7625)
		(end 221.4625 112.643044)
		(width 0.15)
		(layer "In7.Cu")
		(net 95)
	)
	(segment
		(start 221.4625 112.643044)
		(end 221.4625 117.656956)
		(width 0.15)
		(layer "In7.Cu")
		(net 95)
	)
	(segment
		(start 222.318044 118.5125)
		(end 222.6375 118.5125)
		(width 0.15)
		(layer "In7.Cu")
		(net 95)
	)
	(segment
		(start 230.026956 110.7625)
		(end 223.343044 110.7625)
		(width 0.15)
		(layer "In7.Cu")
		(net 95)
	)
	(segment
		(start 230.818032 111.553576)
		(end 230.026956 110.7625)
		(width 0.15)
		(layer "In7.Cu")
		(net 95)
	)
	(segment
		(start 222.6375 118.5125)
		(end 222.8 118.675)
		(width 0.15)
		(layer "In7.Cu")
		(net 95)
	)
	(segment
		(start 230.980532 112.62)
		(end 230.818032 112.4575)
		(width 0.15)
		(layer "In7.Cu")
		(net 95)
	)
	(segment
		(start 87.9 69.4)
		(end 92 69.4)
		(width 0.1)
		(layer "F.Cu")
		(net 96)
	)
	(segment
		(start 87.45 69.85)
		(end 87.9 69.4)
		(width 0.1)
		(layer "F.Cu")
		(net 96)
	)
	(segment
		(start 92.630532 70.030532)
		(end 92.630532 70.65)
		(width 0.1)
		(layer "F.Cu")
		(net 96)
	)
	(segment
		(start 92 69.4)
		(end 92.630532 70.030532)
		(width 0.1)
		(layer "F.Cu")
		(net 96)
	)
	(via
		(at 87.45 69.85)
		(size 0.45)
		(drill 0.1)
		(layers "F.Cu" "B.Cu")
		(net 96)
	)
	(segment
		(start 87.45 69.85)
		(end 87.8 69.5)
		(width 0.1)
		(layer "B.Cu")
		(net 96)
	)
	(segment
		(start 87.8 69.5)
		(end 87.8 67.6)
		(width 0.1)
		(layer "B.Cu")
		(net 96)
	)
	(segment
		(start 144.230532 72.15)
		(end 144.880532 71.5)
		(width 0.1)
		(layer "F.Cu")
		(net 97)
	)
	(segment
		(start 147.6 70.6)
		(end 147.6 69.6)
		(width 0.1)
		(layer "F.Cu")
		(net 97)
	)
	(segment
		(start 140.7 63.5)
		(end 141.2 63)
		(width 0.1)
		(layer "F.Cu")
		(net 97)
	)
	(segment
		(start 144.880532 71.5)
		(end 146.7 71.5)
		(width 0.1)
		(layer "F.Cu")
		(net 97)
	)
	(segment
		(start 146.9 68.9)
		(end 143.2 68.9)
		(width 0.1)
		(layer "F.Cu")
		(net 97)
	)
	(segment
		(start 147.6 69.6)
		(end 146.9 68.9)
		(width 0.1)
		(layer "F.Cu")
		(net 97)
	)
	(segment
		(start 143.2 68.9)
		(end 140.7 66.4)
		(width 0.1)
		(layer "F.Cu")
		(net 97)
	)
	(segment
		(start 158.06 142.64)
		(end 158.06 142.98)
		(width 0.15)
		(layer "F.Cu")
		(net 97)
	)
	(segment
		(start 137.7 97.2)
		(end 134.2 100.7)
		(width 0.1)
		(layer "F.Cu")
		(net 97)
	)
	(segment
		(start 146.7 71.5)
		(end 147.6 70.6)
		(width 0.1)
		(layer "F.Cu")
		(net 97)
	)
	(segment
		(start 140.7 66.4)
		(end 140.7 63.5)
		(width 0.1)
		(layer "F.Cu")
		(net 97)
	)
	(segment
		(start 158.4 142.3)
		(end 158.06 142.64)
		(width 0.15)
		(layer "F.Cu")
		(net 97)
	)
	(segment
		(start 134.2 100.7)
		(end 134.2 101.8)
		(width 0.1)
		(layer "F.Cu")
		(net 97)
	)
	(via
		(at 134.2 101.8)
		(size 0.45)
		(drill 0.1)
		(layers "F.Cu" "B.Cu")
		(net 97)
	)
	(via
		(at 137.7 97.2)
		(size 0.45)
		(drill 0.1)
		(layers "F.Cu" "B.Cu")
		(net 97)
	)
	(via
		(at 123.7 65.1)
		(size 0.45)
		(drill 0.1)
		(layers "F.Cu" "B.Cu")
		(net 97)
	)
	(via
		(at 141.2 63)
		(size 0.45)
		(drill 0.1)
		(layers "F.Cu" "B.Cu")
		(net 97)
	)
	(via
		(at 158.4 142.3)
		(size 0.45)
		(drill 0.1)
		(layers "F.Cu" "B.Cu")
		(net 97)
	)
	(segment
		(start 149.8 123)
		(end 147.2 120.4)
		(width 0.1)
		(layer "B.Cu")
		(net 97)
	)
	(segment
		(start 127.5 87.2)
		(end 128.2 87.9)
		(width 0.1)
		(layer "B.Cu")
		(net 97)
	)
	(segment
		(start 128.6 87.9)
		(end 130.65 89.95)
		(width 0.1)
		(layer "B.Cu")
		(net 97)
	)
	(segment
		(start 135.4 108.6)
		(end 135.4 103)
		(width 0.1)
		(layer "B.Cu")
		(net 97)
	)
	(segment
		(start 142.6 112.2)
		(end 141.4 111)
		(width 0.1)
		(layer "B.Cu")
		(net 97)
	)
	(segment
		(start 131 73.9)
		(end 130.1 74.8)
		(width 0.1)
		(layer "B.Cu")
		(net 97)
	)
	(segment
		(start 128.2 87.9)
		(end 128.6 87.9)
		(width 0.1)
		(layer "B.Cu")
		(net 97)
	)
	(segment
		(start 157.25 141.25)
		(end 157.25 141.4)
		(width 0.1)
		(layer "B.Cu")
		(net 97)
	)
	(segment
		(start 147.2 118)
		(end 148.6 116.6)
		(width 0.1)
		(layer "B.Cu")
		(net 97)
	)
	(segment
		(start 126.3 65.1)
		(end 131.2 70)
		(width 0.1)
		(layer "B.Cu")
		(net 97)
	)
	(segment
		(start 149.2 116.6)
		(end 149.4 116.4)
		(width 0.1)
		(layer "B.Cu")
		(net 97)
	)
	(segment
		(start 131 72.7)
		(end 131 73.9)
		(width 0.1)
		(layer "B.Cu")
		(net 97)
	)
	(segment
		(start 149.4 116.4)
		(end 149.4 115.6)
		(width 0.1)
		(layer "B.Cu")
		(net 97)
	)
	(segment
		(start 157.25 141.8)
		(end 157.75 142.3)
		(width 0.1)
		(layer "B.Cu")
		(net 97)
	)
	(segment
		(start 125.85 85.25)
		(end 127.5 86.9)
		(width 0.1)
		(layer "B.Cu")
		(net 97)
	)
	(segment
		(start 130.65 89.95)
		(end 130.65 90.45)
		(width 0.1)
		(layer "B.Cu")
		(net 97)
	)
	(segment
		(start 156.4 141.4)
		(end 149.8 134.8)
		(width 0.1)
		(layer "B.Cu")
		(net 97)
	)
	(segment
		(start 145.4 112.2)
		(end 142.6 112.2)
		(width 0.1)
		(layer "B.Cu")
		(net 97)
	)
	(segment
		(start 131.1 90.9)
		(end 137.4 97.2)
		(width 0.1)
		(layer "B.Cu")
		(net 97)
	)
	(segment
		(start 157.75 142.3)
		(end 158.4 142.3)
		(width 0.1)
		(layer "B.Cu")
		(net 97)
	)
	(segment
		(start 156.7 140.7)
		(end 157.25 141.25)
		(width 0.1)
		(layer "B.Cu")
		(net 97)
	)
	(segment
		(start 147.2 120.4)
		(end 147.2 118)
		(width 0.1)
		(layer "B.Cu")
		(net 97)
	)
	(segment
		(start 148.6 115.4)
		(end 145.4 112.2)
		(width 0.1)
		(layer "B.Cu")
		(net 97)
	)
	(segment
		(start 130.1 74.8)
		(end 130.1 78.1)
		(width 0.1)
		(layer "B.Cu")
		(net 97)
	)
	(segment
		(start 123.7 65.1)
		(end 126.3 65.1)
		(width 0.1)
		(layer "B.Cu")
		(net 97)
	)
	(segment
		(start 148.6 116.6)
		(end 149.2 116.6)
		(width 0.1)
		(layer "B.Cu")
		(net 97)
	)
	(segment
		(start 126.4 84.2)
		(end 125.85 84.75)
		(width 0.1)
		(layer "B.Cu")
		(net 97)
	)
	(segment
		(start 130.65 90.45)
		(end 131.1 90.9)
		(width 0.1)
		(layer "B.Cu")
		(net 97)
	)
	(segment
		(start 130.1 78.1)
		(end 126.4 81.8)
		(width 0.1)
		(layer "B.Cu")
		(net 97)
	)
	(segment
		(start 127.5 86.9)
		(end 127.5 87.2)
		(width 0.1)
		(layer "B.Cu")
		(net 97)
	)
	(segment
		(start 135.4 103)
		(end 134.2 101.8)
		(width 0.1)
		(layer "B.Cu")
		(net 97)
	)
	(segment
		(start 137.8 111)
		(end 135.4 108.6)
		(width 0.1)
		(layer "B.Cu")
		(net 97)
	)
	(segment
		(start 149.4 115.6)
		(end 149.2 115.4)
		(width 0.1)
		(layer "B.Cu")
		(net 97)
	)
	(segment
		(start 137.4 97.2)
		(end 137.7 97.2)
		(width 0.1)
		(layer "B.Cu")
		(net 97)
	)
	(segment
		(start 131.2 72.5)
		(end 131 72.7)
		(width 0.1)
		(layer "B.Cu")
		(net 97)
	)
	(segment
		(start 149.8 134.8)
		(end 149.8 123)
		(width 0.1)
		(layer "B.Cu")
		(net 97)
	)
	(segment
		(start 141.4 111)
		(end 137.8 111)
		(width 0.1)
		(layer "B.Cu")
		(net 97)
	)
	(segment
		(start 157.25 141.4)
		(end 156.4 141.4)
		(width 0.1)
		(layer "B.Cu")
		(net 97)
	)
	(segment
		(start 157.25 141.4)
		(end 157.25 141.8)
		(width 0.1)
		(layer "B.Cu")
		(net 97)
	)
	(segment
		(start 149.2 115.4)
		(end 148.6 115.4)
		(width 0.1)
		(layer "B.Cu")
		(net 97)
	)
	(segment
		(start 125.85 84.75)
		(end 125.85 85.25)
		(width 0.1)
		(layer "B.Cu")
		(net 97)
	)
	(segment
		(start 131.2 70)
		(end 131.2 72.5)
		(width 0.1)
		(layer "B.Cu")
		(net 97)
	)
	(segment
		(start 126.4 81.8)
		(end 126.4 84.2)
		(width 0.1)
		(layer "B.Cu")
		(net 97)
	)
	(segment
		(start 134.96 62.54)
		(end 139.14 62.54)
		(width 0.1)
		(layer "In5.Cu")
		(net 97)
	)
	(segment
		(start 139.85 63.25)
		(end 140.95 63.25)
		(width 0.1)
		(layer "In5.Cu")
		(net 97)
	)
	(segment
		(start 123.7 65.1)
		(end 125.86 62.94)
		(width 0.1)
		(layer "In5.Cu")
		(net 97)
	)
	(segment
		(start 140.95 63.25)
		(end 141.2 63)
		(width 0.1)
		(layer "In5.Cu")
		(net 97)
	)
	(segment
		(start 125.86 62.94)
		(end 128.35 62.94)
		(width 0.1)
		(layer "In5.Cu")
		(net 97)
	)
	(segment
		(start 128.35 62.94)
		(end 129.25 62.04)
		(width 0.1)
		(layer "In5.Cu")
		(net 97)
	)
	(segment
		(start 139.14 62.54)
		(end 139.85 63.25)
		(width 0.1)
		(layer "In5.Cu")
		(net 97)
	)
	(segment
		(start 129.25 62.04)
		(end 134.46 62.04)
		(width 0.1)
		(layer "In5.Cu")
		(net 97)
	)
	(segment
		(start 134.46 62.04)
		(end 134.96 62.54)
		(width 0.1)
		(layer "In5.Cu")
		(net 97)
	)
	(segment
		(start 68.6 91.3)
		(end 68.9 91)
		(width 0.1)
		(layer "F.Cu")
		(net 98)
	)
	(segment
		(start 63 93.7)
		(end 60.6 93.7)
		(width 0.1)
		(layer "F.Cu")
		(net 98)
	)
	(segment
		(start 136 113.5)
		(end 136 123.6)
		(width 0.1)
		(layer "F.Cu")
		(net 98)
	)
	(segment
		(start 71.7 141.8)
		(end 75.1 141.8)
		(width 0.1)
		(layer "F.Cu")
		(net 98)
	)
	(segment
		(start 135 131.5)
		(end 135 136.7)
		(width 0.1)
		(layer "F.Cu")
		(net 98)
	)
	(segment
		(start 67.4 89)
		(end 66.3 89)
		(width 0.1)
		(layer "F.Cu")
		(net 98)
	)
	(segment
		(start 64.25 86.43)
		(end 64.07 86.43)
		(width 0.1)
		(layer "F.Cu")
		(net 98)
	)
	(segment
		(start 64 88.3)
		(end 64.7 89)
		(width 0.1)
		(layer "F.Cu")
		(net 98)
	)
	(segment
		(start 64 86.5)
		(end 64 88.3)
		(width 0.1)
		(layer "F.Cu")
		(net 98)
	)
	(segment
		(start 63 93.7)
		(end 63.364 93.336)
		(width 0.1)
		(layer "F.Cu")
		(net 98)
	)
	(segment
		(start 135.52 110.1)
		(end 134.6 110.1)
		(width 0.1)
		(layer "F.Cu")
		(net 98)
	)
	(segment
		(start 136 130.5)
		(end 135 131.5)
		(width 0.1)
		(layer "F.Cu")
		(net 98)
	)
	(segment
		(start 136 123.6)
		(end 136 130.5)
		(width 0.1)
		(layer "F.Cu")
		(net 98)
	)
	(segment
		(start 134 111.5)
		(end 136 113.5)
		(width 0.1)
		(layer "F.Cu")
		(net 98)
	)
	(segment
		(start 67.9 91.3)
		(end 68.6 91.3)
		(width 0.1)
		(layer "F.Cu")
		(net 98)
	)
	(segment
		(start 67.704 89.304)
		(end 67.4 89)
		(width 0.1)
		(layer "F.Cu")
		(net 98)
	)
	(segment
		(start 67.704 90.301)
		(end 67.704 89.304)
		(width 0.1)
		(layer "F.Cu")
		(net 98)
	)
	(segment
		(start 67.704 90.301)
		(end 67.704 91.104)
		(width 0.1)
		(layer "F.Cu")
		(net 98)
	)
	(segment
		(start 67.704 91.104)
		(end 67.9 91.3)
		(width 0.1)
		(layer "F.Cu")
		(net 98)
	)
	(segment
		(start 64.07 86.43)
		(end 64 86.5)
		(width 0.1)
		(layer "F.Cu")
		(net 98)
	)
	(segment
		(start 134 110.7)
		(end 134 111.5)
		(width 0.1)
		(layer "F.Cu")
		(net 98)
	)
	(segment
		(start 78.6 138.3)
		(end 81.4 138.3)
		(width 0.1)
		(layer "F.Cu")
		(net 98)
	)
	(segment
		(start 75.1 141.8)
		(end 78.6 138.3)
		(width 0.1)
		(layer "F.Cu")
		(net 98)
	)
	(segment
		(start 63.364 90.341)
		(end 63.364 93.336)
		(width 0.1)
		(layer "F.Cu")
		(net 98)
	)
	(segment
		(start 64.7 89)
		(end 66.3 89)
		(width 0.1)
		(layer "F.Cu")
		(net 98)
	)
	(segment
		(start 134.6 110.1)
		(end 134 110.7)
		(width 0.1)
		(layer "F.Cu")
		(net 98)
	)
	(via
		(at 135 136.7)
		(size 0.45)
		(drill 0.1)
		(layers "F.Cu" "B.Cu")
		(net 98)
	)
	(via
		(at 60.6 93.7)
		(size 0.45)
		(drill 0.1)
		(layers "F.Cu" "B.Cu")
		(net 98)
	)
	(via
		(at 66.3 89)
		(size 0.45)
		(drill 0.1)
		(layers "F.Cu" "B.Cu")
		(net 98)
	)
	(via
		(at 71.7 141.8)
		(size 0.45)
		(drill 0.1)
		(layers "F.Cu" "B.Cu")
		(net 98)
	)
	(via
		(at 68.9 91)
		(size 0.45)
		(drill 0.1)
		(layers "F.Cu" "B.Cu")
		(net 98)
	)
	(via
		(at 81.4 138.3)
		(size 0.45)
		(drill 0.1)
		(layers "F.Cu" "B.Cu")
		(net 98)
	)
	(segment
		(start 72.1 121.6)
		(end 67.5 121.6)
		(width 0.1)
		(layer "B.Cu")
		(net 98)
	)
	(segment
		(start 72.25 115.25)
		(end 72.5 115.5)
		(width 0.1)
		(layer "B.Cu")
		(net 98)
	)
	(segment
		(start 64.65 135.6)
		(end 70.85 141.8)
		(width 0.1)
		(layer "B.Cu")
		(net 98)
	)
	(segment
		(start 64.65 124.45)
		(end 64.65 135.6)
		(width 0.1)
		(layer "B.Cu")
		(net 98)
	)
	(segment
		(start 72.5 121.2)
		(end 72.1 121.6)
		(width 0.1)
		(layer "B.Cu")
		(net 98)
	)
	(segment
		(start 67.5 121.6)
		(end 64.65 124.45)
		(width 0.1)
		(layer "B.Cu")
		(net 98)
	)
	(segment
		(start 68.9 91)
		(end 68.9 114.75)
		(width 0.1)
		(layer "B.Cu")
		(net 98)
	)
	(segment
		(start 70.85 141.8)
		(end 71.7 141.8)
		(width 0.1)
		(layer "B.Cu")
		(net 98)
	)
	(segment
		(start 68.9 114.75)
		(end 69.4 115.25)
		(width 0.1)
		(layer "B.Cu")
		(net 98)
	)
	(segment
		(start 72.5 115.5)
		(end 72.5 121.2)
		(width 0.1)
		(layer "B.Cu")
		(net 98)
	)
	(segment
		(start 69.4 115.25)
		(end 72.25 115.25)
		(width 0.1)
		(layer "B.Cu")
		(net 98)
	)
	(segment
		(start 82.5 138.6)
		(end 93.3 138.6)
		(width 0.1)
		(layer "In7.Cu")
		(net 98)
	)
	(segment
		(start 120 136.8)
		(end 132.7 136.8)
		(width 0.1)
		(layer "In7.Cu")
		(net 98)
	)
	(segment
		(start 93.3 138.6)
		(end 93.9 139.2)
		(width 0.1)
		(layer "In7.Cu")
		(net 98)
	)
	(segment
		(start 99.4 139.2)
		(end 101.1 140.9)
		(width 0.1)
		(layer "In7.Cu")
		(net 98)
	)
	(segment
		(start 63.6 93.7)
		(end 65.1 92.2)
		(width 0.1)
		(layer "In7.Cu")
		(net 98)
	)
	(segment
		(start 134.9 136.8)
		(end 135 136.7)
		(width 0.1)
		(layer "In7.Cu")
		(net 98)
	)
	(segment
		(start 115.9 140.9)
		(end 120 136.8)
		(width 0.1)
		(layer "In7.Cu")
		(net 98)
	)
	(segment
		(start 101.1 140.9)
		(end 115.9 140.9)
		(width 0.1)
		(layer "In7.Cu")
		(net 98)
	)
	(segment
		(start 81.4 138.3)
		(end 82.2 138.3)
		(width 0.1)
		(layer "In7.Cu")
		(net 98)
	)
	(segment
		(start 65.1 92.2)
		(end 65.1 90.2)
		(width 0.1)
		(layer "In7.Cu")
		(net 98)
	)
	(segment
		(start 65.1 90.2)
		(end 66.3 89)
		(width 0.1)
		(layer "In7.Cu")
		(net 98)
	)
	(segment
		(start 132.7 136.8)
		(end 134.9 136.8)
		(width 0.1)
		(layer "In7.Cu")
		(net 98)
	)
	(segment
		(start 93.9 139.2)
		(end 99.4 139.2)
		(width 0.1)
		(layer "In7.Cu")
		(net 98)
	)
	(segment
		(start 82.2 138.3)
		(end 82.5 138.6)
		(width 0.1)
		(layer "In7.Cu")
		(net 98)
	)
	(segment
		(start 60.6 93.7)
		(end 63.6 93.7)
		(width 0.1)
		(layer "In7.Cu")
		(net 98)
	)
	(segment
		(start 140 114.4)
		(end 140 129)
		(width 0.1)
		(layer "F.Cu")
		(net 100)
	)
	(segment
		(start 158.06 144.23)
		(end 158.21 144.38)
		(width 0.15)
		(layer "F.Cu")
		(net 100)
	)
	(segment
		(start 158.21 144.38)
		(end 158.245478 144.38)
		(width 0.15)
		(layer "F.Cu")
		(net 100)
	)
	(segment
		(start 136.5 134.681745)
		(end 142.568255 140.75)
		(width 0.1)
		(layer "F.Cu")
		(net 100)
	)
	(segment
		(start 158.245478 144.38)
		(end 158.410089 144.544611)
		(width 0.15)
		(layer "F.Cu")
		(net 100)
	)
	(segment
		(start 158.06 143.88)
		(end 158.06 144.23)
		(width 0.15)
		(layer "F.Cu")
		(net 100)
	)
	(segment
		(start 157.6 136)
		(end 158.2 135.4)
		(width 0.1)
		(layer "F.Cu")
		(net 100)
	)
	(segment
		(start 146.75 140.75)
		(end 151.5 136)
		(width 0.1)
		(layer "F.Cu")
		(net 100)
	)
	(segment
		(start 142.568255 140.75)
		(end 146.75 140.75)
		(width 0.1)
		(layer "F.Cu")
		(net 100)
	)
	(segment
		(start 140 129)
		(end 136.5 132.5)
		(width 0.1)
		(layer "F.Cu")
		(net 100)
	)
	(segment
		(start 151.5 136)
		(end 157.6 136)
		(width 0.1)
		(layer "F.Cu")
		(net 100)
	)
	(segment
		(start 136.5 132.5)
		(end 136.5 134.681745)
		(width 0.1)
		(layer "F.Cu")
		(net 100)
	)
	(via
		(at 158.410089 144.544611)
		(size 0.45)
		(drill 0.1)
		(layers "F.Cu" "B.Cu")
		(net 100)
	)
	(via
		(at 140 114.4)
		(size 0.45)
		(drill 0.1)
		(layers "F.Cu" "B.Cu")
		(net 100)
	)
	(via
		(at 136.830532 79.65)
		(size 0.45)
		(drill 0.1)
		(layers "F.Cu" "B.Cu")
		(net 100)
	)
	(via
		(at 158.2 135.4)
		(size 0.45)
		(drill 0.1)
		(layers "F.Cu" "B.Cu")
		(net 100)
	)
	(segment
		(start 159 144.8)
		(end 159.8 144.8)
		(width 0.15)
		(layer "B.Cu")
		(net 100)
	)
	(segment
		(start 158.410089 144.544611)
		(end 158.744611 144.544611)
		(width 0.15)
		(layer "B.Cu")
		(net 100)
	)
	(segment
		(start 158.744611 144.544611)
		(end 159 144.8)
		(width 0.15)
		(layer "B.Cu")
		(net 100)
	)
	(segment
		(start 159.8 144.8)
		(end 160 145)
		(width 0.15)
		(layer "B.Cu")
		(net 100)
	)
	(segment
		(start 137.990266 76.409734)
		(end 136.830532 77.569468)
		(width 0.1)
		(layer "In5.Cu")
		(net 100)
	)
	(segment
		(start 146.55 80.9)
		(end 144.75 79.1)
		(width 0.1)
		(layer "In5.Cu")
		(net 100)
	)
	(segment
		(start 144.926 86.744255)
		(end 144.25 86.068255)
		(width 0.1)
		(layer "In5.Cu")
		(net 100)
	)
	(segment
		(start 144.25 85.4)
		(end 144.523999 85.126001)
		(width 0.1)
		(layer "In5.Cu")
		(net 100)
	)
	(segment
		(start 142.75 71.35)
		(end 141.775 70.375)
		(width 0.1)
		(layer "In5.Cu")
		(net 100)
	)
	(segment
		(start 144.75 74.7)
		(end 144.3 74.25)
		(width 0.1)
		(layer "In5.Cu")
		(net 100)
	)
	(segment
		(start 138.6 72.8)
		(end 137.990266 73.409734)
		(width 0.1)
		(layer "In5.Cu")
		(net 100)
	)
	(segment
		(start 136.830532 77.569468)
		(end 136.830532 79.65)
		(width 0.1)
		(layer "In5.Cu")
		(net 100)
	)
	(segment
		(start 144.75 77.85)
		(end 145.35 77.25)
		(width 0.1)
		(layer "In5.Cu")
		(net 100)
	)
	(segment
		(start 140 98.884314)
		(end 140 92.7)
		(width 0.1)
		(layer "In5.Cu")
		(net 100)
	)
	(segment
		(start 140 114.4)
		(end 140 99.815686)
		(width 0.1)
		(layer "In5.Cu")
		(net 100)
	)
	(segment
		(start 144.686804 85.074)
		(end 145.160314 85.074)
		(width 0.1)
		(layer "In5.Cu")
		(net 100)
	)
	(segment
		(start 139.85 99.665686)
		(end 139.85 99.034314)
		(width 0.1)
		(layer "In5.Cu")
		(net 100)
	)
	(segment
		(start 144.577999 87.422001)
		(end 144.926 87.074)
		(width 0.1)
		(layer "In5.Cu")
		(net 100)
	)
	(segment
		(start 140 99.815686)
		(end 139.85 99.665686)
		(width 0.1)
		(layer "In5.Cu")
		(net 100)
	)
	(segment
		(start 144.75 75.45)
		(end 144.75 74.7)
		(width 0.1)
		(layer "In5.Cu")
		(net 100)
	)
	(segment
		(start 144.25 86.068255)
		(end 144.25 85.4)
		(width 0.1)
		(layer "In5.Cu")
		(net 100)
	)
	(segment
		(start 144.75 79.1)
		(end 144.75 77.85)
		(width 0.1)
		(layer "In5.Cu")
		(net 100)
	)
	(segment
		(start 138.6 71)
		(end 138.6 72.8)
		(width 0.1)
		(layer "In5.Cu")
		(net 100)
	)
	(segment
		(start 143.75 88.95)
		(end 143.75 88.059315)
		(width 0.1)
		(layer "In5.Cu")
		(net 100)
	)
	(segment
		(start 143.05 74.25)
		(end 142.75 73.95)
		(width 0.1)
		(layer "In5.Cu")
		(net 100)
	)
	(segment
		(start 137.990266 73.409734)
		(end 137.990266 76.409734)
		(width 0.1)
		(layer "In5.Cu")
		(net 100)
	)
	(segment
		(start 144.3 74.25)
		(end 143.05 74.25)
		(width 0.1)
		(layer "In5.Cu")
		(net 100)
	)
	(segment
		(start 144.387314 87.422001)
		(end 144.577999 87.422001)
		(width 0.1)
		(layer "In5.Cu")
		(net 100)
	)
	(segment
		(start 139.85 99.034314)
		(end 140 98.884314)
		(width 0.1)
		(layer "In5.Cu")
		(net 100)
	)
	(segment
		(start 145.35 76.05)
		(end 144.75 75.45)
		(width 0.1)
		(layer "In5.Cu")
		(net 100)
	)
	(segment
		(start 141.775 70.375)
		(end 139.225 70.375)
		(width 0.1)
		(layer "In5.Cu")
		(net 100)
	)
	(segment
		(start 145.35 77.25)
		(end 145.35 76.05)
		(width 0.1)
		(layer "In5.Cu")
		(net 100)
	)
	(segment
		(start 145.234314 85)
		(end 145.534316 85)
		(width 0.1)
		(layer "In5.Cu")
		(net 100)
	)
	(segment
		(start 144.926 87.074)
		(end 144.926 86.744255)
		(width 0.1)
		(layer "In5.Cu")
		(net 100)
	)
	(segment
		(start 142.75 73.95)
		(end 142.75 71.35)
		(width 0.1)
		(layer "In5.Cu")
		(net 100)
	)
	(segment
		(start 144.523999 85.126001)
		(end 144.634801 85.126002)
		(width 0.1)
		(layer "In5.Cu")
		(net 100)
	)
	(segment
		(start 139.225 70.375)
		(end 138.6 71)
		(width 0.1)
		(layer "In5.Cu")
		(net 100)
	)
	(segment
		(start 140 92.7)
		(end 143.75 88.95)
		(width 0.1)
		(layer "In5.Cu")
		(net 100)
	)
	(segment
		(start 143.75 88.059315)
		(end 144.387314 87.422001)
		(width 0.1)
		(layer "In5.Cu")
		(net 100)
	)
	(segment
		(start 146.55 83.984316)
		(end 146.55 80.9)
		(width 0.1)
		(layer "In5.Cu")
		(net 100)
	)
	(segment
		(start 145.160314 85.074)
		(end 145.234314 85)
		(width 0.1)
		(layer "In5.Cu")
		(net 100)
	)
	(segment
		(start 144.634801 85.126002)
		(end 144.686804 85.074)
		(width 0.1)
		(layer "In5.Cu")
		(net 100)
	)
	(segment
		(start 145.534316 85)
		(end 146.55 83.984316)
		(width 0.1)
		(layer "In5.Cu")
		(net 100)
	)
	(segment
		(start 160.2 143.2)
		(end 159.6 143.8)
		(width 0.1)
		(layer "In7.Cu")
		(net 100)
	)
	(segment
		(start 160.2 140.8)
		(end 160.2 143.2)
		(width 0.1)
		(layer "In7.Cu")
		(net 100)
	)
	(segment
		(start 159.6 143.8)
		(end 158.8 143.8)
		(width 0.1)
		(layer "In7.Cu")
		(net 100)
	)
	(segment
		(start 158.2 138.8)
		(end 160.2 140.8)
		(width 0.1)
		(layer "In7.Cu")
		(net 100)
	)
	(segment
		(start 158.2 135.4)
		(end 158.2 138.8)
		(width 0.1)
		(layer "In7.Cu")
		(net 100)
	)
	(segment
		(start 158.410089 144.189911)
		(end 158.410089 144.544611)
		(width 0.1)
		(layer "In7.Cu")
		(net 100)
	)
	(segment
		(start 158.8 143.8)
		(end 158.410089 144.189911)
		(width 0.1)
		(layer "In7.Cu")
		(net 100)
	)
	(segment
		(start 112.695532 81.885)
		(end 112.580532 82)
		(width 0.19)
		(layer "F.Cu")
		(net 101)
	)
	(segment
		(start 112.430532 81.15)
		(end 112.695532 81.415)
		(width 0.19)
		(layer "F.Cu")
		(net 101)
	)
	(segment
		(start 192.621 143.275)
		(end 192.306 142.96)
		(width 0.19)
		(layer "F.Cu")
		(net 101)
	)
	(segment
		(start 112.695532 81.415)
		(end 112.695532 81.885)
		(width 0.19)
		(layer "F.Cu")
		(net 101)
	)
	(segment
		(start 191.691 142.96)
		(end 191.576 143.075)
		(width 0.19)
		(layer "F.Cu")
		(net 101)
	)
	(segment
		(start 192.306 142.96)
		(end 191.691 142.96)
		(width 0.19)
		(layer "F.Cu")
		(net 101)
	)
	(segment
		(start 192.646 143.275)
		(end 192.621 143.275)
		(width 0.19)
		(layer "F.Cu")
		(net 101)
	)
	(via
		(at 191.576 143.075)
		(size 0.45)
		(drill 0.1)
		(layers "F.Cu" "B.Cu")
		(net 101)
	)
	(via
		(at 112.580532 82)
		(size 0.45)
		(drill 0.1)
		(layers "F.Cu" "B.Cu")
		(net 101)
	)
	(segment
		(start 179.291502 142.96)
		(end 188.235 142.96)
		(width 0.19)
		(layer "B.Cu")
		(net 101)
	)
	(segment
		(start 165.764002 143.175)
		(end 165.764002 143.202965)
		(width 0.19)
		(layer "B.Cu")
		(net 101)
	)
	(segment
		(start 173.349002 141.882043)
		(end 173.549002 141.882043)
		(width 0.19)
		(layer "B.Cu")
		(net 101)
	)
	(segment
		(start 119.82337 87.785)
		(end 122.52337 87.785)
		(width 0.19)
		(layer "B.Cu")
		(net 101)
	)
	(segment
		(start 175.764002 142.097025)
		(end 175.764002 142.375)
		(width 0.19)
		(layer "B.Cu")
		(net 101)
	)
	(segment
		(start 167.764002 142.097043)
		(end 167.764002 143.074362)
		(width 0.19)
		(layer "B.Cu")
		(net 101)
	)
	(segment
		(start 117.27337 85.035)
		(end 118.07337 85.035)
		(width 0.19)
		(layer "B.Cu")
		(net 101)
	)
	(segment
		(start 150.791522 133.114782)
		(end 160.63674 142.96)
		(width 0.19)
		(layer "B.Cu")
		(net 101)
	)
	(segment
		(start 122.52337 87.785)
		(end 150.791522 116.053152)
		(width 0.19)
		(layer "B.Cu")
		(net 101)
	)
	(segment
		(start 169.134002 143.074362)
		(end 169.134002 142.097043)
		(width 0.19)
		(layer "B.Cu")
		(net 101)
	)
	(segment
		(start 112.695532 82.115)
		(end 112.695532 82.957162)
		(width 0.19)
		(layer "B.Cu")
		(net 101)
	)
	(segment
		(start 178.291502 141.92465)
		(end 178.491502 141.92465)
		(width 0.19)
		(layer "B.Cu")
		(net 101)
	)
	(segment
		(start 113.22337 83.485)
		(end 115.72337 83.485)
		(width 0.19)
		(layer "B.Cu")
		(net 101)
	)
	(segment
		(start 118.815 86.77663)
		(end 119.82337 87.785)
		(width 0.19)
		(layer "B.Cu")
		(net 101)
	)
	(segment
		(start 177.139002 143.55)
		(end 177.596502 143.55)
		(width 0.19)
		(layer "B.Cu")
		(net 101)
	)
	(segment
		(start 174.349002 142.96)
		(end 174.549002 142.96)
		(width 0.19)
		(layer "B.Cu")
		(net 101)
	)
	(segment
		(start 191.461 142.96)
		(end 191.576 143.075)
		(width 0.19)
		(layer "B.Cu")
		(net 101)
	)
	(segment
		(start 118.07337 85.035)
		(end 118.815 85.77663)
		(width 0.19)
		(layer "B.Cu")
		(net 101)
	)
	(segment
		(start 171.134002 142.375)
		(end 171.134002 142.097043)
		(width 0.19)
		(layer "B.Cu")
		(net 101)
	)
	(segment
		(start 178.706502 142.13965)
		(end 178.706502 142.375)
		(width 0.19)
		(layer "B.Cu")
		(net 101)
	)
	(segment
		(start 112.580532 82)
		(end 112.695532 82.115)
		(width 0.19)
		(layer "B.Cu")
		(net 101)
	)
	(segment
		(start 176.349002 142.96)
		(end 176.549002 142.96)
		(width 0.19)
		(layer "B.Cu")
		(net 101)
	)
	(segment
		(start 160.63674 142.96)
		(end 165.549002 142.96)
		(width 0.19)
		(layer "B.Cu")
		(net 101)
	)
	(segment
		(start 175.349002 141.882025)
		(end 175.549002 141.882025)
		(width 0.19)
		(layer "B.Cu")
		(net 101)
	)
	(segment
		(start 171.349002 141.882043)
		(end 171.549002 141.882043)
		(width 0.19)
		(layer "B.Cu")
		(net 101)
	)
	(segment
		(start 178.076502 143.07)
		(end 178.076502 142.13965)
		(width 0.19)
		(layer "B.Cu")
		(net 101)
	)
	(segment
		(start 150.791522 116.053152)
		(end 150.791522 133.114782)
		(width 0.19)
		(layer "B.Cu")
		(net 101)
	)
	(segment
		(start 167.134002 143.202965)
		(end 167.134002 142.097043)
		(width 0.19)
		(layer "B.Cu")
		(net 101)
	)
	(segment
		(start 171.764002 142.097043)
		(end 171.764002 142.375)
		(width 0.19)
		(layer "B.Cu")
		(net 101)
	)
	(segment
		(start 166.349002 143.787965)
		(end 166.549002 143.787965)
		(width 0.19)
		(layer "B.Cu")
		(net 101)
	)
	(segment
		(start 170.349002 142.96)
		(end 170.549002 142.96)
		(width 0.19)
		(layer "B.Cu")
		(net 101)
	)
	(segment
		(start 188.235 142.96)
		(end 191.461 142.96)
		(width 0.19)
		(layer "B.Cu")
		(net 101)
	)
	(segment
		(start 169.764002 142.097043)
		(end 169.764002 142.375)
		(width 0.19)
		(layer "B.Cu")
		(net 101)
	)
	(segment
		(start 175.134002 142.375)
		(end 175.134002 142.097025)
		(width 0.19)
		(layer "B.Cu")
		(net 101)
	)
	(segment
		(start 169.349002 141.882043)
		(end 169.549002 141.882043)
		(width 0.19)
		(layer "B.Cu")
		(net 101)
	)
	(segment
		(start 173.134002 142.375)
		(end 173.134002 142.097043)
		(width 0.19)
		(layer "B.Cu")
		(net 101)
	)
	(segment
		(start 112.695532 82.957162)
		(end 113.22337 83.485)
		(width 0.19)
		(layer "B.Cu")
		(net 101)
	)
	(segment
		(start 173.764002 142.097043)
		(end 173.764002 142.375)
		(width 0.19)
		(layer "B.Cu")
		(net 101)
	)
	(segment
		(start 172.349002 142.96)
		(end 172.549002 142.96)
		(width 0.19)
		(layer "B.Cu")
		(net 101)
	)
	(segment
		(start 168.248364 143.558724)
		(end 168.64964 143.558724)
		(width 0.19)
		(layer "B.Cu")
		(net 101)
	)
	(segment
		(start 167.349002 141.882043)
		(end 167.549002 141.882043)
		(width 0.19)
		(layer "B.Cu")
		(net 101)
	)
	(segment
		(start 115.72337 83.485)
		(end 117.27337 85.035)
		(width 0.19)
		(layer "B.Cu")
		(net 101)
	)
	(segment
		(start 118.815 85.77663)
		(end 118.815 86.77663)
		(width 0.19)
		(layer "B.Cu")
		(net 101)
	)
	(arc
		(start 171.764002 142.375)
		(mid 171.935345 142.788657)
		(end 172.349002 142.96)
		(width 0.19)
		(layer "B.Cu")
		(net 101)
	)
	(arc
		(start 174.549002 142.96)
		(mid 174.962659 142.788657)
		(end 175.134002 142.375)
		(width 0.19)
		(layer "B.Cu")
		(net 101)
	)
	(arc
		(start 169.134002 142.097043)
		(mid 169.196974 141.945015)
		(end 169.349002 141.882043)
		(width 0.19)
		(layer "B.Cu")
		(net 101)
	)
	(arc
		(start 178.491502 141.92465)
		(mid 178.64353 141.987622)
		(end 178.706502 142.13965)
		(width 0.19)
		(layer "B.Cu")
		(net 101)
	)
	(arc
		(start 171.134002 142.097043)
		(mid 171.196974 141.945015)
		(end 171.349002 141.882043)
		(width 0.19)
		(layer "B.Cu")
		(net 101)
	)
	(arc
		(start 169.549002 141.882043)
		(mid 169.70103 141.945015)
		(end 169.764002 142.097043)
		(width 0.19)
		(layer "B.Cu")
		(net 101)
	)
	(arc
		(start 170.549002 142.96)
		(mid 170.962659 142.788657)
		(end 171.134002 142.375)
		(width 0.19)
		(layer "B.Cu")
		(net 101)
	)
	(arc
		(start 175.764002 142.375)
		(mid 175.935345 142.788657)
		(end 176.349002 142.96)
		(width 0.19)
		(layer "B.Cu")
		(net 101)
	)
	(arc
		(start 178.076502 142.13965)
		(mid 178.139474 141.987622)
		(end 178.291502 141.92465)
		(width 0.19)
		(layer "B.Cu")
		(net 101)
	)
	(arc
		(start 177.596502 143.55)
		(mid 177.935913 143.409411)
		(end 178.076502 143.07)
		(width 0.19)
		(layer "B.Cu")
		(net 101)
	)
	(arc
		(start 176.659002 143.07)
		(mid 176.799591 143.409411)
		(end 177.139002 143.55)
		(width 0.19)
		(layer "B.Cu")
		(net 101)
	)
	(arc
		(start 171.549002 141.882043)
		(mid 171.70103 141.945015)
		(end 171.764002 142.097043)
		(width 0.19)
		(layer "B.Cu")
		(net 101)
	)
	(arc
		(start 169.764002 142.375)
		(mid 169.935345 142.788657)
		(end 170.349002 142.96)
		(width 0.19)
		(layer "B.Cu")
		(net 101)
	)
	(arc
		(start 165.764002 143.202965)
		(mid 165.935345 143.616622)
		(end 166.349002 143.787965)
		(width 0.19)
		(layer "B.Cu")
		(net 101)
	)
	(arc
		(start 167.764002 143.074362)
		(mid 167.905868 143.416858)
		(end 168.248364 143.558724)
		(width 0.19)
		(layer "B.Cu")
		(net 101)
	)
	(arc
		(start 178.706502 142.375)
		(mid 178.877845 142.788657)
		(end 179.291502 142.96)
		(width 0.19)
		(layer "B.Cu")
		(net 101)
	)
	(arc
		(start 172.549002 142.96)
		(mid 172.962659 142.788657)
		(end 173.134002 142.375)
		(width 0.19)
		(layer "B.Cu")
		(net 101)
	)
	(arc
		(start 168.64964 143.558724)
		(mid 168.992136 143.416858)
		(end 169.134002 143.074362)
		(width 0.19)
		(layer "B.Cu")
		(net 101)
	)
	(arc
		(start 167.549002 141.882043)
		(mid 167.70103 141.945015)
		(end 167.764002 142.097043)
		(width 0.19)
		(layer "B.Cu")
		(net 101)
	)
	(arc
		(start 175.549002 141.882025)
		(mid 175.70103 141.944997)
		(end 175.764002 142.097025)
		(width 0.19)
		(layer "B.Cu")
		(net 101)
	)
	(arc
		(start 175.134002 142.097025)
		(mid 175.196974 141.944997)
		(end 175.349002 141.882025)
		(width 0.19)
		(layer "B.Cu")
		(net 101)
	)
	(arc
		(start 176.549002 142.96)
		(mid 176.626784 142.992218)
		(end 176.659002 143.07)
		(width 0.19)
		(layer "B.Cu")
		(net 101)
	)
	(arc
		(start 167.134002 142.097043)
		(mid 167.196974 141.945015)
		(end 167.349002 141.882043)
		(width 0.19)
		(layer "B.Cu")
		(net 101)
	)
	(arc
		(start 166.549002 143.787965)
		(mid 166.962659 143.616622)
		(end 167.134002 143.202965)
		(width 0.19)
		(layer "B.Cu")
		(net 101)
	)
	(arc
		(start 173.549002 141.882043)
		(mid 173.70103 141.945015)
		(end 173.764002 142.097043)
		(width 0.19)
		(layer "B.Cu")
		(net 101)
	)
	(arc
		(start 173.134002 142.097043)
		(mid 173.196974 141.945015)
		(end 173.349002 141.882043)
		(width 0.19)
		(layer "B.Cu")
		(net 101)
	)
	(arc
		(start 165.549002 142.96)
		(mid 165.70103 143.022972)
		(end 165.764002 143.175)
		(width 0.19)
		(layer "B.Cu")
		(net 101)
	)
	(arc
		(start 173.764002 142.375)
		(mid 173.935345 142.788657)
		(end 174.349002 142.96)
		(width 0.19)
		(layer "B.Cu")
		(net 101)
	)
	(via
		(at 130.530532 82.65)
		(size 0.45)
		(drill 0.1)
		(layers "F.Cu" "B.Cu")
		(net 102)
	)
	(via
		(at 200.703294 63.403294)
		(size 0.45)
		(drill 0.1)
		(layers "F.Cu" "B.Cu")
		(net 102)
	)
	(segment
		(start 200.975 62.972488)
		(end 200.703294 63.244194)
		(width 0.17)
		(layer "B.Cu")
		(net 102)
	)
	(segment
		(start 203.158 58.84)
		(end 203.083 58.915)
		(width 0.17)
		(layer "B.Cu")
		(net 102)
	)
	(segment
		(start 200.703294 63.244194)
		(end 200.703294 63.403294)
		(width 0.17)
		(layer "B.Cu")
		(net 102)
	)
	(segment
		(start 203.083 58.915)
		(end 203.083 59.364488)
		(width 0.17)
		(layer "B.Cu")
		(net 102)
	)
	(segment
		(start 200.975 61.472488)
		(end 200.975 62.972488)
		(width 0.17)
		(layer "B.Cu")
		(net 102)
	)
	(segment
		(start 203.158 58.39)
		(end 203.158 58.84)
		(width 0.17)
		(layer "B.Cu")
		(net 102)
	)
	(segment
		(start 203.083 59.364488)
		(end 200.975 61.472488)
		(width 0.17)
		(layer "B.Cu")
		(net 102)
	)
	(segment
		(start 167.956844 83.6125)
		(end 181.669344 69.9)
		(width 0.125)
		(layer "In2.Cu")
		(net 102)
	)
	(segment
		(start 159.464037 82.593778)
		(end 159.574037 82.593778)
		(width 0.125)
		(layer "In2.Cu")
		(net 102)
	)
	(segment
		(start 130.868031 82.987499)
		(end 130.868031 83.227131)
		(width 0.125)
		(layer "In2.Cu")
		(net 102)
	)
	(segment
		(start 157.814037 83.6125)
		(end 157.924037 83.6125)
		(width 0.125)
		(layer "In2.Cu")
		(net 102)
	)
	(segment
		(start 157.156537 83.28)
		(end 157.156537 82.701278)
		(width 0.125)
		(layer "In2.Cu")
		(net 102)
	)
	(segment
		(start 159.681537 83.6125)
		(end 159.681537 84.098703)
		(width 0.125)
		(layer "In2.Cu")
		(net 102)
	)
	(segment
		(start 196.2466 63.6125)
		(end 200.2466 63.6125)
		(width 0.125)
		(layer "In2.Cu")
		(net 102)
	)
	(segment
		(start 160.564037 82.593778)
		(end 160.674037 82.593778)
		(width 0.125)
		(layer "In2.Cu")
		(net 102)
	)
	(segment
		(start 159.356537 83.3875)
		(end 159.356537 82.701278)
		(width 0.125)
		(layer "In2.Cu")
		(net 102)
	)
	(segment
		(start 157.264037 82.593778)
		(end 157.374037 82.593778)
		(width 0.125)
		(layer "In2.Cu")
		(net 102)
	)
	(segment
		(start 193.9591 69.9)
		(end 194.8125 69.0466)
		(width 0.125)
		(layer "In2.Cu")
		(net 102)
	)
	(segment
		(start 159.356537 83.6125)
		(end 159.356537 83.3875)
		(width 0.125)
		(layer "In2.Cu")
		(net 102)
	)
	(segment
		(start 158.256537 83.28)
		(end 158.256537 82.701278)
		(width 0.125)
		(layer "In2.Cu")
		(net 102)
	)
	(segment
		(start 194.8125 69.0466)
		(end 194.8125 65.0466)
		(width 0.125)
		(layer "In2.Cu")
		(net 102)
	)
	(segment
		(start 158.581537 83.28)
		(end 158.581537 83.6125)
		(width 0.125)
		(layer "In2.Cu")
		(net 102)
	)
	(segment
		(start 160.456537 83.28)
		(end 160.456537 82.701278)
		(width 0.125)
		(layer "In2.Cu")
		(net 102)
	)
	(segment
		(start 200.455806 63.403294)
		(end 200.703294 63.403294)
		(width 0.125)
		(layer "In2.Cu")
		(net 102)
	)
	(segment
		(start 158.581537 82.701278)
		(end 158.581537 83.28)
		(width 0.125)
		(layer "In2.Cu")
		(net 102)
	)
	(segment
		(start 159.681537 82.701278)
		(end 159.681537 83.3875)
		(width 0.125)
		(layer "In2.Cu")
		(net 102)
	)
	(segment
		(start 130.868031 83.227131)
		(end 131.2534 83.6125)
		(width 0.125)
		(layer "In2.Cu")
		(net 102)
	)
	(segment
		(start 167.56207 83.6125)
		(end 167.956844 83.6125)
		(width 0.125)
		(layer "In2.Cu")
		(net 102)
	)
	(segment
		(start 161.114037 83.6125)
		(end 161.224037 83.6125)
		(width 0.125)
		(layer "In2.Cu")
		(net 102)
	)
	(segment
		(start 160.014037 84.431203)
		(end 160.124037 84.431203)
		(width 0.125)
		(layer "In2.Cu")
		(net 102)
	)
	(segment
		(start 181.669344 69.9)
		(end 193.9591 69.9)
		(width 0.125)
		(layer "In2.Cu")
		(net 102)
	)
	(segment
		(start 131.2534 83.6125)
		(end 156.824037 83.6125)
		(width 0.125)
		(layer "In2.Cu")
		(net 102)
	)
	(segment
		(start 200.2466 63.6125)
		(end 200.455806 63.403294)
		(width 0.125)
		(layer "In2.Cu")
		(net 102)
	)
	(segment
		(start 130.530532 82.65)
		(end 130.868031 82.987499)
		(width 0.125)
		(layer "In2.Cu")
		(net 102)
	)
	(segment
		(start 160.456537 84.098703)
		(end 160.456537 83.6125)
		(width 0.125)
		(layer "In2.Cu")
		(net 102)
	)
	(segment
		(start 157.481537 82.701278)
		(end 157.481537 83.28)
		(width 0.125)
		(layer "In2.Cu")
		(net 102)
	)
	(segment
		(start 158.581537 83.6125)
		(end 158.581537 84.098703)
		(width 0.125)
		(layer "In2.Cu")
		(net 102)
	)
	(segment
		(start 160.781537 82.701278)
		(end 160.781537 83.28)
		(width 0.125)
		(layer "In2.Cu")
		(net 102)
	)
	(segment
		(start 160.456537 83.6125)
		(end 160.456537 83.28)
		(width 0.125)
		(layer "In2.Cu")
		(net 102)
	)
	(segment
		(start 159.681537 83.3875)
		(end 159.681537 83.6125)
		(width 0.125)
		(layer "In2.Cu")
		(net 102)
	)
	(segment
		(start 158.364037 82.593778)
		(end 158.474037 82.593778)
		(width 0.125)
		(layer "In2.Cu")
		(net 102)
	)
	(segment
		(start 158.914037 84.431203)
		(end 159.024037 84.431203)
		(width 0.125)
		(layer "In2.Cu")
		(net 102)
	)
	(segment
		(start 159.356537 84.098703)
		(end 159.356537 83.6125)
		(width 0.125)
		(layer "In2.Cu")
		(net 102)
	)
	(segment
		(start 194.8125 65.0466)
		(end 196.2466 63.6125)
		(width 0.125)
		(layer "In2.Cu")
		(net 102)
	)
	(segment
		(start 161.224037 83.6125)
		(end 167.56207 83.6125)
		(width 0.125)
		(layer "In2.Cu")
		(net 102)
	)
	(arc
		(start 158.581537 84.098703)
		(mid 158.678924 84.333816)
		(end 158.914037 84.431203)
		(width 0.125)
		(layer "In2.Cu")
		(net 102)
	)
	(arc
		(start 160.456537 82.701278)
		(mid 160.488023 82.625264)
		(end 160.564037 82.593778)
		(width 0.125)
		(layer "In2.Cu")
		(net 102)
	)
	(arc
		(start 159.356537 82.701278)
		(mid 159.388023 82.625264)
		(end 159.464037 82.593778)
		(width 0.125)
		(layer "In2.Cu")
		(net 102)
	)
	(arc
		(start 157.481537 83.28)
		(mid 157.578924 83.515113)
		(end 157.814037 83.6125)
		(width 0.125)
		(layer "In2.Cu")
		(net 102)
	)
	(arc
		(start 158.474037 82.593778)
		(mid 158.550051 82.625264)
		(end 158.581537 82.701278)
		(width 0.125)
		(layer "In2.Cu")
		(net 102)
	)
	(arc
		(start 157.374037 82.593778)
		(mid 157.450051 82.625264)
		(end 157.481537 82.701278)
		(width 0.125)
		(layer "In2.Cu")
		(net 102)
	)
	(arc
		(start 158.256537 82.701278)
		(mid 158.288023 82.625264)
		(end 158.364037 82.593778)
		(width 0.125)
		(layer "In2.Cu")
		(net 102)
	)
	(arc
		(start 157.924037 83.6125)
		(mid 158.15915 83.515113)
		(end 158.256537 83.28)
		(width 0.125)
		(layer "In2.Cu")
		(net 102)
	)
	(arc
		(start 159.681537 84.098703)
		(mid 159.778924 84.333816)
		(end 160.014037 84.431203)
		(width 0.125)
		(layer "In2.Cu")
		(net 102)
	)
	(arc
		(start 160.781537 83.28)
		(mid 160.878924 83.515113)
		(end 161.114037 83.6125)
		(width 0.125)
		(layer "In2.Cu")
		(net 102)
	)
	(arc
		(start 160.124037 84.431203)
		(mid 160.35915 84.333816)
		(end 160.456537 84.098703)
		(width 0.125)
		(layer "In2.Cu")
		(net 102)
	)
	(arc
		(start 160.674037 82.593778)
		(mid 160.750051 82.625264)
		(end 160.781537 82.701278)
		(width 0.125)
		(layer "In2.Cu")
		(net 102)
	)
	(arc
		(start 159.024037 84.431203)
		(mid 159.25915 84.333816)
		(end 159.356537 84.098703)
		(width 0.125)
		(layer "In2.Cu")
		(net 102)
	)
	(arc
		(start 159.574037 82.593778)
		(mid 159.650051 82.625264)
		(end 159.681537 82.701278)
		(width 0.125)
		(layer "In2.Cu")
		(net 102)
	)
	(arc
		(start 157.156537 82.701278)
		(mid 157.188023 82.625264)
		(end 157.264037 82.593778)
		(width 0.125)
		(layer "In2.Cu")
		(net 102)
	)
	(arc
		(start 156.824037 83.6125)
		(mid 157.05915 83.515113)
		(end 157.156537 83.28)
		(width 0.125)
		(layer "In2.Cu")
		(net 102)
	)
	(segment
		(start 220.017499 112.427)
		(end 219.952499 112.362)
		(width 0.19)
		(layer "F.Cu")
		(net 103)
	)
	(segment
		(start 234.930532 117.035)
		(end 234.865532 117.1)
		(width 0.19)
		(layer "F.Cu")
		(net 103)
	)
	(segment
		(start 220.43 112.427)
		(end 220.017499 112.427)
		(width 0.19)
		(layer "F.Cu")
		(net 103)
	)
	(segment
		(start 219.62 112.385)
		(end 219.305 112.7)
		(width 0.19)
		(layer "F.Cu")
		(net 103)
	)
	(segment
		(start 225.215 118.97663)
		(end 225.215 112.97663)
		(width 0.19)
		(layer "F.Cu")
		(net 103)
	)
	(segment
		(start 221.614501 112.427)
		(end 221.202 112.427)
		(width 0.19)
		(layer "F.Cu")
		(net 103)
	)
	(segment
		(start 221.679501 112.362)
		(end 221.614501 112.427)
		(width 0.19)
		(layer "F.Cu")
		(net 103)
	)
	(segment
		(start 221.202 112.427)
		(end 220.43 112.427)
		(width 0.19)
		(layer "F.Cu")
		(net 103)
	)
	(segment
		(start 234.865532 118.766098)
		(end 233.64663 119.985)
		(width 0.19)
		(layer "F.Cu")
		(net 103)
	)
	(segment
		(start 219.305 112.7)
		(end 219.28 112.7)
		(width 0.19)
		(layer "F.Cu")
		(net 103)
	)
	(segment
		(start 219.952499 112.362)
		(end 219.85 112.362)
		(width 0.19)
		(layer "F.Cu")
		(net 103)
	)
	(segment
		(start 224.60037 112.362)
		(end 221.679501 112.362)
		(width 0.19)
		(layer "F.Cu")
		(net 103)
	)
	(segment
		(start 233.64663 119.985)
		(end 226.22337 119.985)
		(width 0.19)
		(layer "F.Cu")
		(net 103)
	)
	(segment
		(start 225.215 112.97663)
		(end 224.60037 112.362)
		(width 0.19)
		(layer "F.Cu")
		(net 103)
	)
	(segment
		(start 219.827 112.385)
		(end 219.62 112.385)
		(width 0.19)
		(layer "F.Cu")
		(net 103)
	)
	(segment
		(start 226.22337 119.985)
		(end 225.215 118.97663)
		(width 0.19)
		(layer "F.Cu")
		(net 103)
	)
	(segment
		(start 234.930532 116.3475)
		(end 234.930532 117.035)
		(width 0.19)
		(layer "F.Cu")
		(net 103)
	)
	(segment
		(start 234.865532 117.1)
		(end 234.865532 118.766098)
		(width 0.19)
		(layer "F.Cu")
		(net 103)
	)
	(segment
		(start 219.85 112.362)
		(end 219.827 112.385)
		(width 0.19)
		(layer "F.Cu")
		(net 103)
	)
	(segment
		(start 84 114.7)
		(end 84 112.9)
		(width 0.1)
		(layer "F.Cu")
		(net 104)
	)
	(segment
		(start 108.4 134.4)
		(end 108.4 134.8)
		(width 0.1)
		(layer "F.Cu")
		(net 104)
	)
	(segment
		(start 93.280532 85)
		(end 92.630532 85.65)
		(width 0.1)
		(layer "F.Cu")
		(net 104)
	)
	(segment
		(start 112.1 134.7)
		(end 111.8 134.4)
		(width 0.1)
		(layer "F.Cu")
		(net 104)
	)
	(segment
		(start 125.6 134.7)
		(end 112.1 134.7)
		(width 0.1)
		(layer "F.Cu")
		(net 104)
	)
	(segment
		(start 88.2 116)
		(end 87.4 115.2)
		(width 0.1)
		(layer "F.Cu")
		(net 104)
	)
	(segment
		(start 101.8 129.9)
		(end 96.4 129.9)
		(width 0.1)
		(layer "F.Cu")
		(net 104)
	)
	(segment
		(start 163.6 103.9)
		(end 171.3 103.9)
		(width 0.1)
		(layer "F.Cu")
		(net 104)
	)
	(segment
		(start 95.5 120.4)
		(end 97.5 122.4)
		(width 0.1)
		(layer "F.Cu")
		(net 104)
	)
	(segment
		(start 95.4 85)
		(end 93.280532 85)
		(width 0.1)
		(layer "F.Cu")
		(net 104)
	)
	(segment
		(start 96.4 129.9)
		(end 95.5 129)
		(width 0.1)
		(layer "F.Cu")
		(net 104)
	)
	(segment
		(start 86 112.7)
		(end 86.5 113.2)
		(width 0.1)
		(layer "F.Cu")
		(net 104)
	)
	(segment
		(start 97.675 86.225)
		(end 98 85.9)
		(width 0.1)
		(layer "F.Cu")
		(net 104)
	)
	(segment
		(start 84 112.9)
		(end 84.2 112.7)
		(width 0.1)
		(layer "F.Cu")
		(net 104)
	)
	(segment
		(start 84.5 115.2)
		(end 84 114.7)
		(width 0.1)
		(layer "F.Cu")
		(net 104)
	)
	(segment
		(start 89.8 119.2)
		(end 91.2 119.2)
		(width 0.1)
		(layer "F.Cu")
		(net 104)
	)
	(segment
		(start 92.4 120.4)
		(end 95.5 120.4)
		(width 0.1)
		(layer "F.Cu")
		(net 104)
	)
	(segment
		(start 96.075 86.225)
		(end 95.8 85.95)
		(width 0.1)
		(layer "F.Cu")
		(net 104)
	)
	(segment
		(start 89.8 119.2)
		(end 88.2 117.6)
		(width 0.1)
		(layer "F.Cu")
		(net 104)
	)
	(segment
		(start 130.8 104.6)
		(end 133.1 104.6)
		(width 0.1)
		(layer "F.Cu")
		(net 104)
	)
	(segment
		(start 87.6 113.2)
		(end 91.7 109.1)
		(width 0.1)
		(layer "F.Cu")
		(net 104)
	)
	(segment
		(start 96.075 86.225)
		(end 97.675 86.225)
		(width 0.1)
		(layer "F.Cu")
		(net 104)
	)
	(segment
		(start 98 85.9)
		(end 98 85)
		(width 0.1)
		(layer "F.Cu")
		(net 104)
	)
	(segment
		(start 135.8 101.9)
		(end 143.3 101.9)
		(width 0.1)
		(layer "F.Cu")
		(net 104)
	)
	(segment
		(start 96 126.5)
		(end 95.5 127)
		(width 0.1)
		(layer "F.Cu")
		(net 104)
	)
	(segment
		(start 106.7 135.4)
		(end 106.3 135)
		(width 0.1)
		(layer "F.Cu")
		(net 104)
	)
	(segment
		(start 95.5 129)
		(end 95.5 127)
		(width 0.1)
		(layer "F.Cu")
		(net 104)
	)
	(segment
		(start 88.2 117.6)
		(end 88.2 116)
		(width 0.1)
		(layer "F.Cu")
		(net 104)
	)
	(segment
		(start 84.2 112.7)
		(end 86 112.7)
		(width 0.1)
		(layer "F.Cu")
		(net 104)
	)
	(segment
		(start 106.3 134.4)
		(end 101.8 129.9)
		(width 0.1)
		(layer "F.Cu")
		(net 104)
	)
	(segment
		(start 126.9 109.5)
		(end 126.9 133.4)
		(width 0.1)
		(layer "F.Cu")
		(net 104)
	)
	(segment
		(start 108.4 134.8)
		(end 107.8 135.4)
		(width 0.1)
		(layer "F.Cu")
		(net 104)
	)
	(segment
		(start 111.8 134.4)
		(end 108.4 134.4)
		(width 0.1)
		(layer "F.Cu")
		(net 104)
	)
	(segment
		(start 96.8 126.5)
		(end 96 126.5)
		(width 0.1)
		(layer "F.Cu")
		(net 104)
	)
	(segment
		(start 95.8 85.4)
		(end 95.4 85)
		(width 0.1)
		(layer "F.Cu")
		(net 104)
	)
	(segment
		(start 107.8 135.4)
		(end 106.7 135.4)
		(width 0.1)
		(layer "F.Cu")
		(net 104)
	)
	(segment
		(start 91.2 119.2)
		(end 92.4 120.4)
		(width 0.1)
		(layer "F.Cu")
		(net 104)
	)
	(segment
		(start 95.8 85.95)
		(end 95.8 85.4)
		(width 0.1)
		(layer "F.Cu")
		(net 104)
	)
	(segment
		(start 171.3 103.9)
		(end 172.3 102.9)
		(width 0.1)
		(layer "F.Cu")
		(net 104)
	)
	(segment
		(start 126.9 133.4)
		(end 125.6 134.7)
		(width 0.1)
		(layer "F.Cu")
		(net 104)
	)
	(segment
		(start 97.5 122.4)
		(end 98.7 122.4)
		(width 0.1)
		(layer "F.Cu")
		(net 104)
	)
	(segment
		(start 106.3 135)
		(end 106.3 134.4)
		(width 0.1)
		(layer "F.Cu")
		(net 104)
	)
	(segment
		(start 87.4 115.2)
		(end 84.5 115.2)
		(width 0.1)
		(layer "F.Cu")
		(net 104)
	)
	(segment
		(start 86.5 113.2)
		(end 87.6 113.2)
		(width 0.1)
		(layer "F.Cu")
		(net 104)
	)
	(segment
		(start 126.4 109)
		(end 130.8 104.6)
		(width 0.1)
		(layer "F.Cu")
		(net 104)
	)
	(segment
		(start 133.1 104.6)
		(end 135.8 101.9)
		(width 0.1)
		(layer "F.Cu")
		(net 104)
	)
	(segment
		(start 91.7 109.1)
		(end 92.1 109.1)
		(width 0.1)
		(layer "F.Cu")
		(net 104)
	)
	(segment
		(start 126.4 109)
		(end 126.9 109.5)
		(width 0.1)
		(layer "F.Cu")
		(net 104)
	)
	(via
		(at 98 85)
		(size 0.45)
		(drill 0.1)
		(layers "F.Cu" "B.Cu")
		(net 104)
	)
	(via
		(at 92.1 109.1)
		(size 0.45)
		(drill 0.1)
		(layers "F.Cu" "B.Cu")
		(net 104)
	)
	(via
		(at 108.4 134.4)
		(size 0.45)
		(drill 0.1)
		(layers "F.Cu" "B.Cu")
		(net 104)
	)
	(via
		(at 172.3 102.9)
		(size 0.45)
		(drill 0.1)
		(layers "F.Cu" "B.Cu")
		(net 104)
	)
	(via
		(at 143.3 101.9)
		(size 0.45)
		(drill 0.1)
		(layers "F.Cu" "B.Cu")
		(net 104)
	)
	(via
		(at 192.515 86.58)
		(size 0.45)
		(drill 0.1)
		(layers "F.Cu" "B.Cu")
		(net 104)
	)
	(via
		(at 163.6 103.9)
		(size 0.45)
		(drill 0.1)
		(layers "F.Cu" "B.Cu")
		(net 104)
	)
	(via
		(at 216.5 75.8)
		(size 0.45)
		(drill 0.1)
		(layers "F.Cu" "B.Cu")
		(net 104)
	)
	(via
		(at 98.7 122.4)
		(size 0.45)
		(drill 0.1)
		(layers "F.Cu" "B.Cu")
		(net 104)
	)
	(via
		(at 126.4 109)
		(size 0.45)
		(drill 0.1)
		(layers "F.Cu" "B.Cu")
		(net 104)
	)
	(via
		(at 96.8 126.5)
		(size 0.45)
		(drill 0.1)
		(layers "F.Cu" "B.Cu")
		(net 104)
	)
	(segment
		(start 125.6 109.8)
		(end 126.4 109)
		(width 0.1)
		(layer "B.Cu")
		(net 104)
	)
	(segment
		(start 215.538 76.450532)
		(end 216.349468 76.450532)
		(width 0.1)
		(layer "B.Cu")
		(net 104)
	)
	(segment
		(start 215.538 77.362)
		(end 215.538 76.450532)
		(width 0.1)
		(layer "B.Cu")
		(net 104)
	)
	(segment
		(start 188.6 91.8)
		(end 177.5 102.9)
		(width 0.1)
		(layer "B.Cu")
		(net 104)
	)
	(segment
		(start 125.08 109.8)
		(end 125.6 109.8)
		(width 0.1)
		(layer "B.Cu")
		(net 104)
	)
	(segment
		(start 177.5 102.9)
		(end 172.3 102.9)
		(width 0.1)
		(layer "B.Cu")
		(net 104)
	)
	(segment
		(start 146.4 101.9)
		(end 148.8 104.3)
		(width 0.1)
		(layer "B.Cu")
		(net 104)
	)
	(segment
		(start 109.35 134.33)
		(end 108.47 134.33)
		(width 0.1)
		(layer "B.Cu")
		(net 104)
	)
	(segment
		(start 155.1 100.3)
		(end 155.4 100)
		(width 0.1)
		(layer "B.Cu")
		(net 104)
	)
	(segment
		(start 216.5 76.3)
		(end 216.5 75.8)
		(width 0.1)
		(layer "B.Cu")
		(net 104)
	)
	(segment
		(start 150.5 103.1)
		(end 150.6 103)
		(width 0.1)
		(layer "B.Cu")
		(net 104)
	)
	(segment
		(start 148.8 104.3)
		(end 150.3 104.3)
		(width 0.1)
		(layer "B.Cu")
		(net 104)
	)
	(segment
		(start 150.3 104.3)
		(end 150.5 104.1)
		(width 0.1)
		(layer "B.Cu")
		(net 104)
	)
	(segment
		(start 188.6 90)
		(end 188.6 91.8)
		(width 0.1)
		(layer "B.Cu")
		(net 104)
	)
	(segment
		(start 150.5 104.1)
		(end 150.5 103.1)
		(width 0.1)
		(layer "B.Cu")
		(net 104)
	)
	(segment
		(start 156.9 100)
		(end 160.8 103.9)
		(width 0.1)
		(layer "B.Cu")
		(net 104)
	)
	(segment
		(start 108.47 134.33)
		(end 108.4 134.4)
		(width 0.1)
		(layer "B.Cu")
		(net 104)
	)
	(segment
		(start 155.1 101)
		(end 155.1 100.3)
		(width 0.1)
		(layer "B.Cu")
		(net 104)
	)
	(segment
		(start 150.6 103)
		(end 153.1 103)
		(width 0.1)
		(layer "B.Cu")
		(net 104)
	)
	(segment
		(start 155.4 100)
		(end 156.9 100)
		(width 0.1)
		(layer "B.Cu")
		(net 104)
	)
	(segment
		(start 160.8 103.9)
		(end 163.6 103.9)
		(width 0.1)
		(layer "B.Cu")
		(net 104)
	)
	(segment
		(start 216.349468 76.450532)
		(end 216.5 76.3)
		(width 0.1)
		(layer "B.Cu")
		(net 104)
	)
	(segment
		(start 143.3 101.9)
		(end 146.4 101.9)
		(width 0.1)
		(layer "B.Cu")
		(net 104)
	)
	(segment
		(start 192.515 86.58)
		(end 192.02 86.58)
		(width 0.1)
		(layer "B.Cu")
		(net 104)
	)
	(segment
		(start 153.1 103)
		(end 155.1 101)
		(width 0.1)
		(layer "B.Cu")
		(net 104)
	)
	(segment
		(start 96.8 126.5)
		(end 96.8 125.3)
		(width 0.1)
		(layer "B.Cu")
		(net 104)
	)
	(segment
		(start 96.8 125.3)
		(end 98.7 123.4)
		(width 0.1)
		(layer "B.Cu")
		(net 104)
	)
	(segment
		(start 98.7 122.4)
		(end 98.7 123.4)
		(width 0.1)
		(layer "B.Cu")
		(net 104)
	)
	(segment
		(start 214.448 77.507)
		(end 215.393 77.507)
		(width 0.1)
		(layer "B.Cu")
		(net 104)
	)
	(segment
		(start 192.02 86.58)
		(end 188.6 90)
		(width 0.1)
		(layer "B.Cu")
		(net 104)
	)
	(segment
		(start 215.393 77.507)
		(end 215.538 77.362)
		(width 0.1)
		(layer "B.Cu")
		(net 104)
	)
	(segment
		(start 93.8 103.4)
		(end 93.8 97.6)
		(width 0.1)
		(layer "In5.Cu")
		(net 104)
	)
	(segment
		(start 98 85.8)
		(end 98 85)
		(width 0.1)
		(layer "In5.Cu")
		(net 104)
	)
	(segment
		(start 96.9 88.3)
		(end 96.9 86.9)
		(width 0.1)
		(layer "In5.Cu")
		(net 104)
	)
	(segment
		(start 192.9 86.58)
		(end 192.515 86.58)
		(width 0.1)
		(layer "In5.Cu")
		(net 104)
	)
	(segment
		(start 196.4 68.3)
		(end 195.5 69.2)
		(width 0.1)
		(layer "In5.Cu")
		(net 104)
	)
	(segment
		(start 193.88 85.6)
		(end 192.9 86.58)
		(width 0.1)
		(layer "In5.Cu")
		(net 104)
	)
	(segment
		(start 211.1 75.8)
		(end 208.9 73.6)
		(width 0.1)
		(layer "In5.Cu")
		(net 104)
	)
	(segment
		(start 96.9 86.9)
		(end 98 85.8)
		(width 0.1)
		(layer "In5.Cu")
		(net 104)
	)
	(segment
		(start 94.3 90.9)
		(end 96.9 88.3)
		(width 0.1)
		(layer "In5.Cu")
		(net 104)
	)
	(segment
		(start 200.1 68.3)
		(end 196.4 68.3)
		(width 0.1)
		(layer "In5.Cu")
		(net 104)
	)
	(segment
		(start 193.68 79.06)
		(end 193.88 79.26)
		(width 0.1)
		(layer "In5.Cu")
		(net 104)
	)
	(segment
		(start 93.2 97)
		(end 93.2 95.3)
		(width 0.1)
		(layer "In5.Cu")
		(net 104)
	)
	(segment
		(start 93.8 94.7)
		(end 93.8 92.3)
		(width 0.1)
		(layer "In5.Cu")
		(net 104)
	)
	(segment
		(start 193.68 72.52)
		(end 193.68 79.06)
		(width 0.1)
		(layer "In5.Cu")
		(net 104)
	)
	(segment
		(start 93.2 95.3)
		(end 93.8 94.7)
		(width 0.1)
		(layer "In5.Cu")
		(net 104)
	)
	(segment
		(start 216.5 75.8)
		(end 211.1 75.8)
		(width 0.1)
		(layer "In5.Cu")
		(net 104)
	)
	(segment
		(start 93.8 97.6)
		(end 93.2 97)
		(width 0.1)
		(layer "In5.Cu")
		(net 104)
	)
	(segment
		(start 94.3 91.8)
		(end 94.3 90.9)
		(width 0.1)
		(layer "In5.Cu")
		(net 104)
	)
	(segment
		(start 90.7 106.5)
		(end 93.8 103.4)
		(width 0.1)
		(layer "In5.Cu")
		(net 104)
	)
	(segment
		(start 195.5 70.7)
		(end 193.68 72.52)
		(width 0.1)
		(layer "In5.Cu")
		(net 104)
	)
	(segment
		(start 90.7 107.7)
		(end 90.7 106.5)
		(width 0.1)
		(layer "In5.Cu")
		(net 104)
	)
	(segment
		(start 92.1 109.1)
		(end 90.7 107.7)
		(width 0.1)
		(layer "In5.Cu")
		(net 104)
	)
	(segment
		(start 205.4 73.6)
		(end 200.1 68.3)
		(width 0.1)
		(layer "In5.Cu")
		(net 104)
	)
	(segment
		(start 195.5 69.2)
		(end 195.5 70.7)
		(width 0.1)
		(layer "In5.Cu")
		(net 104)
	)
	(segment
		(start 208.9 73.6)
		(end 205.4 73.6)
		(width 0.1)
		(layer "In5.Cu")
		(net 104)
	)
	(segment
		(start 193.88 79.26)
		(end 193.88 85.6)
		(width 0.1)
		(layer "In5.Cu")
		(net 104)
	)
	(segment
		(start 93.8 92.3)
		(end 94.3 91.8)
		(width 0.1)
		(layer "In5.Cu")
		(net 104)
	)
	(segment
		(start 76.6 92.65)
		(end 76.05 92.1)
		(width 0.1)
		(layer "F.Cu")
		(net 105)
	)
	(segment
		(start 122.85 77.65)
		(end 122.85 78.2)
		(width 0.1)
		(layer "F.Cu")
		(net 105)
	)
	(segment
		(start 123.330532 76.65)
		(end 123.330532 77.169468)
		(width 0.1)
		(layer "F.Cu")
		(net 105)
	)
	(segment
		(start 86.45 112.2)
		(end 86.15 111.9)
		(width 0.1)
		(layer "F.Cu")
		(net 105)
	)
	(segment
		(start 81.599998 98.825736)
		(end 81.224264 98.450002)
		(width 0.1)
		(layer "F.Cu")
		(net 105)
	)
	(segment
		(start 75.3 91.85)
		(end 75.3 86.975)
		(width 0.1)
		(layer "F.Cu")
		(net 105)
	)
	(segment
		(start 77.774264 98.450002)
		(end 76.6 97.275738)
		(width 0.1)
		(layer "F.Cu")
		(net 105)
	)
	(segment
		(start 86.15 111.9)
		(end 86.15 110.775736)
		(width 0.1)
		(layer "F.Cu")
		(net 105)
	)
	(segment
		(start 86.15 110.775736)
		(end 85.274265 109.900001)
		(width 0.1)
		(layer "F.Cu")
		(net 105)
	)
	(segment
		(start 123.330532 77.169468)
		(end 122.85 77.65)
		(width 0.1)
		(layer "F.Cu")
		(net 105)
	)
	(segment
		(start 81.874262 109.900001)
		(end 81.599998 109.625737)
		(width 0.1)
		(layer "F.Cu")
		(net 105)
	)
	(segment
		(start 86.9 112.2)
		(end 86.45 112.2)
		(width 0.1)
		(layer "F.Cu")
		(net 105)
	)
	(segment
		(start 81.224264 98.450002)
		(end 77.774264 98.450002)
		(width 0.1)
		(layer "F.Cu")
		(net 105)
	)
	(segment
		(start 85.274265 109.900001)
		(end 81.874262 109.900001)
		(width 0.1)
		(layer "F.Cu")
		(net 105)
	)
	(segment
		(start 81.599998 109.625737)
		(end 81.599998 98.825736)
		(width 0.1)
		(layer "F.Cu")
		(net 105)
	)
	(segment
		(start 75.55 92.1)
		(end 75.3 91.85)
		(width 0.1)
		(layer "F.Cu")
		(net 105)
	)
	(segment
		(start 74.9 86.575)
		(end 75.3 86.975)
		(width 0.1)
		(layer "F.Cu")
		(net 105)
	)
	(segment
		(start 122.85 78.2)
		(end 123.55 78.9)
		(width 0.1)
		(layer "F.Cu")
		(net 105)
	)
	(segment
		(start 76.05 92.1)
		(end 75.55 92.1)
		(width 0.1)
		(layer "F.Cu")
		(net 105)
	)
	(segment
		(start 76.6 97.275738)
		(end 76.6 92.65)
		(width 0.1)
		(layer "F.Cu")
		(net 105)
	)
	(segment
		(start 74.9 86.575)
		(end 74.5 86.575)
		(width 0.1)
		(layer "F.Cu")
		(net 105)
	)
	(via
		(at 86.9 112.2)
		(size 0.45)
		(drill 0.1)
		(layers "F.Cu" "B.Cu")
		(net 105)
	)
	(via
		(at 74.5 86.575)
		(size 0.45)
		(drill 0.1)
		(layers "F.Cu" "B.Cu")
		(net 105)
	)
	(via
		(at 123.55 78.9)
		(size 0.45)
		(drill 0.1)
		(layers "F.Cu" "B.Cu")
		(net 105)
	)
	(segment
		(start 120.775 76.375)
		(end 120.775 77.725)
		(width 0.1)
		(layer "In5.Cu")
		(net 105)
	)
	(segment
		(start 125.2 75.675)
		(end 123.775 74.25)
		(width 0.1)
		(layer "In5.Cu")
		(net 105)
	)
	(segment
		(start 99.474575 93.602635)
		(end 98.2 94.87721)
		(width 0.1)
		(layer "In5.Cu")
		(net 105)
	)
	(segment
		(start 93 113.45)
		(end 91.5 113.45)
		(width 0.1)
		(layer "In5.Cu")
		(net 105)
	)
	(segment
		(start 118.125 80.05)
		(end 115.6 80.05)
		(width 0.1)
		(layer "In5.Cu")
		(net 105)
	)
	(segment
		(start 125.2 76.825)
		(end 125.2 75.675)
		(width 0.1)
		(layer "In5.Cu")
		(net 105)
	)
	(segment
		(start 113.127209 83.150001)
		(end 102.674575 93.602635)
		(width 0.1)
		(layer "In5.Cu")
		(net 105)
	)
	(segment
		(start 96.000001 109.251469)
		(end 95.613235 109.638235)
		(width 0.1)
		(layer "In5.Cu")
		(net 105)
	)
	(segment
		(start 102.674575 93.602635)
		(end 99.474575 93.602635)
		(width 0.1)
		(layer "In5.Cu")
		(net 105)
	)
	(segment
		(start 114.737869 80.912131)
		(end 114.737869 82.137869)
		(width 0.1)
		(layer "In5.Cu")
		(net 105)
	)
	(segment
		(start 120.47 74.605)
		(end 120.47 76.07)
		(width 0.1)
		(layer "In5.Cu")
		(net 105)
	)
	(segment
		(start 120.775 77.725)
		(end 119.875 78.625)
		(width 0.1)
		(layer "In5.Cu")
		(net 105)
	)
	(segment
		(start 91.5 113.45)
		(end 90.5 112.45)
		(width 0.1)
		(layer "In5.Cu")
		(net 105)
	)
	(segment
		(start 98.2 94.87721)
		(end 98.2 100.52721)
		(width 0.1)
		(layer "In5.Cu")
		(net 105)
	)
	(segment
		(start 124.375 77.65)
		(end 125.2 76.825)
		(width 0.1)
		(layer "In5.Cu")
		(net 105)
	)
	(segment
		(start 124.375 78.075)
		(end 124.375 77.65)
		(width 0.1)
		(layer "In5.Cu")
		(net 105)
	)
	(segment
		(start 95.613235 110.836765)
		(end 93 113.45)
		(width 0.1)
		(layer "In5.Cu")
		(net 105)
	)
	(segment
		(start 123.775 74.25)
		(end 120.825 74.25)
		(width 0.1)
		(layer "In5.Cu")
		(net 105)
	)
	(segment
		(start 120.825 74.25)
		(end 120.47 74.605)
		(width 0.1)
		(layer "In5.Cu")
		(net 105)
	)
	(segment
		(start 119.55 78.625)
		(end 118.125 80.05)
		(width 0.1)
		(layer "In5.Cu")
		(net 105)
	)
	(segment
		(start 87.15 112.45)
		(end 86.9 112.2)
		(width 0.1)
		(layer "In5.Cu")
		(net 105)
	)
	(segment
		(start 119.875 78.625)
		(end 119.55 78.625)
		(width 0.1)
		(layer "In5.Cu")
		(net 105)
	)
	(segment
		(start 115.6 80.05)
		(end 114.737869 80.912131)
		(width 0.1)
		(layer "In5.Cu")
		(net 105)
	)
	(segment
		(start 95.613235 109.638235)
		(end 95.613235 110.836765)
		(width 0.1)
		(layer "In5.Cu")
		(net 105)
	)
	(segment
		(start 96.000001 102.727209)
		(end 96.000001 109.251469)
		(width 0.1)
		(layer "In5.Cu")
		(net 105)
	)
	(segment
		(start 120.47 76.07)
		(end 120.775 76.375)
		(width 0.1)
		(layer "In5.Cu")
		(net 105)
	)
	(segment
		(start 114.737869 82.137869)
		(end 113.725737 83.150001)
		(width 0.1)
		(layer "In5.Cu")
		(net 105)
	)
	(segment
		(start 113.725737 83.150001)
		(end 113.127209 83.150001)
		(width 0.1)
		(layer "In5.Cu")
		(net 105)
	)
	(segment
		(start 123.55 78.9)
		(end 124.375 78.075)
		(width 0.1)
		(layer "In5.Cu")
		(net 105)
	)
	(segment
		(start 98.2 100.52721)
		(end 96.000001 102.727209)
		(width 0.1)
		(layer "In5.Cu")
		(net 105)
	)
	(segment
		(start 87.15 112.45)
		(end 90.5 112.45)
		(width 0.1)
		(layer "In5.Cu")
		(net 105)
	)
	(segment
		(start 192.306 147.415)
		(end 191.40263 147.415)
		(width 0.19)
		(layer "F.Cu")
		(net 106)
	)
	(segment
		(start 191.40263 147.415)
		(end 190.211 146.22337)
		(width 0.19)
		(layer "F.Cu")
		(net 106)
	)
	(segment
		(start 190.211 146.22337)
		(end 190.211 141.515)
		(width 0.19)
		(layer "F.Cu")
		(net 106)
	)
	(segment
		(start 192.621 147.1)
		(end 192.306 147.415)
		(width 0.19)
		(layer "F.Cu")
		(net 106)
	)
	(segment
		(start 112.695532 74.885)
		(end 112.695532 74.515)
		(width 0.19)
		(layer "F.Cu")
		(net 106)
	)
	(segment
		(start 190.211 141.515)
		(end 190.326 141.4)
		(width 0.19)
		(layer "F.Cu")
		(net 106)
	)
	(segment
		(start 192.646 147.1)
		(end 192.621 147.1)
		(width 0.19)
		(layer "F.Cu")
		(net 106)
	)
	(segment
		(start 112.430532 75.15)
		(end 112.695532 74.885)
		(width 0.19)
		(layer "F.Cu")
		(net 106)
	)
	(segment
		(start 112.695532 74.515)
		(end 112.580532 74.4)
		(width 0.19)
		(layer "F.Cu")
		(net 106)
	)
	(via
		(at 190.326 141.4)
		(size 0.45)
		(drill 0.1)
		(layers "F.Cu" "B.Cu")
		(net 106)
	)
	(via
		(at 112.580532 74.4)
		(size 0.45)
		(drill 0.1)
		(layers "F.Cu" "B.Cu")
		(net 106)
	)
	(segment
		(start 190.211 141.285)
		(end 190.326 141.4)
		(width 0.19)
		(layer "B.Cu")
		(net 106)
	)
	(segment
		(start 190.211 140.52337)
		(end 190.211 141.285)
		(width 0.19)
		(layer "B.Cu")
		(net 106)
	)
	(segment
		(start 121.57663 84.715)
		(end 122.57663 84.715)
		(width 0.19)
		(layer "B.Cu")
		(net 106)
	)
	(segment
		(start 116.07663 80.215)
		(end 116.57663 80.215)
		(width 0.19)
		(layer "B.Cu")
		(net 106)
	)
	(segment
		(start 153 115.13837)
		(end 153 132.2)
		(width 0.19)
		(layer "B.Cu")
		(net 106)
	)
	(segment
		(start 112.580532 74.4)
		(end 112.695532 74.285)
		(width 0.19)
		(layer "B.Cu")
		(net 106)
	)
	(segment
		(start 116.57663 80.215)
		(end 117.97663 81.615)
		(width 0.19)
		(layer "B.Cu")
		(net 106)
	)
	(segment
		(start 112.695532 73.242838)
		(end 113.32337 72.615)
		(width 0.19)
		(layer "B.Cu")
		(net 106)
	)
	(segment
		(start 115.785 79.92337)
		(end 116.07663 80.215)
		(width 0.19)
		(layer "B.Cu")
		(net 106)
	)
	(segment
		(start 115.085 73.42337)
		(end 115.085 76.22337)
		(width 0.19)
		(layer "B.Cu")
		(net 106)
	)
	(segment
		(start 122.57663 84.715)
		(end 153 115.13837)
		(width 0.19)
		(layer "B.Cu")
		(net 106)
	)
	(segment
		(start 115.085 76.22337)
		(end 116.385 77.52337)
		(width 0.19)
		(layer "B.Cu")
		(net 106)
	)
	(segment
		(start 114.27663 72.615)
		(end 115.085 73.42337)
		(width 0.19)
		(layer "B.Cu")
		(net 106)
	)
	(segment
		(start 160.315 139.515)
		(end 189.20263 139.515)
		(width 0.19)
		(layer "B.Cu")
		(net 106)
	)
	(segment
		(start 116.385 77.52337)
		(end 116.385 78.47663)
		(width 0.19)
		(layer "B.Cu")
		(net 106)
	)
	(segment
		(start 117.97663 81.615)
		(end 118.47663 81.615)
		(width 0.19)
		(layer "B.Cu")
		(net 106)
	)
	(segment
		(start 112.695532 74.285)
		(end 112.695532 73.242838)
		(width 0.19)
		(layer "B.Cu")
		(net 106)
	)
	(segment
		(start 115.785 79.07663)
		(end 115.785 79.92337)
		(width 0.19)
		(layer "B.Cu")
		(net 106)
	)
	(segment
		(start 118.47663 81.615)
		(end 121.57663 84.715)
		(width 0.19)
		(layer "B.Cu")
		(net 106)
	)
	(segment
		(start 113.32337 72.615)
		(end 114.27663 72.615)
		(width 0.19)
		(layer "B.Cu")
		(net 106)
	)
	(segment
		(start 153 132.2)
		(end 160.315 139.515)
		(width 0.19)
		(layer "B.Cu")
		(net 106)
	)
	(segment
		(start 189.20263 139.515)
		(end 190.211 140.52337)
		(width 0.19)
		(layer "B.Cu")
		(net 106)
	)
	(segment
		(start 116.385 78.47663)
		(end 115.785 79.07663)
		(width 0.19)
		(layer "B.Cu")
		(net 106)
	)
	(segment
		(start 98.430532 70.65)
		(end 98.45 70.65)
		(width 0.1)
		(layer "F.Cu")
		(net 107)
	)
	(via
		(at 98.45 70.65)
		(size 0.45)
		(drill 0.1)
		(layers "F.Cu" "B.Cu")
		(net 107)
	)
	(segment
		(start 98.15 70.35)
		(end 98.45 70.65)
		(width 0.1)
		(layer "B.Cu")
		(net 107)
	)
	(segment
		(start 98.15 69.7)
		(end 98.15 70.35)
		(width 0.1)
		(layer "B.Cu")
		(net 107)
	)
	(segment
		(start 134.675 71.15)
		(end 135.25 71.15)
		(width 0.1)
		(layer "F.Cu")
		(net 108)
	)
	(segment
		(start 134.575 71.05)
		(end 134.675 71.15)
		(width 0.1)
		(layer "F.Cu")
		(net 108)
	)
	(segment
		(start 135.25 71.15)
		(end 135.7 71.6)
		(width 0.1)
		(layer "F.Cu")
		(net 108)
	)
	(segment
		(start 135.7 71.6)
		(end 136.480532 71.6)
		(width 0.1)
		(layer "F.Cu")
		(net 108)
	)
	(segment
		(start 136.480532 71.6)
		(end 137.030532 72.15)
		(width 0.1)
		(layer "F.Cu")
		(net 108)
	)
	(via
		(at 134.575 71.05)
		(size 0.45)
		(drill 0.1)
		(layers "F.Cu" "B.Cu")
		(net 108)
	)
	(segment
		(start 134 71.3)
		(end 134 72.4)
		(width 0.1)
		(layer "B.Cu")
		(net 108)
	)
	(segment
		(start 134.25 71.05)
		(end 134 71.3)
		(width 0.1)
		(layer "B.Cu")
		(net 108)
	)
	(segment
		(start 134.575 71.05)
		(end 134.25 71.05)
		(width 0.1)
		(layer "B.Cu")
		(net 108)
	)
	(segment
		(start 133.8 72.6)
		(end 133.2 72.6)
		(width 0.1)
		(layer "B.Cu")
		(net 108)
	)
	(segment
		(start 134 72.4)
		(end 133.8 72.6)
		(width 0.1)
		(layer "B.Cu")
		(net 108)
	)
	(via
		(at 83.2 135.5)
		(size 0.45)
		(drill 0.1)
		(layers "F.Cu" "B.Cu")
		(net 109)
	)
	(via
		(at 75.775 113.225)
		(size 0.45)
		(drill 0.1)
		(layers "F.Cu" "B.Cu")
		(net 109)
	)
	(via
		(at 144.6 92.6)
		(size 0.45)
		(drill 0.1)
		(layers "F.Cu" "B.Cu")
		(net 109)
	)
	(via
		(at 144.230532 81.15)
		(size 0.45)
		(drill 0.1)
		(layers "F.Cu" "B.Cu")
		(net 109)
	)
	(segment
		(start 144.6 91.7)
		(end 144.6 92.6)
		(width 0.1)
		(layer "B.Cu")
		(net 109)
	)
	(segment
		(start 143.75 85.35)
		(end 143.875 85.475)
		(width 0.1)
		(layer "B.Cu")
		(net 109)
	)
	(segment
		(start 143.875 85.475)
		(end 143.875 90.975)
		(width 0.1)
		(layer "B.Cu")
		(net 109)
	)
	(segment
		(start 143.6 83.85)
		(end 143.75 84)
		(width 0.1)
		(layer "B.Cu")
		(net 109)
	)
	(segment
		(start 143.875 90.975)
		(end 144.6 91.7)
		(width 0.1)
		(layer "B.Cu")
		(net 109)
	)
	(segment
		(start 143.6 82.4)
		(end 143.6 83.85)
		(width 0.1)
		(layer "B.Cu")
		(net 109)
	)
	(segment
		(start 144.230532 81.769468)
		(end 143.6 82.4)
		(width 0.1)
		(layer "B.Cu")
		(net 109)
	)
	(segment
		(start 75.775532 113.235)
		(end 75.775532 113.225532)
		(width 0.1)
		(layer "B.Cu")
		(net 109)
	)
	(segment
		(start 144.230532 81.15)
		(end 144.230532 81.769468)
		(width 0.1)
		(layer "B.Cu")
		(net 109)
	)
	(segment
		(start 143.75 84)
		(end 143.75 85.35)
		(width 0.1)
		(layer "B.Cu")
		(net 109)
	)
	(segment
		(start 75.775532 113.225532)
		(end 75.775 113.225)
		(width 0.1)
		(layer "B.Cu")
		(net 109)
	)
	(segment
		(start 144.599998 102.5)
		(end 144.599998 92.600002)
		(width 0.1)
		(layer "In5.Cu")
		(net 109)
	)
	(segment
		(start 144.599998 92.600002)
		(end 144.6 92.6)
		(width 0.1)
		(layer "In5.Cu")
		(net 109)
	)
	(segment
		(start 112.597057 123.699999)
		(end 138.197055 123.699999)
		(width 0.1)
		(layer "In5.Cu")
		(net 109)
	)
	(segment
		(start 144.599998 107.899998)
		(end 144 107.3)
		(width 0.1)
		(layer "In5.Cu")
		(net 109)
	)
	(segment
		(start 83.2 131.6)
		(end 84.6 130.2)
		(width 0.1)
		(layer "In5.Cu")
		(net 109)
	)
	(segment
		(start 144 107.3)
		(end 144 103.099998)
		(width 0.1)
		(layer "In5.Cu")
		(net 109)
	)
	(segment
		(start 84.6 130.2)
		(end 106.097056 130.2)
		(width 0.1)
		(layer "In5.Cu")
		(net 109)
	)
	(segment
		(start 106.097056 130.2)
		(end 112.597057 123.699999)
		(width 0.1)
		(layer "In5.Cu")
		(net 109)
	)
	(segment
		(start 144.599998 117.297056)
		(end 144.599998 107.899998)
		(width 0.1)
		(layer "In5.Cu")
		(net 109)
	)
	(segment
		(start 144 103.099998)
		(end 144.599998 102.5)
		(width 0.1)
		(layer "In5.Cu")
		(net 109)
	)
	(segment
		(start 83.2 135.5)
		(end 83.2 131.6)
		(width 0.1)
		(layer "In5.Cu")
		(net 109)
	)
	(segment
		(start 138.197055 123.699999)
		(end 144.599998 117.297056)
		(width 0.1)
		(layer "In5.Cu")
		(net 109)
	)
	(segment
		(start 79.2 129.1)
		(end 79.2 116.1)
		(width 0.1)
		(layer "In7.Cu")
		(net 109)
	)
	(segment
		(start 83.2 135.5)
		(end 83.2 133.1)
		(width 0.1)
		(layer "In7.Cu")
		(net 109)
	)
	(segment
		(start 76.325 113.225)
		(end 75.775 113.225)
		(width 0.1)
		(layer "In7.Cu")
		(net 109)
	)
	(segment
		(start 83.2 133.1)
		(end 79.2 129.1)
		(width 0.1)
		(layer "In7.Cu")
		(net 109)
	)
	(segment
		(start 79.2 116.1)
		(end 76.325 113.225)
		(width 0.1)
		(layer "In7.Cu")
		(net 109)
	)
	(segment
		(start 221.24 125.925)
		(end 221.652501 125.925)
		(width 0.19)
		(layer "F.Cu")
		(net 110)
	)
	(segment
		(start 234.495532 131.512838)
		(end 234.495532 130.631251)
		(width 0.19)
		(layer "F.Cu")
		(net 110)
	)
	(segment
		(start 234.430532 130.566251)
		(end 234.430532 129.3475)
		(width 0.19)
		(layer "F.Cu")
		(net 110)
	)
	(segment
		(start 230.5 133.115)
		(end 232.89337 133.115)
		(width 0.19)
		(layer "F.Cu")
		(net 110)
	)
	(segment
		(start 232.89337 133.115)
		(end 234.495532 131.512838)
		(width 0.19)
		(layer "F.Cu")
		(net 110)
	)
	(segment
		(start 227.6 133.115)
		(end 230.5 133.115)
		(width 0.19)
		(layer "F.Cu")
		(net 110)
	)
	(segment
		(start 220.468 125.925)
		(end 220.055499 125.925)
		(width 0.19)
		(layer "F.Cu")
		(net 110)
	)
	(segment
		(start 220.055499 125.925)
		(end 219.990499 125.99)
		(width 0.19)
		(layer "F.Cu")
		(net 110)
	)
	(segment
		(start 219.558408 125.99)
		(end 219.543408 126.005)
		(width 0.19)
		(layer "F.Cu")
		(net 110)
	)
	(segment
		(start 234.495532 130.631251)
		(end 234.430532 130.566251)
		(width 0.19)
		(layer "F.Cu")
		(net 110)
	)
	(segment
		(start 224.05163 125.99)
		(end 225.185 127.12337)
		(width 0.19)
		(layer "F.Cu")
		(net 110)
	)
	(segment
		(start 219.543408 126.005)
		(end 219.505 126.005)
		(width 0.19)
		(layer "F.Cu")
		(net 110)
	)
	(segment
		(start 225.185 132.02337)
		(end 226.27663 133.115)
		(width 0.19)
		(layer "F.Cu")
		(net 110)
	)
	(segment
		(start 227 132.640343)
		(end 227.1 132.640343)
		(width 0.19)
		(layer "F.Cu")
		(net 110)
	)
	(segment
		(start 227.3 132.840343)
		(end 227.3 132.915)
		(width 0.19)
		(layer "F.Cu")
		(net 110)
	)
	(segment
		(start 225.185 127.12337)
		(end 225.185 132.02337)
		(width 0.19)
		(layer "F.Cu")
		(net 110)
	)
	(segment
		(start 226.27663 133.115)
		(end 226.6 133.115)
		(width 0.19)
		(layer "F.Cu")
		(net 110)
	)
	(segment
		(start 226.8 132.915)
		(end 226.8 132.840343)
		(width 0.19)
		(layer "F.Cu")
		(net 110)
	)
	(segment
		(start 220.468 125.925)
		(end 221.24 125.925)
		(width 0.19)
		(layer "F.Cu")
		(net 110)
	)
	(segment
		(start 219.990499 125.99)
		(end 219.558408 125.99)
		(width 0.19)
		(layer "F.Cu")
		(net 110)
	)
	(segment
		(start 221.717501 125.99)
		(end 224.05163 125.99)
		(width 0.19)
		(layer "F.Cu")
		(net 110)
	)
	(segment
		(start 227.5 133.115)
		(end 227.6 133.115)
		(width 0.19)
		(layer "F.Cu")
		(net 110)
	)
	(segment
		(start 221.652501 125.925)
		(end 221.717501 125.99)
		(width 0.19)
		(layer "F.Cu")
		(net 110)
	)
	(segment
		(start 219.505 126.005)
		(end 219.175 125.675)
		(width 0.19)
		(layer "F.Cu")
		(net 110)
	)
	(arc
		(start 227.1 132.640343)
		(mid 227.241421 132.698922)
		(end 227.3 132.840343)
		(width 0.19)
		(layer "F.Cu")
		(net 110)
	)
	(arc
		(start 227.3 132.915)
		(mid 227.358579 133.056421)
		(end 227.5 133.115)
		(width 0.19)
		(layer "F.Cu")
		(net 110)
	)
	(arc
		(start 226.6 133.115)
		(mid 226.741421 133.056421)
		(end 226.8 132.915)
		(width 0.19)
		(layer "F.Cu")
		(net 110)
	)
	(arc
		(start 226.8 132.840343)
		(mid 226.858579 132.698922)
		(end 227 132.640343)
		(width 0.19)
		(layer "F.Cu")
		(net 110)
	)
	(via
		(at 102.430532 76.65)
		(size 0.45)
		(drill 0.1)
		(layers "F.Cu" "B.Cu")
		(net 111)
	)
	(via
		(at 75.775532 94.185)
		(size 0.45)
		(drill 0.1)
		(layers "F.Cu" "B.Cu")
		(net 111)
	)
	(segment
		(start 102.430532 76.669468)
		(end 102.430532 76.65)
		(width 0.1)
		(layer "In5.Cu")
		(net 111)
	)
	(segment
		(start 77.625 86.575)
		(end 79.375 84.825)
		(width 0.1)
		(layer "In5.Cu")
		(net 111)
	)
	(segment
		(start 96.2 77.9)
		(end 97.35 77.9)
		(width 0.1)
		(layer "In5.Cu")
		(net 111)
	)
	(segment
		(start 90.5 80.3)
		(end 93.7 77.1)
		(width 0.1)
		(layer "In5.Cu")
		(net 111)
	)
	(segment
		(start 76.59 88.96)
		(end 77.625 87.925)
		(width 0.1)
		(layer "In5.Cu")
		(net 111)
	)
	(segment
		(start 98.15 77.1)
		(end 102 77.1)
		(width 0.1)
		(layer "In5.Cu")
		(net 111)
	)
	(segment
		(start 75.775532 94.185)
		(end 76.59 93.370532)
		(width 0.1)
		(layer "In5.Cu")
		(net 111)
	)
	(segment
		(start 97.35 77.9)
		(end 98.15 77.1)
		(width 0.1)
		(layer "In5.Cu")
		(net 111)
	)
	(segment
		(start 77.625 87.925)
		(end 77.625 86.575)
		(width 0.1)
		(layer "In5.Cu")
		(net 111)
	)
	(segment
		(start 79.375 84.825)
		(end 86.875 84.825)
		(width 0.1)
		(layer "In5.Cu")
		(net 111)
	)
	(segment
		(start 93.7 77.1)
		(end 95.4 77.1)
		(width 0.1)
		(layer "In5.Cu")
		(net 111)
	)
	(segment
		(start 76.59 93.370532)
		(end 76.59 88.96)
		(width 0.1)
		(layer "In5.Cu")
		(net 111)
	)
	(segment
		(start 90.5 81.2)
		(end 90.5 80.3)
		(width 0.1)
		(layer "In5.Cu")
		(net 111)
	)
	(segment
		(start 86.875 84.825)
		(end 90.5 81.2)
		(width 0.1)
		(layer "In5.Cu")
		(net 111)
	)
	(segment
		(start 95.4 77.1)
		(end 96.2 77.9)
		(width 0.1)
		(layer "In5.Cu")
		(net 111)
	)
	(segment
		(start 102 77.1)
		(end 102.430532 76.669468)
		(width 0.1)
		(layer "In5.Cu")
		(net 111)
	)
	(segment
		(start 149.7 113.4)
		(end 149.7 114.4)
		(width 0.1)
		(layer "F.Cu")
		(net 112)
	)
	(segment
		(start 149.2 114.9)
		(end 144.1 114.9)
		(width 0.1)
		(layer "F.Cu")
		(net 112)
	)
	(segment
		(start 148.248 113)
		(end 148.9 112.348)
		(width 0.1)
		(layer "F.Cu")
		(net 112)
	)
	(segment
		(start 143.2 115.8)
		(end 143.2 116.4)
		(width 0.1)
		(layer "F.Cu")
		(net 112)
	)
	(segment
		(start 149.7 114.4)
		(end 149.2 114.9)
		(width 0.1)
		(layer "F.Cu")
		(net 112)
	)
	(segment
		(start 147.48 113)
		(end 148.248 113)
		(width 0.1)
		(layer "F.Cu")
		(net 112)
	)
	(segment
		(start 144.1 114.9)
		(end 143.2 115.8)
		(width 0.1)
		(layer "F.Cu")
		(net 112)
	)
	(segment
		(start 149.748 112.348)
		(end 150.144 112.744)
		(width 0.1)
		(layer "F.Cu")
		(net 112)
	)
	(segment
		(start 150.144 112.744)
		(end 151.23 112.744)
		(width 0.1)
		(layer "F.Cu")
		(net 112)
	)
	(segment
		(start 149.748 112.348)
		(end 148.9 112.348)
		(width 0.1)
		(layer "F.Cu")
		(net 112)
	)
	(via
		(at 135.930532 82.65)
		(size 0.45)
		(drill 0.1)
		(layers "F.Cu" "B.Cu")
		(net 112)
	)
	(via
		(at 149.7 113.4)
		(size 0.45)
		(drill 0.1)
		(layers "F.Cu" "B.Cu")
		(net 112)
	)
	(via
		(at 148.9 112.348)
		(size 0.45)
		(drill 0.1)
		(layers "F.Cu" "B.Cu")
		(net 112)
	)
	(via
		(at 143.2 116.4)
		(size 0.45)
		(drill 0.1)
		(layers "F.Cu" "B.Cu")
		(net 112)
	)
	(via
		(at 129.9 115.5)
		(size 0.45)
		(drill 0.1)
		(layers "F.Cu" "B.Cu")
		(net 112)
	)
	(segment
		(start 149.7 113.4)
		(end 149.7 113.05)
		(width 0.1)
		(layer "B.Cu")
		(net 112)
	)
	(segment
		(start 148.998 112.348)
		(end 148.9 112.348)
		(width 0.1)
		(layer "B.Cu")
		(net 112)
	)
	(segment
		(start 149.7 113.05)
		(end 148.998 112.348)
		(width 0.1)
		(layer "B.Cu")
		(net 112)
	)
	(segment
		(start 129.9 116)
		(end 130.3 116.4)
		(width 0.1)
		(layer "B.Cu")
		(net 112)
	)
	(segment
		(start 130.3 116.4)
		(end 143.2 116.4)
		(width 0.1)
		(layer "B.Cu")
		(net 112)
	)
	(segment
		(start 129.9 115.5)
		(end 129.9 116)
		(width 0.1)
		(layer "B.Cu")
		(net 112)
	)
	(segment
		(start 135.2 87.1)
		(end 135.2 86.6)
		(width 0.1)
		(layer "In5.Cu")
		(net 112)
	)
	(segment
		(start 135.7 83.7)
		(end 135.930532 83.469468)
		(width 0.1)
		(layer "In5.Cu")
		(net 112)
	)
	(segment
		(start 135.2 86.6)
		(end 135.7 86.1)
		(width 0.1)
		(layer "In5.Cu")
		(net 112)
	)
	(segment
		(start 129.9 115.5)
		(end 129.8 115.4)
		(width 0.1)
		(layer "In5.Cu")
		(net 112)
	)
	(segment
		(start 135.930532 83.469468)
		(end 135.930532 82.65)
		(width 0.1)
		(layer "In5.Cu")
		(net 112)
	)
	(segment
		(start 129.8 92.5)
		(end 135.2 87.1)
		(width 0.1)
		(layer "In5.Cu")
		(net 112)
	)
	(segment
		(start 129.8 115.4)
		(end 129.8 92.5)
		(width 0.1)
		(layer "In5.Cu")
		(net 112)
	)
	(segment
		(start 135.7 86.1)
		(end 135.7 83.7)
		(width 0.1)
		(layer "In5.Cu")
		(net 112)
	)
	(segment
		(start 125.405532 80.275)
		(end 125.280532 80.4)
		(width 0.17)
		(layer "F.Cu")
		(net 113)
	)
	(segment
		(start 125.130532 79.65)
		(end 125.405532 79.925)
		(width 0.17)
		(layer "F.Cu")
		(net 113)
	)
	(segment
		(start 125.405532 79.925)
		(end 125.405532 80.275)
		(width 0.17)
		(layer "F.Cu")
		(net 113)
	)
	(via
		(at 125.280532 80.4)
		(size 0.45)
		(drill 0.1)
		(layers "F.Cu" "B.Cu")
		(net 113)
	)
	(via
		(at 63.1 104.011)
		(size 0.45)
		(drill 0.1)
		(layers "F.Cu" "B.Cu")
		(net 113)
	)
	(segment
		(start 63.615999 103.886)
		(end 63.225 103.886)
		(width 0.17)
		(layer "B.Cu")
		(net 113)
	)
	(segment
		(start 64.59 103.96)
		(end 63.689999 103.96)
		(width 0.17)
		(layer "B.Cu")
		(net 113)
	)
	(segment
		(start 63.225 103.886)
		(end 63.1 104.011)
		(width 0.17)
		(layer "B.Cu")
		(net 113)
	)
	(segment
		(start 63.689999 103.96)
		(end 63.615999 103.886)
		(width 0.17)
		(layer "B.Cu")
		(net 113)
	)
	(segment
		(start 86.7091 77.4125)
		(end 90.5216 77.4125)
		(width 0.125)
		(layer "In2.Cu")
		(net 113)
	)
	(segment
		(start 104.9791 78.2425)
		(end 104.9791 77.97)
		(width 0.125)
		(layer "In2.Cu")
		(net 113)
	)
	(segment
		(start 86.1591 77.775)
		(end 86.3466 77.775)
		(width 0.125)
		(layer "In2.Cu")
		(net 113)
	)
	(segment
		(start 108.573365 78.440575)
		(end 108.95697 78.056969)
		(width 0.125)
		(layer "In2.Cu")
		(net 113)
	)
	(segment
		(start 125.2534 79.9125)
		(end 125.468031 80.127131)
		(width 0.125)
		(layer "In2.Cu")
		(net 113)
	)
	(segment
		(start 124.9466 79.9125)
		(end 125.2534 79.9125)
		(width 0.125)
		(layer "In2.Cu")
		(net 113)
	)
	(segment
		(start 122.2534 77.4125)
		(end 122.6875 77.8466)
		(width 0.125)
		(layer "In2.Cu")
		(net 113)
	)
	(segment
		(start 85.6091 77.05)
		(end 85.7966 77.05)
		(width 0.125)
		(layer "In2.Cu")
		(net 113)
	)
	(segment
		(start 100.5791 77.7425)
		(end 100.5791 77.21875)
		(width 0.125)
		(layer "In2.Cu")
		(net 113)
	)
	(segment
		(start 99.8041 77.1575)
		(end 99.8041 77.7425)
		(width 0.125)
		(layer "In2.Cu")
		(net 113)
	)
	(segment
		(start 91.9116 77.0125)
		(end 92.8284 77.0125)
		(width 0.125)
		(layer "In2.Cu")
		(net 113)
	)
	(segment
		(start 93.2284 77.4125)
		(end 95.5534 77.4125)
		(width 0.125)
		(layer "In2.Cu")
		(net 113)
	)
	(segment
		(start 91.5791 76.6075)
		(end 91.5791 76.68)
		(width 0.125)
		(layer "In2.Cu")
		(net 113)
	)
	(segment
		(start 109.5534 78.8125)
		(end 112.1466 78.8125)
		(width 0.125)
		(layer "In2.Cu")
		(net 113)
	)
	(segment
		(start 83.5466 82.2125)
		(end 84.2125 81.5466)
		(width 0.125)
		(layer "In2.Cu")
		(net 113)
	)
	(segment
		(start 64.6125 100.9534)
		(end 64.3125 100.6534)
		(width 0.125)
		(layer "In2.Cu")
		(net 113)
	)
	(segment
		(start 101.7866 77.5125)
		(end 103.6534 77.5125)
		(width 0.125)
		(layer "In2.Cu")
		(net 113)
	)
	(segment
		(start 105.0866 77.8625)
		(end 105.6966 77.8625)
		(width 0.125)
		(layer "In2.Cu")
		(net 113)
	)
	(segment
		(start 100.64785 77.15)
		(end 100.83535 77.15)
		(width 0.125)
		(layer "In2.Cu")
		(net 113)
	)
	(segment
		(start 98.7041 77.0575)
		(end 98.7041 77.18)
		(width 0.125)
		(layer "In2.Cu")
		(net 113)
	)
	(segment
		(start 90.5216 77.4125)
		(end 90.9216 77.0125)
		(width 0.125)
		(layer "In2.Cu")
		(net 113)
	)
	(segment
		(start 91.3616 76.5)
		(end 91.4716 76.5)
		(width 0.125)
		(layer "In2.Cu")
		(net 113)
	)
	(segment
		(start 108.95697 78.05697)
		(end 109.032984 77.980956)
		(width 0.125)
		(layer "In2.Cu")
		(net 113)
	)
	(segment
		(start 64.3125 87.1266)
		(end 66.5625 84.8766)
		(width 0.125)
		(layer "In2.Cu")
		(net 113)
	)
	(segment
		(start 100.9041 77.21875)
		(end 100.9041 78.2425)
		(width 0.125)
		(layer "In2.Cu")
		(net 113)
	)
	(segment
		(start 104.2041 77.97)
		(end 104.2041 78.2425)
		(width 0.125)
		(layer "In2.Cu")
		(net 113)
	)
	(segment
		(start 99.4791 77.18)
		(end 99.4791 77.1575)
		(width 0.125)
		(layer "In2.Cu")
		(net 113)
	)
	(segment
		(start 106.0466 77.5125)
		(end 108.2534 77.5125)
		(width 0.125)
		(layer "In2.Cu")
		(net 113)
	)
	(segment
		(start 99.5866 77.05)
		(end 99.6966 77.05)
		(width 0.125)
		(layer "In2.Cu")
		(net 113)
	)
	(segment
		(start 113.3466 77.6125)
		(end 116.3534 77.6125)
		(width 0.125)
		(layer "In2.Cu")
		(net 113)
	)
	(segment
		(start 64.3125 100.6534)
		(end 64.3125 87.1266)
		(width 0.125)
		(layer "In2.Cu")
		(net 113)
	)
	(segment
		(start 101.2366 78.575)
		(end 101.3466 78.575)
		(width 0.125)
		(layer "In2.Cu")
		(net 113)
	)
	(segment
		(start 68.8966 82.2125)
		(end 83.5466 82.2125)
		(width 0.125)
		(layer "In2.Cu")
		(net 113)
	)
	(segment
		(start 85.388063 78.37412)
		(end 84.912533 77.89859)
		(width 0.125)
		(layer "In2.Cu")
		(net 113)
	)
	(segment
		(start 121.759903 77.4125)
		(end 122.2534 77.4125)
		(width 0.125)
		(layer "In2.Cu")
		(net 113)
	)
	(segment
		(start 84.364527 78.446599)
		(end 84.840056 78.922128)
		(width 0.125)
		(layer "In2.Cu")
		(net 113)
	)
	(segment
		(start 116.3534 77.6125)
		(end 117.6534 78.9125)
		(width 0.125)
		(layer "In2.Cu")
		(net 113)
	)
	(segment
		(start 112.1466 78.8125)
		(end 113.3466 77.6125)
		(width 0.125)
		(layer "In2.Cu")
		(net 113)
	)
	(segment
		(start 122.6875 79.1466)
		(end 123.8534 80.3125)
		(width 0.125)
		(layer "In2.Cu")
		(net 113)
	)
	(segment
		(start 105.6966 77.8625)
		(end 106.0466 77.5125)
		(width 0.125)
		(layer "In2.Cu")
		(net 113)
	)
	(segment
		(start 125.468031 80.212501)
		(end 125.280532 80.4)
		(width 0.125)
		(layer "In2.Cu")
		(net 113)
	)
	(segment
		(start 92.8284 77.0125)
		(end 93.2284 77.4125)
		(width 0.125)
		(layer "In2.Cu")
		(net 113)
	)
	(segment
		(start 85.86535 77.11875)
		(end 85.86535 77.48125)
		(width 0.125)
		(layer "In2.Cu")
		(net 113)
	)
	(segment
		(start 84.212499 78.446599)
		(end 84.2125 81.5466)
		(width 0.125)
		(layer "In2.Cu")
		(net 113)
	)
	(segment
		(start 122.6875 77.8466)
		(end 122.6875 79.1466)
		(width 0.125)
		(layer "In2.Cu")
		(net 113)
	)
	(segment
		(start 64.6125 103.1466)
		(end 64.6125 100.9534)
		(width 0.125)
		(layer "In2.Cu")
		(net 113)
	)
	(segment
		(start 109.112535 77.901408)
		(end 109.588063 77.425877)
		(width 0.125)
		(layer "In2.Cu")
		(net 113)
	)
	(segment
		(start 104.0034 77.8625)
		(end 104.0966 77.8625)
		(width 0.125)
		(layer "In2.Cu")
		(net 113)
	)
	(segment
		(start 96.3534 78.2125)
		(end 97.3466 78.2125)
		(width 0.125)
		(layer "In2.Cu")
		(net 113)
	)
	(segment
		(start 100.1366 78.075)
		(end 100.2466 78.075)
		(width 0.125)
		(layer "In2.Cu")
		(net 113)
	)
	(segment
		(start 121.339903 77.5325)
		(end 121.339903 77.581903)
		(width 0.125)
		(layer "In2.Cu")
		(net 113)
	)
	(segment
		(start 95.5534 77.4125)
		(end 96.3534 78.2125)
		(width 0.125)
		(layer "In2.Cu")
		(net 113)
	)
	(segment
		(start 63.935599 103.823501)
		(end 64.6125 103.1466)
		(width 0.125)
		(layer "In2.Cu")
		(net 113)
	)
	(segment
		(start 99.0366 77.5125)
		(end 99.1466 77.5125)
		(width 0.125)
		(layer "In2.Cu")
		(net 113)
	)
	(segment
		(start 63.1 104.011)
		(end 63.287499 103.823501)
		(width 0.125)
		(layer "In2.Cu")
		(net 113)
	)
	(segment
		(start 108.95697 78.056969)
		(end 108.95697 78.05697)
		(width 0.125)
		(layer "In2.Cu")
		(net 113)
	)
	(segment
		(start 109.032984 77.980956)
		(end 109.112535 77.901408)
		(width 0.125)
		(layer "In2.Cu")
		(net 113)
	)
	(segment
		(start 91.2541 76.68)
		(end 91.2541 76.6075)
		(width 0.125)
		(layer "In2.Cu")
		(net 113)
	)
	(segment
		(start 98.4866 76.95)
		(end 98.5966 76.95)
		(width 0.125)
		(layer "In2.Cu")
		(net 113)
	)
	(segment
		(start 97.3466 78.2125)
		(end 98.0466 77.5125)
		(width 0.125)
		(layer "In2.Cu")
		(net 113)
	)
	(segment
		(start 124.5466 80.3125)
		(end 124.9466 79.9125)
		(width 0.125)
		(layer "In2.Cu")
		(net 113)
	)
	(segment
		(start 125.468031 80.127131)
		(end 125.468031 80.212501)
		(width 0.125)
		(layer "In2.Cu")
		(net 113)
	)
	(segment
		(start 109.740091 77.425877)
		(end 109.817872 77.503658)
		(width 0.125)
		(layer "In2.Cu")
		(net 113)
	)
	(segment
		(start 121.459903 77.701903)
		(end 121.519903 77.701903)
		(width 0.125)
		(layer "In2.Cu")
		(net 113)
	)
	(segment
		(start 109.817872 77.655686)
		(end 109.342343 78.131216)
		(width 0.125)
		(layer "In2.Cu")
		(net 113)
	)
	(segment
		(start 98.3791 77.18)
		(end 98.3791 77.0575)
		(width 0.125)
		(layer "In2.Cu")
		(net 113)
	)
	(segment
		(start 108.025358 78.362794)
		(end 108.103139 78.440575)
		(width 0.125)
		(layer "In2.Cu")
		(net 113)
	)
	(segment
		(start 63.287499 103.823501)
		(end 63.935599 103.823501)
		(width 0.125)
		(layer "In2.Cu")
		(net 113)
	)
	(segment
		(start 109.342343 78.601442)
		(end 109.5534 78.8125)
		(width 0.125)
		(layer "In2.Cu")
		(net 113)
	)
	(segment
		(start 121.639903 77.581903)
		(end 121.639903 77.5325)
		(width 0.125)
		(layer "In2.Cu")
		(net 113)
	)
	(segment
		(start 84.990316 77.668782)
		(end 85.2466 77.4125)
		(width 0.125)
		(layer "In2.Cu")
		(net 113)
	)
	(segment
		(start 66.5625 84.5466)
		(end 68.8966 82.2125)
		(width 0.125)
		(layer "In2.Cu")
		(net 113)
	)
	(segment
		(start 108.2534 77.5125)
		(end 108.2534 77.512499)
		(width 0.125)
		(layer "In2.Cu")
		(net 113)
	)
	(segment
		(start 66.5625 84.8766)
		(end 66.5625 84.5466)
		(width 0.125)
		(layer "In2.Cu")
		(net 113)
	)
	(segment
		(start 84.912533 77.746562)
		(end 84.990316 77.668782)
		(width 0.125)
		(layer "In2.Cu")
		(net 113)
	)
	(segment
		(start 103.6534 77.5125)
		(end 104.0034 77.8625)
		(width 0.125)
		(layer "In2.Cu")
		(net 113)
	)
	(segment
		(start 121.1466 77.4125)
		(end 121.219903 77.4125)
		(width 0.125)
		(layer "In2.Cu")
		(net 113)
	)
	(segment
		(start 85.310282 78.922128)
		(end 85.388063 78.844346)
		(width 0.125)
		(layer "In2.Cu")
		(net 113)
	)
	(segment
		(start 117.6534 78.9125)
		(end 119.6466 78.9125)
		(width 0.125)
		(layer "In2.Cu")
		(net 113)
	)
	(segment
		(start 101.6791 78.2425)
		(end 101.6791 77.62)
		(width 0.125)
		(layer "In2.Cu")
		(net 113)
	)
	(segment
		(start 123.8534 80.3125)
		(end 124.5466 80.3125)
		(width 0.125)
		(layer "In2.Cu")
		(net 113)
	)
	(segment
		(start 119.6466 78.9125)
		(end 121.1466 77.4125)
		(width 0.125)
		(layer "In2.Cu")
		(net 113)
	)
	(segment
		(start 104.5366 78.575)
		(end 104.6466 78.575)
		(width 0.125)
		(layer "In2.Cu")
		(net 113)
	)
	(segment
		(start 108.2534 77.664527)
		(end 108.025358 77.892568)
		(width 0.125)
		(layer "In2.Cu")
		(net 113)
	)
	(arc
		(start 100.5791 77.21875)
		(mid 100.599236 77.170136)
		(end 100.64785 77.15)
		(width 0.125)
		(layer "In2.Cu")
		(net 113)
	)
	(arc
		(start 98.0466 77.5125)
		(mid 98.281713 77.415113)
		(end 98.3791 77.18)
		(width 0.125)
		(layer "In2.Cu")
		(net 113)
	)
	(arc
		(start 121.219903 77.4125)
		(mid 121.304756 77.447647)
		(end 121.339903 77.5325)
		(width 0.125)
		(layer "In2.Cu")
		(net 113)
	)
	(arc
		(start 84.840056 78.922128)
		(mid 85.075169 79.019515)
		(end 85.310282 78.922128)
		(width 0.125)
		(layer "In2.Cu")
		(net 113)
	)
	(arc
		(start 121.519903 77.701903)
		(mid 121.604756 77.666756)
		(end 121.639903 77.581903)
		(width 0.125)
		(layer "In2.Cu")
		(net 113)
	)
	(arc
		(start 104.0966 77.8625)
		(mid 104.172614 77.893986)
		(end 104.2041 77.97)
		(width 0.125)
		(layer "In2.Cu")
		(net 113)
	)
	(arc
		(start 109.342343 78.131216)
		(mid 109.244956 78.366329)
		(end 109.342343 78.601442)
		(width 0.125)
		(layer "In2.Cu")
		(net 113)
	)
	(arc
		(start 85.2466 77.4125)
		(mid 85.454313 77.326463)
		(end 85.54035 77.11875)
		(width 0.125)
		(layer "In2.Cu")
		(net 113)
	)
	(arc
		(start 98.3791 77.0575)
		(mid 98.410586 76.981486)
		(end 98.4866 76.95)
		(width 0.125)
		(layer "In2.Cu")
		(net 113)
	)
	(arc
		(start 98.5966 76.95)
		(mid 98.672614 76.981486)
		(end 98.7041 77.0575)
		(width 0.125)
		(layer "In2.Cu")
		(net 113)
	)
	(arc
		(start 84.912533 77.89859)
		(mid 84.881047 77.822576)
		(end 84.912533 77.746562)
		(width 0.125)
		(layer "In2.Cu")
		(net 113)
	)
	(arc
		(start 99.4791 77.1575)
		(mid 99.510586 77.081486)
		(end 99.5866 77.05)
		(width 0.125)
		(layer "In2.Cu")
		(net 113)
	)
	(arc
		(start 99.1466 77.5125)
		(mid 99.381713 77.415113)
		(end 99.4791 77.18)
		(width 0.125)
		(layer "In2.Cu")
		(net 113)
	)
	(arc
		(start 86.3466 77.775)
		(mid 86.554313 77.688963)
		(end 86.64035 77.48125)
		(width 0.125)
		(layer "In2.Cu")
		(net 113)
	)
	(arc
		(start 100.9041 78.2425)
		(mid 101.001487 78.477613)
		(end 101.2366 78.575)
		(width 0.125)
		(layer "In2.Cu")
		(net 113)
	)
	(arc
		(start 98.7041 77.18)
		(mid 98.801487 77.415113)
		(end 99.0366 77.5125)
		(width 0.125)
		(layer "In2.Cu")
		(net 113)
	)
	(arc
		(start 85.388063 78.844346)
		(mid 85.48545 78.609233)
		(end 85.388063 78.37412)
		(width 0.125)
		(layer "In2.Cu")
		(net 113)
	)
	(arc
		(start 108.103139 78.440575)
		(mid 108.338252 78.537962)
		(end 108.573365 78.440575)
		(width 0.125)
		(layer "In2.Cu")
		(net 113)
	)
	(arc
		(start 109.588063 77.425877)
		(mid 109.664077 77.394391)
		(end 109.740091 77.425877)
		(width 0.125)
		(layer "In2.Cu")
		(net 113)
	)
	(arc
		(start 108.2534 77.512499)
		(mid 108.284886 77.588513)
		(end 108.2534 77.664527)
		(width 0.125)
		(layer "In2.Cu")
		(net 113)
	)
	(arc
		(start 90.9216 77.0125)
		(mid 91.156713 76.915113)
		(end 91.2541 76.68)
		(width 0.125)
		(layer "In2.Cu")
		(net 113)
	)
	(arc
		(start 101.3466 78.575)
		(mid 101.581713 78.477613)
		(end 101.6791 78.2425)
		(width 0.125)
		(layer "In2.Cu")
		(net 113)
	)
	(arc
		(start 85.54035 77.11875)
		(mid 85.560486 77.070136)
		(end 85.6091 77.05)
		(width 0.125)
		(layer "In2.Cu")
		(net 113)
	)
	(arc
		(start 109.817872 77.503658)
		(mid 109.849358 77.579672)
		(end 109.817872 77.655686)
		(width 0.125)
		(layer "In2.Cu")
		(net 113)
	)
	(arc
		(start 86.64035 77.48125)
		(mid 86.660486 77.432636)
		(end 86.7091 77.4125)
		(width 0.125)
		(layer "In2.Cu")
		(net 113)
	)
	(arc
		(start 99.6966 77.05)
		(mid 99.772614 77.081486)
		(end 99.8041 77.1575)
		(width 0.125)
		(layer "In2.Cu")
		(net 113)
	)
	(arc
		(start 108.025358 77.892568)
		(mid 107.927971 78.127681)
		(end 108.025358 78.362794)
		(width 0.125)
		(layer "In2.Cu")
		(net 113)
	)
	(arc
		(start 100.2466 78.075)
		(mid 100.481713 77.977613)
		(end 100.5791 77.7425)
		(width 0.125)
		(layer "In2.Cu")
		(net 113)
	)
	(arc
		(start 104.9791 77.97)
		(mid 105.010586 77.893986)
		(end 105.0866 77.8625)
		(width 0.125)
		(layer "In2.Cu")
		(net 113)
	)
	(arc
		(start 104.2041 78.2425)
		(mid 104.301487 78.477613)
		(end 104.5366 78.575)
		(width 0.125)
		(layer "In2.Cu")
		(net 113)
	)
	(arc
		(start 99.8041 77.7425)
		(mid 99.901487 77.977613)
		(end 100.1366 78.075)
		(width 0.125)
		(layer "In2.Cu")
		(net 113)
	)
	(arc
		(start 121.639903 77.5325)
		(mid 121.67505 77.447647)
		(end 121.759903 77.4125)
		(width 0.125)
		(layer "In2.Cu")
		(net 113)
	)
	(arc
		(start 84.212499 78.446599)
		(mid 84.288513 78.415113)
		(end 84.364527 78.446599)
		(width 0.125)
		(layer "In2.Cu")
		(net 113)
	)
	(arc
		(start 100.83535 77.15)
		(mid 100.883964 77.170136)
		(end 100.9041 77.21875)
		(width 0.125)
		(layer "In2.Cu")
		(net 113)
	)
	(arc
		(start 101.6791 77.62)
		(mid 101.710586 77.543986)
		(end 101.7866 77.5125)
		(width 0.125)
		(layer "In2.Cu")
		(net 113)
	)
	(arc
		(start 91.4716 76.5)
		(mid 91.547614 76.531486)
		(end 91.5791 76.6075)
		(width 0.125)
		(layer "In2.Cu")
		(net 113)
	)
	(arc
		(start 91.2541 76.6075)
		(mid 91.285586 76.531486)
		(end 91.3616 76.5)
		(width 0.125)
		(layer "In2.Cu")
		(net 113)
	)
	(arc
		(start 91.5791 76.68)
		(mid 91.676487 76.915113)
		(end 91.9116 77.0125)
		(width 0.125)
		(layer "In2.Cu")
		(net 113)
	)
	(arc
		(start 85.86535 77.48125)
		(mid 85.951387 77.688963)
		(end 86.1591 77.775)
		(width 0.125)
		(layer "In2.Cu")
		(net 113)
	)
	(arc
		(start 85.7966 77.05)
		(mid 85.845214 77.070136)
		(end 85.86535 77.11875)
		(width 0.125)
		(layer "In2.Cu")
		(net 113)
	)
	(arc
		(start 104.6466 78.575)
		(mid 104.881713 78.477613)
		(end 104.9791 78.2425)
		(width 0.125)
		(layer "In2.Cu")
		(net 113)
	)
	(arc
		(start 121.339903 77.581903)
		(mid 121.37505 77.666756)
		(end 121.459903 77.701903)
		(width 0.125)
		(layer "In2.Cu")
		(net 113)
	)
	(via
		(at 75.775532 97.995)
		(size 0.45)
		(drill 0.1)
		(layers "F.Cu" "B.Cu")
		(net 114)
	)
	(via
		(at 103.330532 76.65)
		(size 0.45)
		(drill 0.1)
		(layers "F.Cu" "B.Cu")
		(net 114)
	)
	(segment
		(start 96.1 78.15)
		(end 97.55 78.15)
		(width 0.1)
		(layer "In5.Cu")
		(net 114)
	)
	(segment
		(start 77.5 93.1)
		(end 77.5 88.8)
		(width 0.1)
		(layer "In5.Cu")
		(net 114)
	)
	(segment
		(start 76.4 94.2)
		(end 77.5 93.1)
		(width 0.1)
		(layer "In5.Cu")
		(net 114)
	)
	(segment
		(start 79.55 85.95)
		(end 88.1 85.95)
		(width 0.1)
		(layer "In5.Cu")
		(net 114)
	)
	(segment
		(start 77.925 88.375)
		(end 77.925 87.575)
		(width 0.1)
		(layer "In5.Cu")
		(net 114)
	)
	(segment
		(start 77.5 88.8)
		(end 77.925 88.375)
		(width 0.1)
		(layer "In5.Cu")
		(net 114)
	)
	(segment
		(start 91.3 82.75)
		(end 91.3 80.2)
		(width 0.1)
		(layer "In5.Cu")
		(net 114)
	)
	(segment
		(start 93.8 77.7)
		(end 95.65 77.7)
		(width 0.1)
		(layer "In5.Cu")
		(net 114)
	)
	(segment
		(start 88.1 85.95)
		(end 91.3 82.75)
		(width 0.1)
		(layer "In5.Cu")
		(net 114)
	)
	(segment
		(start 77.925 87.575)
		(end 79.55 85.95)
		(width 0.1)
		(layer "In5.Cu")
		(net 114)
	)
	(segment
		(start 102.380532 77.6)
		(end 103.330532 76.65)
		(width 0.1)
		(layer "In5.Cu")
		(net 114)
	)
	(segment
		(start 97.55 78.15)
		(end 98.1 77.6)
		(width 0.1)
		(layer "In5.Cu")
		(net 114)
	)
	(segment
		(start 76.4 97.370532)
		(end 76.4 94.2)
		(width 0.1)
		(layer "In5.Cu")
		(net 114)
	)
	(segment
		(start 98.1 77.6)
		(end 102.380532 77.6)
		(width 0.1)
		(layer "In5.Cu")
		(net 114)
	)
	(segment
		(start 91.3 80.2)
		(end 93.8 77.7)
		(width 0.1)
		(layer "In5.Cu")
		(net 114)
	)
	(segment
		(start 95.65 77.7)
		(end 96.1 78.15)
		(width 0.1)
		(layer "In5.Cu")
		(net 114)
	)
	(segment
		(start 75.775532 97.995)
		(end 76.4 97.370532)
		(width 0.1)
		(layer "In5.Cu")
		(net 114)
	)
	(segment
		(start 231.430532 129.3475)
		(end 231.430532 130.460532)
		(width 0.2)
		(layer "F.Cu")
		(net 115)
	)
	(segment
		(start 233.930532 131.039468)
		(end 233.77 131.2)
		(width 0.2)
		(layer "F.Cu")
		(net 115)
	)
	(segment
		(start 233.930532 127.0725)
		(end 233.930532 125.760532)
		(width 0.2)
		(layer "F.Cu")
		(net 115)
	)
	(segment
		(start 232.060532 134.323)
		(end 231.277 134.323)
		(width 0.1)
		(layer "F.Cu")
		(net 115)
	)
	(segment
		(start 231.430532 126.039468)
		(end 231.57 125.9)
		(width 0.2)
		(layer "F.Cu")
		(net 115)
	)
	(segment
		(start 233.930532 129.3475)
		(end 233.930532 131.039468)
		(width 0.2)
		(layer "F.Cu")
		(net 115)
	)
	(segment
		(start 214.48 131.8)
		(end 215.2 131.8)
		(width 0.1)
		(layer "F.Cu")
		(net 115)
	)
	(segment
		(start 231.430532 128.260532)
		(end 231.37 128.2)
		(width 0.2)
		(layer "F.Cu")
		(net 115)
	)
	(segment
		(start 233.930532 129.3475)
		(end 233.930532 128.239468)
		(width 0.2)
		(layer "F.Cu")
		(net 115)
	)
	(segment
		(start 231.430532 129.3475)
		(end 231.430532 128.260532)
		(width 0.2)
		(layer "F.Cu")
		(net 115)
	)
	(segment
		(start 231.430532 128.139468)
		(end 231.37 128.2)
		(width 0.2)
		(layer "F.Cu")
		(net 115)
	)
	(segment
		(start 231.430532 130.460532)
		(end 231.47 130.5)
		(width 0.2)
		(layer "F.Cu")
		(net 115)
	)
	(segment
		(start 233.930532 125.760532)
		(end 233.57 125.4)
		(width 0.2)
		(layer "F.Cu")
		(net 115)
	)
	(segment
		(start 233.930532 127.0725)
		(end 233.930532 128.160532)
		(width 0.2)
		(layer "F.Cu")
		(net 115)
	)
	(segment
		(start 231.430532 127.0725)
		(end 231.430532 128.139468)
		(width 0.2)
		(layer "F.Cu")
		(net 115)
	)
	(segment
		(start 231.099 134.501)
		(end 231.099 134.947)
		(width 0.1)
		(layer "F.Cu")
		(net 115)
	)
	(segment
		(start 233.930532 128.239468)
		(end 233.97 128.2)
		(width 0.2)
		(layer "F.Cu")
		(net 115)
	)
	(segment
		(start 233.930532 128.160532)
		(end 233.97 128.2)
		(width 0.2)
		(layer "F.Cu")
		(net 115)
	)
	(segment
		(start 231.430532 127.0725)
		(end 231.430532 126.039468)
		(width 0.2)
		(layer "F.Cu")
		(net 115)
	)
	(segment
		(start 231.277 134.323)
		(end 231.099 134.501)
		(width 0.1)
		(layer "F.Cu")
		(net 115)
	)
	(via
		(at 231.47 130.5)
		(size 0.45)
		(drill 0.1)
		(layers "F.Cu" "B.Cu")
		(net 115)
	)
	(via
		(at 233.77 131.2)
		(size 0.45)
		(drill 0.1)
		(layers "F.Cu" "B.Cu")
		(net 115)
	)
	(via
		(at 231.099 134.947)
		(size 0.45)
		(drill 0.1)
		(layers "F.Cu" "B.Cu")
		(net 115)
	)
	(via
		(at 231.37 128.2)
		(size 0.45)
		(drill 0.1)
		(layers "F.Cu" "B.Cu")
		(net 115)
	)
	(via
		(at 231.57 125.9)
		(size 0.45)
		(drill 0.1)
		(layers "F.Cu" "B.Cu")
		(net 115)
	)
	(via
		(at 233.57 125.4)
		(size 0.45)
		(drill 0.1)
		(layers "F.Cu" "B.Cu")
		(net 115)
	)
	(via
		(at 215.2 131.8)
		(size 0.45)
		(drill 0.1)
		(layers "F.Cu" "B.Cu")
		(net 115)
	)
	(via
		(at 233.97 128.2)
		(size 0.45)
		(drill 0.1)
		(layers "F.Cu" "B.Cu")
		(net 115)
	)
	(segment
		(start 230.77 129.6)
		(end 231.07 129.6)
		(width 0.2)
		(layer "B.Cu")
		(net 115)
	)
	(segment
		(start 231.37 129.3)
		(end 231.37 128.2)
		(width 0.2)
		(layer "B.Cu")
		(net 115)
	)
	(segment
		(start 217.2 131.8)
		(end 220.299999 134.899999)
		(width 0.1)
		(layer "B.Cu")
		(net 115)
	)
	(segment
		(start 230.55 126.9)
		(end 231.37 126.9)
		(width 0.2)
		(layer "B.Cu")
		(net 115)
	)
	(segment
		(start 220.299999 134.899999)
		(end 229.4 134.899999)
		(width 0.1)
		(layer "B.Cu")
		(net 115)
	)
	(segment
		(start 231.57 126.7)
		(end 231.57 125.9)
		(width 0.2)
		(layer "B.Cu")
		(net 115)
	)
	(segment
		(start 231.37 126.9)
		(end 231.57 126.7)
		(width 0.2)
		(layer "B.Cu")
		(net 115)
	)
	(segment
		(start 231.07 129.6)
		(end 231.17 129.5)
		(width 0.2)
		(layer "B.Cu")
		(net 115)
	)
	(segment
		(start 215.2 131.8)
		(end 217.2 131.8)
		(width 0.1)
		(layer "B.Cu")
		(net 115)
	)
	(segment
		(start 231.17 129.5)
		(end 231.37 129.3)
		(width 0.2)
		(layer "B.Cu")
		(net 115)
	)
	(via
		(at 128.730532 73.65)
		(size 0.45)
		(drill 0.1)
		(layers "F.Cu" "B.Cu")
		(net 116)
	)
	(via
		(at 207.107 59.8)
		(size 0.45)
		(drill 0.1)
		(layers "F.Cu" "B.Cu")
		(net 116)
	)
	(segment
		(start 207.232 59.675)
		(end 207.107 59.8)
		(width 0.17)
		(layer "B.Cu")
		(net 116)
	)
	(segment
		(start 207.232 59.365001)
		(end 207.232 59.675)
		(width 0.17)
		(layer "B.Cu")
		(net 116)
	)
	(segment
		(start 207.157 59.290001)
		(end 207.232 59.365001)
		(width 0.17)
		(layer "B.Cu")
		(net 116)
	)
	(segment
		(start 207.157 58.39)
		(end 207.157 59.290001)
		(width 0.17)
		(layer "B.Cu")
		(net 116)
	)
	(segment
		(start 168.068976 71.782246)
		(end 168.180699 71.670522)
		(width 0.125)
		(layer "In2.Cu")
		(net 116)
	)
	(segment
		(start 166.416928 71.853421)
		(end 166.552205 71.988698)
		(width 0.125)
		(layer "In2.Cu")
		(net 116)
	)
	(segment
		(start 133.329147 74.2875)
		(end 164.094303 74.287501)
		(width 0.125)
		(layer "In2.Cu")
		(net 116)
	)
	(segment
		(start 165.658421 72.723378)
		(end 165.770145 72.611657)
		(width 0.125)
		(layer "In2.Cu")
		(net 116)
	)
	(segment
		(start 167.134644 71.135706)
		(end 167.269922 71.270984)
		(width 0.125)
		(layer "In2.Cu")
		(net 116)
	)
	(segment
		(start 207.294499 60.446401)
		(end 207.0034 60.7375)
		(width 0.125)
		(layer "In2.Cu")
		(net 116)
	)
	(segment
		(start 207.0034 60.7375)
		(end 206.3216 60.7375)
		(width 0.125)
		(layer "In2.Cu")
		(net 116)
	)
	(segment
		(start 128.393033 74.108933)
		(end 128.5716 74.2875)
		(width 0.125)
		(layer "In2.Cu")
		(net 116)
	)
	(segment
		(start 167.441041 70.03708)
		(end 167.552764 69.925358)
		(width 0.125)
		(layer "In2.Cu")
		(net 116)
	)
	(segment
		(start 207.294499 59.987499)
		(end 207.294499 60.446401)
		(width 0.125)
		(layer "In2.Cu")
		(net 116)
	)
	(segment
		(start 164.094303 73.999709)
		(end 163.841842 73.747248)
		(width 0.125)
		(layer "In2.Cu")
		(net 116)
	)
	(segment
		(start 164.559557 73.029534)
		(end 165.035465 73.505442)
		(width 0.125)
		(layer "In2.Cu")
		(net 116)
	)
	(segment
		(start 167.269922 71.270984)
		(end 167.269919 71.270982)
		(width 0.125)
		(layer "In2.Cu")
		(net 116)
	)
	(segment
		(start 128.730532 73.65)
		(end 128.393033 73.987499)
		(width 0.125)
		(layer "In2.Cu")
		(net 116)
	)
	(segment
		(start 177.844302 60.5375)
		(end 204.326883 60.5375)
		(width 0.125)
		(layer "In2.Cu")
		(net 116)
	)
	(segment
		(start 166.552203 71.988694)
		(end 167.063499 72.49999)
		(width 0.125)
		(layer "In2.Cu")
		(net 116)
	)
	(segment
		(start 166.552203 71.988694)
		(end 166.552205 71.988698)
		(width 0.125)
		(layer "In2.Cu")
		(net 116)
	)
	(segment
		(start 165.035461 73.50544)
		(end 165.546725 74.016704)
		(width 0.125)
		(layer "In2.Cu")
		(net 116)
	)
	(segment
		(start 167.669434 70.871464)
		(end 167.669435 70.871468)
		(width 0.125)
		(layer "In2.Cu")
		(net 116)
	)
	(segment
		(start 168.387149 70.153752)
		(end 168.538441 70.305044)
		(width 0.125)
		(layer "In2.Cu")
		(net 116)
	)
	(segment
		(start 133.209147 74.128643)
		(end 133.209147 74.1675)
		(width 0.125)
		(layer "In2.Cu")
		(net 116)
	)
	(segment
		(start 204.746883 60.4175)
		(end 204.746883 60.3575)
		(width 0.125)
		(layer "In2.Cu")
		(net 116)
	)
	(segment
		(start 167.44104 70.643072)
		(end 167.669435 70.871468)
		(width 0.125)
		(layer "In2.Cu")
		(net 116)
	)
	(segment
		(start 168.158756 69.925357)
		(end 168.387152 70.153753)
		(width 0.125)
		(layer "In2.Cu")
		(net 116)
	)
	(segment
		(start 204.626883 60.2375)
		(end 204.566883 60.2375)
		(width 0.125)
		(layer "In2.Cu")
		(net 116)
	)
	(segment
		(start 168.937956 69.443845)
		(end 177.844302 60.5375)
		(width 0.125)
		(layer "In2.Cu")
		(net 116)
	)
	(segment
		(start 206.1216 60.5375)
		(end 204.866883 60.5375)
		(width 0.125)
		(layer "In2.Cu")
		(net 116)
	)
	(segment
		(start 207.107 59.8)
		(end 207.294499 59.987499)
		(width 0.125)
		(layer "In2.Cu")
		(net 116)
	)
	(segment
		(start 165.834518 74.016704)
		(end 165.94624 73.904981)
		(width 0.125)
		(layer "In2.Cu")
		(net 116)
	)
	(segment
		(start 167.669434 70.871464)
		(end 168.180699 71.382729)
		(width 0.125)
		(layer "In2.Cu")
		(net 116)
	)
	(segment
		(start 168.681926 70.305044)
		(end 168.937956 70.049013)
		(width 0.125)
		(layer "In2.Cu")
		(net 116)
	)
	(segment
		(start 163.841843 73.141256)
		(end 163.953565 73.029535)
		(width 0.125)
		(layer "In2.Cu")
		(net 116)
	)
	(segment
		(start 204.446883 60.3575)
		(end 204.446883 60.4175)
		(width 0.125)
		(layer "In2.Cu")
		(net 116)
	)
	(segment
		(start 166.41693 71.423765)
		(end 166.70499 71.135706)
		(width 0.125)
		(layer "In2.Cu")
		(net 116)
	)
	(segment
		(start 168.387152 70.153753)
		(end 168.387149 70.153752)
		(width 0.125)
		(layer "In2.Cu")
		(net 116)
	)
	(segment
		(start 165.035465 73.505442)
		(end 165.035461 73.50544)
		(width 0.125)
		(layer "In2.Cu")
		(net 116)
	)
	(segment
		(start 132.909147 74.1675)
		(end 132.909147 74.128643)
		(width 0.125)
		(layer "In2.Cu")
		(net 116)
	)
	(segment
		(start 167.269919 71.270982)
		(end 167.781183 71.782246)
		(width 0.125)
		(layer "In2.Cu")
		(net 116)
	)
	(segment
		(start 128.393033 73.987499)
		(end 128.393033 74.108933)
		(width 0.125)
		(layer "In2.Cu")
		(net 116)
	)
	(segment
		(start 165.94624 73.617188)
		(end 165.658421 73.329369)
		(width 0.125)
		(layer "In2.Cu")
		(net 116)
	)
	(segment
		(start 206.3216 60.7375)
		(end 206.1216 60.5375)
		(width 0.125)
		(layer "In2.Cu")
		(net 116)
	)
	(segment
		(start 166.951777 72.899506)
		(end 167.063499 72.787783)
		(width 0.125)
		(layer "In2.Cu")
		(net 116)
	)
	(segment
		(start 166.376135 72.611657)
		(end 166.663984 72.899506)
		(width 0.125)
		(layer "In2.Cu")
		(net 116)
	)
	(segment
		(start 128.5716 74.2875)
		(end 132.789147 74.2875)
		(width 0.125)
		(layer "In2.Cu")
		(net 116)
	)
	(segment
		(start 133.029147 74.008643)
		(end 133.089147 74.008643)
		(width 0.125)
		(layer "In2.Cu")
		(net 116)
	)
	(arc
		(start 163.953565 73.029535)
		(mid 164.256562 72.904029)
		(end 164.559557 73.029534)
		(width 0.125)
		(layer "In2.Cu")
		(net 116)
	)
	(arc
		(start 165.770145 72.611657)
		(mid 166.07314 72.486152)
		(end 166.376135 72.611657)
		(width 0.125)
		(layer "In2.Cu")
		(net 116)
	)
	(arc
		(start 167.063499 72.787783)
		(mid 167.123103 72.643886)
		(end 167.063499 72.49999)
		(width 0.125)
		(layer "In2.Cu")
		(net 116)
	)
	(arc
		(start 204.866883 60.5375)
		(mid 204.78203 60.502353)
		(end 204.746883 60.4175)
		(width 0.125)
		(layer "In2.Cu")
		(net 116)
	)
	(arc
		(start 167.781183 71.782246)
		(mid 167.92508 71.841849)
		(end 168.068976 71.782246)
		(width 0.125)
		(layer "In2.Cu")
		(net 116)
	)
	(arc
		(start 167.552764 69.925358)
		(mid 167.855761 69.799852)
		(end 168.158756 69.925357)
		(width 0.125)
		(layer "In2.Cu")
		(net 116)
	)
	(arc
		(start 167.44104 70.643072)
		(mid 167.315536 70.340076)
		(end 167.441041 70.03708)
		(width 0.125)
		(layer "In2.Cu")
		(net 116)
	)
	(arc
		(start 163.841842 73.747248)
		(mid 163.716338 73.444252)
		(end 163.841843 73.141256)
		(width 0.125)
		(layer "In2.Cu")
		(net 116)
	)
	(arc
		(start 166.416928 71.853421)
		(mid 166.327945 71.638593)
		(end 166.41693 71.423765)
		(width 0.125)
		(layer "In2.Cu")
		(net 116)
	)
	(arc
		(start 165.94624 73.904981)
		(mid 166.005844 73.761084)
		(end 165.94624 73.617188)
		(width 0.125)
		(layer "In2.Cu")
		(net 116)
	)
	(arc
		(start 164.094303 74.287501)
		(mid 164.153907 74.143605)
		(end 164.094303 73.999709)
		(width 0.125)
		(layer "In2.Cu")
		(net 116)
	)
	(arc
		(start 165.546725 74.016704)
		(mid 165.690622 74.076307)
		(end 165.834518 74.016704)
		(width 0.125)
		(layer "In2.Cu")
		(net 116)
	)
	(arc
		(start 168.538441 70.305044)
		(mid 168.610184 70.33476)
		(end 168.681926 70.305044)
		(width 0.125)
		(layer "In2.Cu")
		(net 116)
	)
	(arc
		(start 204.446883 60.4175)
		(mid 204.411736 60.502353)
		(end 204.326883 60.5375)
		(width 0.125)
		(layer "In2.Cu")
		(net 116)
	)
	(arc
		(start 166.70499 71.135706)
		(mid 166.919818 71.046721)
		(end 167.134644 71.135706)
		(width 0.125)
		(layer "In2.Cu")
		(net 116)
	)
	(arc
		(start 132.789147 74.2875)
		(mid 132.874 74.252353)
		(end 132.909147 74.1675)
		(width 0.125)
		(layer "In2.Cu")
		(net 116)
	)
	(arc
		(start 132.909147 74.128643)
		(mid 132.944294 74.04379)
		(end 133.029147 74.008643)
		(width 0.125)
		(layer "In2.Cu")
		(net 116)
	)
	(arc
		(start 168.937956 69.905528)
		(mid 168.842338 69.674687)
		(end 168.937956 69.443845)
		(width 0.125)
		(layer "In2.Cu")
		(net 116)
	)
	(arc
		(start 204.746883 60.3575)
		(mid 204.711736 60.272647)
		(end 204.626883 60.2375)
		(width 0.125)
		(layer "In2.Cu")
		(net 116)
	)
	(arc
		(start 165.658421 73.329369)
		(mid 165.532916 73.026374)
		(end 165.658421 72.723378)
		(width 0.125)
		(layer "In2.Cu")
		(net 116)
	)
	(arc
		(start 133.089147 74.008643)
		(mid 133.174 74.04379)
		(end 133.209147 74.128643)
		(width 0.125)
		(layer "In2.Cu")
		(net 116)
	)
	(arc
		(start 204.566883 60.2375)
		(mid 204.48203 60.272647)
		(end 204.446883 60.3575)
		(width 0.125)
		(layer "In2.Cu")
		(net 116)
	)
	(arc
		(start 133.209147 74.1675)
		(mid 133.244294 74.252353)
		(end 133.329147 74.2875)
		(width 0.125)
		(layer "In2.Cu")
		(net 116)
	)
	(arc
		(start 168.937956 70.049013)
		(mid 168.967673 69.97727)
		(end 168.937956 69.905528)
		(width 0.125)
		(layer "In2.Cu")
		(net 116)
	)
	(arc
		(start 168.180699 71.670522)
		(mid 168.240303 71.526625)
		(end 168.180699 71.382729)
		(width 0.125)
		(layer "In2.Cu")
		(net 116)
	)
	(arc
		(start 166.663984 72.899506)
		(mid 166.807881 72.959109)
		(end 166.951777 72.899506)
		(width 0.125)
		(layer "In2.Cu")
		(net 116)
	)
	(segment
		(start 134.5 111.1)
		(end 135.52 111.1)
		(width 0.1)
		(layer "F.Cu")
		(net 117)
	)
	(via
		(at 204.8 92.6)
		(size 0.45)
		(drill 0.1)
		(layers "F.Cu" "B.Cu")
		(net 117)
	)
	(via
		(at 134.5 111.1)
		(size 0.45)
		(drill 0.1)
		(layers "F.Cu" "B.Cu")
		(net 117)
	)
	(segment
		(start 211.2 77.834314)
		(end 211.017631 77.651945)
		(width 0.1)
		(layer "B.Cu")
		(net 117)
	)
	(segment
		(start 211.054 66.954)
		(end 211 66.9)
		(width 0.1)
		(layer "B.Cu")
		(net 117)
	)
	(segment
		(start 211.801 63.454)
		(end 211.146 63.454)
		(width 0.1)
		(layer "B.Cu")
		(net 117)
	)
	(segment
		(start 211.017631 77.651945)
		(end 211.017631 75.051945)
		(width 0.1)
		(layer "B.Cu")
		(net 117)
	)
	(segment
		(start 209.1 70.62)
		(end 209.1 69.9)
		(width 0.1)
		(layer "B.Cu")
		(net 117)
	)
	(segment
		(start 211.2 86.565686)
		(end 211.2 77.834314)
		(width 0.1)
		(layer "B.Cu")
		(net 117)
	)
	(segment
		(start 211.146 63.454)
		(end 211 63.6)
		(width 0.1)
		(layer "B.Cu")
		(net 117)
	)
	(segment
		(start 211.1 66.954)
		(end 211.054 66.954)
		(width 0.1)
		(layer "B.Cu")
		(net 117)
	)
	(segment
		(start 211 68)
		(end 211 67)
		(width 0.1)
		(layer "B.Cu")
		(net 117)
	)
	(segment
		(start 204.8 92)
		(end 205.4 91.4)
		(width 0.1)
		(layer "B.Cu")
		(net 117)
	)
	(segment
		(start 211 63.6)
		(end 211 66.9)
		(width 0.1)
		(layer "B.Cu")
		(net 117)
	)
	(segment
		(start 209.5 71.02)
		(end 209.1 70.62)
		(width 0.1)
		(layer "B.Cu")
		(net 117)
	)
	(segment
		(start 211.1 66.954)
		(end 211.046 66.954)
		(width 0.1)
		(layer "B.Cu")
		(net 117)
	)
	(segment
		(start 206.365686 91.4)
		(end 211.2 86.565686)
		(width 0.1)
		(layer "B.Cu")
		(net 117)
	)
	(segment
		(start 211.046 66.954)
		(end 211 67)
		(width 0.1)
		(layer "B.Cu")
		(net 117)
	)
	(segment
		(start 211 66.9)
		(end 211 67)
		(width 0.1)
		(layer "B.Cu")
		(net 117)
	)
	(segment
		(start 209.5 71.02)
		(end 209.92 71.02)
		(width 0.1)
		(layer "B.Cu")
		(net 117)
	)
	(segment
		(start 211.017631 75.051945)
		(end 210.032843 74.067157)
		(width 0.1)
		(layer "B.Cu")
		(net 117)
	)
	(segment
		(start 209.1 69.9)
		(end 211 68)
		(width 0.1)
		(layer "B.Cu")
		(net 117)
	)
	(segment
		(start 205.4 91.4)
		(end 206.365686 91.4)
		(width 0.1)
		(layer "B.Cu")
		(net 117)
	)
	(segment
		(start 210.032843 74.067157)
		(end 210.032843 71.132843)
		(width 0.1)
		(layer "B.Cu")
		(net 117)
	)
	(segment
		(start 204.8 92.6)
		(end 204.8 92)
		(width 0.1)
		(layer "B.Cu")
		(net 117)
	)
	(segment
		(start 209.92 71.02)
		(end 210.032843 71.132843)
		(width 0.1)
		(layer "B.Cu")
		(net 117)
	)
	(segment
		(start 211.801 66.954)
		(end 211.1 66.954)
		(width 0.1)
		(layer "B.Cu")
		(net 117)
	)
	(segment
		(start 144.4 106.8)
		(end 148.4 102.8)
		(width 0.1)
		(layer "In7.Cu")
		(net 117)
	)
	(segment
		(start 191.365686 94.6)
		(end 192.603527 93.362159)
		(width 0.1)
		(layer "In7.Cu")
		(net 117)
	)
	(segment
		(start 153.2 101.65)
		(end 153.2 96.6)
		(width 0.1)
		(layer "In7.Cu")
		(net 117)
	)
	(segment
		(start 198.396473 93.362159)
		(end 198.683289 93.648975)
		(width 0.1)
		(layer "In7.Cu")
		(net 117)
	)
	(segment
		(start 198.683289 93.648975)
		(end 204.116711 93.648975)
		(width 0.1)
		(layer "In7.Cu")
		(net 117)
	)
	(segment
		(start 152.05 102.8)
		(end 153.2 101.65)
		(width 0.1)
		(layer "In7.Cu")
		(net 117)
	)
	(segment
		(start 153.2 96.6)
		(end 155.2 94.6)
		(width 0.1)
		(layer "In7.Cu")
		(net 117)
	)
	(segment
		(start 204.116711 93.648975)
		(end 204.8 92.965686)
		(width 0.1)
		(layer "In7.Cu")
		(net 117)
	)
	(segment
		(start 134.5 110.1)
		(end 137.8 106.8)
		(width 0.1)
		(layer "In7.Cu")
		(net 117)
	)
	(segment
		(start 192.603527 93.362159)
		(end 198.396473 93.362159)
		(width 0.1)
		(layer "In7.Cu")
		(net 117)
	)
	(segment
		(start 137.8 106.8)
		(end 144.4 106.8)
		(width 0.1)
		(layer "In7.Cu")
		(net 117)
	)
	(segment
		(start 155.2 94.6)
		(end 191.365686 94.6)
		(width 0.1)
		(layer "In7.Cu")
		(net 117)
	)
	(segment
		(start 204.8 92.965686)
		(end 204.8 92.6)
		(width 0.1)
		(layer "In7.Cu")
		(net 117)
	)
	(segment
		(start 148.4 102.8)
		(end 152.05 102.8)
		(width 0.1)
		(layer "In7.Cu")
		(net 117)
	)
	(segment
		(start 134.5 111.1)
		(end 134.5 110.1)
		(width 0.1)
		(layer "In7.Cu")
		(net 117)
	)
	(segment
		(start 130.225 100.6)
		(end 132.25 100.6)
		(width 0.1)
		(layer "F.Cu")
		(net 118)
	)
	(segment
		(start 128.1 100.2)
		(end 129.825 100.2)
		(width 0.1)
		(layer "F.Cu")
		(net 118)
	)
	(segment
		(start 129.825 100.2)
		(end 130.225 100.6)
		(width 0.1)
		(layer "F.Cu")
		(net 118)
	)
	(via
		(at 140.430532 73.65)
		(size 0.45)
		(drill 0.1)
		(layers "F.Cu" "B.Cu")
		(net 118)
	)
	(via
		(at 78.1 97.35)
		(size 0.45)
		(drill 0.1)
		(layers "F.Cu" "B.Cu")
		(net 118)
	)
	(via
		(at 128.1 100.2)
		(size 0.45)
		(drill 0.1)
		(layers "F.Cu" "B.Cu")
		(net 118)
	)
	(via
		(at 132.25 100.6)
		(size 0.45)
		(drill 0.1)
		(layers "F.Cu" "B.Cu")
		(net 118)
	)
	(segment
		(start 78.1 97.35)
		(end 78.8 97.35)
		(width 0.1)
		(layer "B.Cu")
		(net 118)
	)
	(segment
		(start 78.95 97.5)
		(end 78.95 98.629468)
		(width 0.1)
		(layer "B.Cu")
		(net 118)
	)
	(segment
		(start 78.8 97.35)
		(end 78.95 97.5)
		(width 0.1)
		(layer "B.Cu")
		(net 118)
	)
	(segment
		(start 78.95 98.629468)
		(end 79.585532 99.265)
		(width 0.1)
		(layer "B.Cu")
		(net 118)
	)
	(segment
		(start 141.4 73.7)
		(end 142.1 74.4)
		(width 0.1)
		(layer "In5.Cu")
		(net 118)
	)
	(segment
		(start 142.9 75.25)
		(end 143.55 75.9)
		(width 0.1)
		(layer "In5.Cu")
		(net 118)
	)
	(segment
		(start 142.725 78.55)
		(end 141.875 78.55)
		(width 0.1)
		(layer "In5.Cu")
		(net 118)
	)
	(segment
		(start 77.9 101.8)
		(end 78.925 102.825)
		(width 0.1)
		(layer "In5.Cu")
		(net 118)
	)
	(segment
		(start 135.1 99.3)
		(end 133.8 100.6)
		(width 0.1)
		(layer "In5.Cu")
		(net 118)
	)
	(segment
		(start 81.75 115.95)
		(end 82.45 116.65)
		(width 0.1)
		(layer "In5.Cu")
		(net 118)
	)
	(segment
		(start 140.430532 73.030532)
		(end 139.8 72.4)
		(width 0.1)
		(layer "In5.Cu")
		(net 118)
	)
	(segment
		(start 141.975 81.275)
		(end 142.5 81.8)
		(width 0.1)
		(layer "In5.Cu")
		(net 118)
	)
	(segment
		(start 140.1 71.75)
		(end 140.75 71.75)
		(width 0.1)
		(layer "In5.Cu")
		(net 118)
	)
	(segment
		(start 143.55 77.05)
		(end 142.825 77.775)
		(width 0.1)
		(layer "In5.Cu")
		(net 118)
	)
	(segment
		(start 140.75 71.75)
		(end 141.4 72.4)
		(width 0.1)
		(layer "In5.Cu")
		(net 118)
	)
	(segment
		(start 100.065686 103.7)
		(end 120.331366 103.7)
		(width 0.1)
		(layer "In5.Cu")
		(net 118)
	)
	(segment
		(start 141.500001 83.999999)
		(end 141.500001 88.168629)
		(width 0.1)
		(layer "In5.Cu")
		(net 118)
	)
	(segment
		(start 82.45 116.65)
		(end 86.6 116.65)
		(width 0.1)
		(layer "In5.Cu")
		(net 118)
	)
	(segment
		(start 142.9 74.9)
		(end 142.9 75.25)
		(width 0.1)
		(layer "In5.Cu")
		(net 118)
	)
	(segment
		(start 142.5 83)
		(end 141.500001 83.999999)
		(width 0.1)
		(layer "In5.Cu")
		(net 118)
	)
	(segment
		(start 78.925 102.825)
		(end 78.925 103.325)
		(width 0.1)
		(layer "In5.Cu")
		(net 118)
	)
	(segment
		(start 141.475 78.95)
		(end 141.475 79.775)
		(width 0.1)
		(layer "In5.Cu")
		(net 118)
	)
	(segment
		(start 86.6 116.65)
		(end 87.05 116.2)
		(width 0.1)
		(layer "In5.Cu")
		(net 118)
	)
	(segment
		(start 79.5 103.9)
		(end 79.85 103.9)
		(width 0.1)
		(layer "In5.Cu")
		(net 118)
	)
	(segment
		(start 141.4 72.4)
		(end 141.4 73.7)
		(width 0.1)
		(layer "In5.Cu")
		(net 118)
	)
	(segment
		(start 79.85 103.9)
		(end 81.75 105.8)
		(width 0.1)
		(layer "In5.Cu")
		(net 118)
	)
	(segment
		(start 77.9 97.55)
		(end 78.1 97.35)
		(width 0.1)
		(layer "In5.Cu")
		(net 118)
	)
	(segment
		(start 99.700001 104.065685)
		(end 100.065686 103.7)
		(width 0.1)
		(layer "In5.Cu")
		(net 118)
	)
	(segment
		(start 81.75 105.8)
		(end 81.75 115.95)
		(width 0.1)
		(layer "In5.Cu")
		(net 118)
	)
	(segment
		(start 142.5 81.8)
		(end 142.5 83)
		(width 0.1)
		(layer "In5.Cu")
		(net 118)
	)
	(segment
		(start 140.430532 73.65)
		(end 140.430532 73.030532)
		(width 0.1)
		(layer "In5.Cu")
		(net 118)
	)
	(segment
		(start 141.500001 88.168629)
		(end 135.1 94.56863)
		(width 0.1)
		(layer "In5.Cu")
		(net 118)
	)
	(segment
		(start 141.975 80.275)
		(end 141.975 81.275)
		(width 0.1)
		(layer "In5.Cu")
		(net 118)
	)
	(segment
		(start 123.831366 100.2)
		(end 128.1 100.2)
		(width 0.1)
		(layer "In5.Cu")
		(net 118)
	)
	(segment
		(start 142.1 74.4)
		(end 142.4 74.4)
		(width 0.1)
		(layer "In5.Cu")
		(net 118)
	)
	(segment
		(start 133.8 100.6)
		(end 132.25 100.6)
		(width 0.1)
		(layer "In5.Cu")
		(net 118)
	)
	(segment
		(start 94.734318 116.2)
		(end 99.700001 111.234317)
		(width 0.1)
		(layer "In5.Cu")
		(net 118)
	)
	(segment
		(start 142.4 74.4)
		(end 142.9 74.9)
		(width 0.1)
		(layer "In5.Cu")
		(net 118)
	)
	(segment
		(start 142.825 77.775)
		(end 142.825 78.45)
		(width 0.1)
		(layer "In5.Cu")
		(net 118)
	)
	(segment
		(start 143.55 75.9)
		(end 143.55 77.05)
		(width 0.1)
		(layer "In5.Cu")
		(net 118)
	)
	(segment
		(start 135.1 94.56863)
		(end 135.1 99.3)
		(width 0.1)
		(layer "In5.Cu")
		(net 118)
	)
	(segment
		(start 141.475 79.775)
		(end 141.975 80.275)
		(width 0.1)
		(layer "In5.Cu")
		(net 118)
	)
	(segment
		(start 139.8 72.4)
		(end 139.8 72.05)
		(width 0.1)
		(layer "In5.Cu")
		(net 118)
	)
	(segment
		(start 141.875 78.55)
		(end 141.475 78.95)
		(width 0.1)
		(layer "In5.Cu")
		(net 118)
	)
	(segment
		(start 142.825 78.45)
		(end 142.725 78.55)
		(width 0.1)
		(layer "In5.Cu")
		(net 118)
	)
	(segment
		(start 99.700001 111.234317)
		(end 99.700001 104.065685)
		(width 0.1)
		(layer "In5.Cu")
		(net 118)
	)
	(segment
		(start 87.05 116.2)
		(end 94.734318 116.2)
		(width 0.1)
		(layer "In5.Cu")
		(net 118)
	)
	(segment
		(start 139.8 72.05)
		(end 140.1 71.75)
		(width 0.1)
		(layer "In5.Cu")
		(net 118)
	)
	(segment
		(start 77.9 101.8)
		(end 77.9 97.55)
		(width 0.1)
		(layer "In5.Cu")
		(net 118)
	)
	(segment
		(start 78.925 103.325)
		(end 79.5 103.9)
		(width 0.1)
		(layer "In5.Cu")
		(net 118)
	)
	(segment
		(start 120.331366 103.7)
		(end 123.831366 100.2)
		(width 0.1)
		(layer "In5.Cu")
		(net 118)
	)
	(segment
		(start 89.030532 76.65)
		(end 89 76.65)
		(width 0.1)
		(layer "F.Cu")
		(net 120)
	)
	(via
		(at 75.775532 85.295)
		(size 0.45)
		(drill 0.1)
		(layers "F.Cu" "B.Cu")
		(net 120)
	)
	(via
		(at 89 76.65)
		(size 0.45)
		(drill 0.1)
		(layers "F.Cu" "B.Cu")
		(net 120)
	)
	(segment
		(start 85.8 78.2)
		(end 86.375 77.625)
		(width 0.1)
		(layer "In5.Cu")
		(net 120)
	)
	(segment
		(start 75.775532 85.295)
		(end 76.4 84.670532)
		(width 0.1)
		(layer "In5.Cu")
		(net 120)
	)
	(segment
		(start 76.4 84.670532)
		(end 76.4 82.5)
		(width 0.1)
		(layer "In5.Cu")
		(net 120)
	)
	(segment
		(start 76.65 82.25)
		(end 83.3 82.25)
		(width 0.1)
		(layer "In5.Cu")
		(net 120)
	)
	(segment
		(start 76.4 82.5)
		(end 76.65 82.25)
		(width 0.1)
		(layer "In5.Cu")
		(net 120)
	)
	(segment
		(start 88.025 77.625)
		(end 89 76.65)
		(width 0.1)
		(layer "In5.Cu")
		(net 120)
	)
	(segment
		(start 83.3 82.25)
		(end 85.8 79.75)
		(width 0.1)
		(layer "In5.Cu")
		(net 120)
	)
	(segment
		(start 86.375 77.625)
		(end 88.025 77.625)
		(width 0.1)
		(layer "In5.Cu")
		(net 120)
	)
	(segment
		(start 85.8 79.75)
		(end 85.8 78.2)
		(width 0.1)
		(layer "In5.Cu")
		(net 120)
	)
	(segment
		(start 128.05 99.45)
		(end 128.1 99.4)
		(width 0.1)
		(layer "F.Cu")
		(net 121)
	)
	(segment
		(start 139.730532 75.15)
		(end 139.75 75.15)
		(width 0.1)
		(layer "F.Cu")
		(net 121)
	)
	(segment
		(start 130.05 99.4)
		(end 130.45 99.8)
		(width 0.1)
		(layer "F.Cu")
		(net 121)
	)
	(segment
		(start 128.1 99.4)
		(end 130.05 99.4)
		(width 0.1)
		(layer "F.Cu")
		(net 121)
	)
	(segment
		(start 130.45 99.8)
		(end 132.25 99.8)
		(width 0.1)
		(layer "F.Cu")
		(net 121)
	)
	(via
		(at 128.05 99.45)
		(size 0.45)
		(drill 0.1)
		(layers "F.Cu" "B.Cu")
		(net 121)
	)
	(via
		(at 139.75 75.15)
		(size 0.45)
		(drill 0.1)
		(layers "F.Cu" "B.Cu")
		(net 121)
	)
	(via
		(at 132.25 99.8)
		(size 0.45)
		(drill 0.1)
		(layers "F.Cu" "B.Cu")
		(net 121)
	)
	(via
		(at 79.585532 96.725)
		(size 0.45)
		(drill 0.1)
		(layers "F.Cu" "B.Cu")
		(net 121)
	)
	(segment
		(start 84.4 116.2)
		(end 86.040863 116.2)
		(width 0.1)
		(layer "In5.Cu")
		(net 121)
	)
	(segment
		(start 82.8 114.6)
		(end 84.4 116.2)
		(width 0.1)
		(layer "In5.Cu")
		(net 121)
	)
	(segment
		(start 98.900002 110.902944)
		(end 98.900002 103.734316)
		(width 0.1)
		(layer "In5.Cu")
		(net 121)
	)
	(segment
		(start 141.55 82.7)
		(end 141.55 81.9)
		(width 0.1)
		(layer "In5.Cu")
		(net 121)
	)
	(segment
		(start 79 97.310532)
		(end 79 102)
		(width 0.1)
		(layer "In5.Cu")
		(net 121)
	)
	(segment
		(start 140.3 74.6)
		(end 139.75 75.15)
		(width 0.1)
		(layer "In5.Cu")
		(net 121)
	)
	(segment
		(start 132.25 99.8)
		(end 133.1 99.8)
		(width 0.1)
		(layer "In5.Cu")
		(net 121)
	)
	(segment
		(start 82.6 102.4)
		(end 82.8 102.6)
		(width 0.1)
		(layer "In5.Cu")
		(net 121)
	)
	(segment
		(start 86.540863 115.7)
		(end 94.102946 115.7)
		(width 0.1)
		(layer "In5.Cu")
		(net 121)
	)
	(segment
		(start 141.75 77.25)
		(end 141.75 76.05)
		(width 0.1)
		(layer "In5.Cu")
		(net 121)
	)
	(segment
		(start 141.1 75.4)
		(end 141.1 74.8)
		(width 0.1)
		(layer "In5.Cu")
		(net 121)
	)
	(segment
		(start 79 102)
		(end 79.4 102.4)
		(width 0.1)
		(layer "In5.Cu")
		(net 121)
	)
	(segment
		(start 140.9 74.6)
		(end 140.3 74.6)
		(width 0.1)
		(layer "In5.Cu")
		(net 121)
	)
	(segment
		(start 98.900002 103.734316)
		(end 100.134315 102.500003)
		(width 0.1)
		(layer "In5.Cu")
		(net 121)
	)
	(segment
		(start 94.102946 115.7)
		(end 98.900002 110.902944)
		(width 0.1)
		(layer "In5.Cu")
		(net 121)
	)
	(segment
		(start 140.7 83.55)
		(end 141.55 82.7)
		(width 0.1)
		(layer "In5.Cu")
		(net 121)
	)
	(segment
		(start 140.875 80.025)
		(end 140.875 78.125)
		(width 0.1)
		(layer "In5.Cu")
		(net 121)
	)
	(segment
		(start 141.55 81.9)
		(end 141.1 81.45)
		(width 0.1)
		(layer "In5.Cu")
		(net 121)
	)
	(segment
		(start 141.75 76.05)
		(end 141.1 75.4)
		(width 0.1)
		(layer "In5.Cu")
		(net 121)
	)
	(segment
		(start 133.1 99.8)
		(end 134.3 98.6)
		(width 0.1)
		(layer "In5.Cu")
		(net 121)
	)
	(segment
		(start 134.3 94.237258)
		(end 140.7 87.837258)
		(width 0.1)
		(layer "In5.Cu")
		(net 121)
	)
	(segment
		(start 79.585532 96.725)
		(end 79 97.310532)
		(width 0.1)
		(layer "In5.Cu")
		(net 121)
	)
	(segment
		(start 123.45 99.45)
		(end 128.05 99.45)
		(width 0.1)
		(layer "In5.Cu")
		(net 121)
	)
	(segment
		(start 100.134315 102.500003)
		(end 120.399997 102.500003)
		(width 0.1)
		(layer "In5.Cu")
		(net 121)
	)
	(segment
		(start 82.8 102.6)
		(end 82.8 114.6)
		(width 0.1)
		(layer "In5.Cu")
		(net 121)
	)
	(segment
		(start 141.1 80.25)
		(end 140.875 80.025)
		(width 0.1)
		(layer "In5.Cu")
		(net 121)
	)
	(segment
		(start 140.875 78.125)
		(end 141.75 77.25)
		(width 0.1)
		(layer "In5.Cu")
		(net 121)
	)
	(segment
		(start 141.1 81.45)
		(end 141.1 80.25)
		(width 0.1)
		(layer "In5.Cu")
		(net 121)
	)
	(segment
		(start 140.7 87.837258)
		(end 140.7 83.55)
		(width 0.1)
		(layer "In5.Cu")
		(net 121)
	)
	(segment
		(start 120.399997 102.500003)
		(end 123.45 99.45)
		(width 0.1)
		(layer "In5.Cu")
		(net 121)
	)
	(segment
		(start 141.1 74.8)
		(end 140.9 74.6)
		(width 0.1)
		(layer "In5.Cu")
		(net 121)
	)
	(segment
		(start 134.3 98.6)
		(end 134.3 94.237258)
		(width 0.1)
		(layer "In5.Cu")
		(net 121)
	)
	(segment
		(start 79.4 102.4)
		(end 82.6 102.4)
		(width 0.1)
		(layer "In5.Cu")
		(net 121)
	)
	(segment
		(start 86.040863 116.2)
		(end 86.540863 115.7)
		(width 0.1)
		(layer "In5.Cu")
		(net 121)
	)
	(via
		(at 130.530532 76.65)
		(size 0.45)
		(drill 0.1)
		(layers "F.Cu" "B.Cu")
		(net 122)
	)
	(via
		(at 192.8375 62.85)
		(size 0.45)
		(drill 0.1)
		(layers "F.Cu" "B.Cu")
		(net 122)
	)
	(segment
		(start 192.8375 62.85)
		(end 192.725 62.9625)
		(width 0.17)
		(layer "B.Cu")
		(net 122)
	)
	(segment
		(start 194.736498 62.502964)
		(end 194.904239 62.335224)
		(width 0.17)
		(layer "B.Cu")
		(net 122)
	)
	(segment
		(start 196.658 59.290001)
		(end 196.658 58.39)
		(width 0.17)
		(layer "B.Cu")
		(net 122)
	)
	(segment
		(start 194.227512 63.525)
		(end 194.736498 63.016014)
		(width 0.17)
		(layer "B.Cu")
		(net 122)
	)
	(segment
		(start 192.725 62.9625)
		(end 192.725 63.227512)
		(width 0.17)
		(layer "B.Cu")
		(net 122)
	)
	(segment
		(start 192.725 63.227512)
		(end 193.022488 63.525)
		(width 0.17)
		(layer "B.Cu")
		(net 122)
	)
	(segment
		(start 195.998458 61.754054)
		(end 196.733 61.019512)
		(width 0.17)
		(layer "B.Cu")
		(net 122)
	)
	(segment
		(start 195.417289 62.335225)
		(end 195.585028 62.167485)
		(width 0.17)
		(layer "B.Cu")
		(net 122)
	)
	(segment
		(start 195.585028 62.167485)
		(end 195.998458 61.754054)
		(width 0.17)
		(layer "B.Cu")
		(net 122)
	)
	(segment
		(start 193.022488 63.525)
		(end 194.227512 63.525)
		(width 0.17)
		(layer "B.Cu")
		(net 122)
	)
	(segment
		(start 196.733 59.365001)
		(end 196.658 59.290001)
		(width 0.17)
		(layer "B.Cu")
		(net 122)
	)
	(segment
		(start 196.733 61.019512)
		(end 196.733 59.365001)
		(width 0.17)
		(layer "B.Cu")
		(net 122)
	)
	(arc
		(start 194.736498 63.016014)
		(mid 194.789626 62.887752)
		(end 194.736499 62.759488)
		(width 0.17)
		(layer "B.Cu")
		(net 122)
	)
	(arc
		(start 194.736499 62.759488)
		(mid 194.68337 62.631226)
		(end 194.736498 62.502964)
		(width 0.17)
		(layer "B.Cu")
		(net 122)
	)
	(arc
		(start 194.904239 62.335224)
		(mid 195.032501 62.282097)
		(end 195.160763 62.335225)
		(width 0.17)
		(layer "B.Cu")
		(net 122)
	)
	(arc
		(start 195.160763 62.335225)
		(mid 195.289027 62.388352)
		(end 195.417289 62.335225)
		(width 0.17)
		(layer "B.Cu")
		(net 122)
	)
	(segment
		(start 158.225729 77.18)
		(end 158.225729 77.5125)
		(width 0.125)
		(layer "In2.Cu")
		(net 122)
	)
	(segment
		(start 167.61632 75.32632)
		(end 179.155139 63.787501)
		(width 0.125)
		(layer "In2.Cu")
		(net 122)
	)
	(segment
		(start 160.100729 77.2875)
		(end 160.100729 77.188416)
		(width 0.125)
		(layer "In2.Cu")
		(net 122)
	)
	(segment
		(start 160.100729 77.5125)
		(end 160.100729 77.2875)
		(width 0.125)
		(layer "In2.Cu")
		(net 122)
	)
	(segment
		(start 154.600729 77.906796)
		(end 154.600729 77.5125)
		(width 0.125)
		(layer "In2.Cu")
		(net 122)
	)
	(segment
		(start 162.408229 76.585704)
		(end 162.518229 76.585704)
		(width 0.125)
		(layer "In2.Cu")
		(net 122)
	)
	(segment
		(start 153.608229 76.585704)
		(end 153.718229 76.585704)
		(width 0.125)
		(layer "In2.Cu")
		(net 122)
	)
	(segment
		(start 159.325729 77.5125)
		(end 159.325729 77.906771)
		(width 0.125)
		(layer "In2.Cu")
		(net 122)
	)
	(segment
		(start 156.908229 77.035706)
		(end 157.018229 77.035706)
		(width 0.125)
		(layer "In2.Cu")
		(net 122)
	)
	(segment
		(start 154.708229 76.585704)
		(end 154.818229 76.585704)
		(width 0.125)
		(layer "In2.Cu")
		(net 122)
	)
	(segment
		(start 159.325729 77.2875)
		(end 159.325729 77.5125)
		(width 0.125)
		(layer "In2.Cu")
		(net 122)
	)
	(segment
		(start 161.525729 77.2875)
		(end 161.525729 77.5125)
		(width 0.125)
		(layer "In2.Cu")
		(net 122)
	)
	(segment
		(start 153.825729 77.5125)
		(end 153.825729 77.906796)
		(width 0.125)
		(layer "In2.Cu")
		(net 122)
	)
	(segment
		(start 161.200729 77.5125)
		(end 161.200729 77.2875)
		(width 0.125)
		(layer "In2.Cu")
		(net 122)
	)
	(segment
		(start 157.458229 77.5125)
		(end 157.568229 77.5125)
		(width 0.125)
		(layer "In2.Cu")
		(net 122)
	)
	(segment
		(start 159.000729 77.5125)
		(end 159.000729 77.2875)
		(width 0.125)
		(layer "In2.Cu")
		(net 122)
	)
	(segment
		(start 162.625729 77.2875)
		(end 162.625729 77.62)
		(width 0.125)
		(layer "In2.Cu")
		(net 122)
	)
	(segment
		(start 160.425729 77.5125)
		(end 160.425729 77.906796)
		(width 0.125)
		(layer "In2.Cu")
		(net 122)
	)
	(segment
		(start 160.100729 77.906771)
		(end 160.100729 77.5125)
		(width 0.125)
		(layer "In2.Cu")
		(net 122)
	)
	(segment
		(start 192.662501 63.024999)
		(end 192.8375 62.85)
		(width 0.125)
		(layer "In2.Cu")
		(net 122)
	)
	(segment
		(start 161.200729 77.2875)
		(end 161.200729 77.188416)
		(width 0.125)
		(layer "In2.Cu")
		(net 122)
	)
	(segment
		(start 162.625729 76.693204)
		(end 162.625729 77.2875)
		(width 0.125)
		(layer "In2.Cu")
		(net 122)
	)
	(segment
		(start 161.200729 77.906796)
		(end 161.200729 77.5125)
		(width 0.125)
		(layer "In2.Cu")
		(net 122)
	)
	(segment
		(start 131.2534 77.5125)
		(end 153.168229 77.5125)
		(width 0.125)
		(layer "In2.Cu")
		(net 122)
	)
	(segment
		(start 154.925729 76.693204)
		(end 154.925729 77.2875)
		(width 0.125)
		(layer "In2.Cu")
		(net 122)
	)
	(segment
		(start 156.025729 77.62)
		(end 156.025729 77.906796)
		(width 0.125)
		(layer "In2.Cu")
		(net 122)
	)
	(segment
		(start 155.258229 78.239296)
		(end 155.368229 78.239296)
		(width 0.125)
		(layer "In2.Cu")
		(net 122)
	)
	(segment
		(start 154.600729 77.2875)
		(end 154.600729 76.693204)
		(width 0.125)
		(layer "In2.Cu")
		(net 122)
	)
	(segment
		(start 157.900729 77.18)
		(end 157.900729 77.143206)
		(width 0.125)
		(layer "In2.Cu")
		(net 122)
	)
	(segment
		(start 156.358229 78.239296)
		(end 156.468229 78.239296)
		(width 0.125)
		(layer "In2.Cu")
		(net 122)
	)
	(segment
		(start 154.925729 77.2875)
		(end 154.925729 77.62)
		(width 0.125)
		(layer "In2.Cu")
		(net 122)
	)
	(segment
		(start 153.825729 77.18)
		(end 153.825729 77.5125)
		(width 0.125)
		(layer "In2.Cu")
		(net 122)
	)
	(segment
		(start 161.525729 77.188416)
		(end 161.525729 77.2875)
		(width 0.125)
		(layer "In2.Cu")
		(net 122)
	)
	(segment
		(start 163.508229 77.5125)
		(end 163.618229 77.5125)
		(width 0.125)
		(layer "In2.Cu")
		(net 122)
	)
	(segment
		(start 162.300729 77.906796)
		(end 162.300729 77.5125)
		(width 0.125)
		(layer "In2.Cu")
		(net 122)
	)
	(segment
		(start 156.800729 77.906796)
		(end 156.800729 77.62)
		(width 0.125)
		(layer "In2.Cu")
		(net 122)
	)
	(segment
		(start 192.221599 63.787501)
		(end 192.662501 63.346599)
		(width 0.125)
		(layer "In2.Cu")
		(net 122)
	)
	(segment
		(start 158.225729 77.143206)
		(end 158.225729 77.18)
		(width 0.125)
		(layer "In2.Cu")
		(net 122)
	)
	(segment
		(start 156.800729 77.62)
		(end 156.800729 77.18)
		(width 0.125)
		(layer "In2.Cu")
		(net 122)
	)
	(segment
		(start 154.600729 77.5125)
		(end 154.600729 77.2875)
		(width 0.125)
		(layer "In2.Cu")
		(net 122)
	)
	(segment
		(start 130.530532 76.65)
		(end 130.868031 76.987499)
		(width 0.125)
		(layer "In2.Cu")
		(net 122)
	)
	(segment
		(start 159.325729 77.188416)
		(end 159.325729 77.2875)
		(width 0.125)
		(layer "In2.Cu")
		(net 122)
	)
	(segment
		(start 159.000729 77.906771)
		(end 159.000729 77.5125)
		(width 0.125)
		(layer "In2.Cu")
		(net 122)
	)
	(segment
		(start 157.125729 77.143206)
		(end 157.125729 77.18)
		(width 0.125)
		(layer "In2.Cu")
		(net 122)
	)
	(segment
		(start 153.825729 76.693204)
		(end 153.825729 77.18)
		(width 0.125)
		(layer "In2.Cu")
		(net 122)
	)
	(segment
		(start 158.225729 77.5125)
		(end 158.225729 77.906771)
		(width 0.125)
		(layer "In2.Cu")
		(net 122)
	)
	(segment
		(start 159.099812 77.089333)
		(end 159.226646 77.089333)
		(width 0.125)
		(layer "In2.Cu")
		(net 122)
	)
	(segment
		(start 154.158229 78.239296)
		(end 154.268229 78.239296)
		(width 0.125)
		(layer "In2.Cu")
		(net 122)
	)
	(segment
		(start 162.300729 77.5125)
		(end 162.300729 77.2875)
		(width 0.125)
		(layer "In2.Cu")
		(net 122)
	)
	(segment
		(start 161.299812 77.089333)
		(end 161.426646 77.089333)
		(width 0.125)
		(layer "In2.Cu")
		(net 122)
	)
	(segment
		(start 161.525729 77.5125)
		(end 161.525729 77.906796)
		(width 0.125)
		(layer "In2.Cu")
		(net 122)
	)
	(segment
		(start 158.008229 77.035706)
		(end 158.118229 77.035706)
		(width 0.125)
		(layer "In2.Cu")
		(net 122)
	)
	(segment
		(start 165.43014 77.5125)
		(end 167.61632 75.32632)
		(width 0.125)
		(layer "In2.Cu")
		(net 122)
	)
	(segment
		(start 159.000729 77.2875)
		(end 159.000729 77.188416)
		(width 0.125)
		(layer "In2.Cu")
		(net 122)
	)
	(segment
		(start 159.658229 78.239271)
		(end 159.768229 78.239271)
		(width 0.125)
		(layer "In2.Cu")
		(net 122)
	)
	(segment
		(start 160.425729 77.2875)
		(end 160.425729 77.5125)
		(width 0.125)
		(layer "In2.Cu")
		(net 122)
	)
	(segment
		(start 154.925729 77.62)
		(end 154.925729 77.906796)
		(width 0.125)
		(layer "In2.Cu")
		(net 122)
	)
	(segment
		(start 155.808229 77.5125)
		(end 155.918229 77.5125)
		(width 0.125)
		(layer "In2.Cu")
		(net 122)
	)
	(segment
		(start 162.625729 77.62)
		(end 162.625729 77.906771)
		(width 0.125)
		(layer "In2.Cu")
		(net 122)
	)
	(segment
		(start 160.758229 78.239296)
		(end 160.868229 78.239296)
		(width 0.125)
		(layer "In2.Cu")
		(net 122)
	)
	(segment
		(start 160.199812 77.089333)
		(end 160.326646 77.089333)
		(width 0.125)
		(layer "In2.Cu")
		(net 122)
	)
	(segment
		(start 160.425729 77.188416)
		(end 160.425729 77.2875)
		(width 0.125)
		(layer "In2.Cu")
		(net 122)
	)
	(segment
		(start 153.500729 77.18)
		(end 153.500729 76.693204)
		(width 0.125)
		(layer "In2.Cu")
		(net 122)
	)
	(segment
		(start 163.618229 77.5125)
		(end 165.43014 77.5125)
		(width 0.125)
		(layer "In2.Cu")
		(net 122)
	)
	(segment
		(start 192.662501 63.346599)
		(end 192.662501 63.024999)
		(width 0.125)
		(layer "In2.Cu")
		(net 122)
	)
	(segment
		(start 155.700729 77.906796)
		(end 155.700729 77.62)
		(width 0.125)
		(layer "In2.Cu")
		(net 122)
	)
	(segment
		(start 162.300729 77.2875)
		(end 162.300729 76.693204)
		(width 0.125)
		(layer "In2.Cu")
		(net 122)
	)
	(segment
		(start 158.558229 78.239271)
		(end 158.668229 78.239271)
		(width 0.125)
		(layer "In2.Cu")
		(net 122)
	)
	(segment
		(start 163.400729 77.906771)
		(end 163.400729 77.62)
		(width 0.125)
		(layer "In2.Cu")
		(net 122)
	)
	(segment
		(start 156.800729 77.18)
		(end 156.800729 77.143206)
		(width 0.125)
		(layer "In2.Cu")
		(net 122)
	)
	(segment
		(start 130.868031 77.127131)
		(end 131.2534 77.5125)
		(width 0.125)
		(layer "In2.Cu")
		(net 122)
	)
	(segment
		(start 161.858229 78.239296)
		(end 161.968229 78.239296)
		(width 0.125)
		(layer "In2.Cu")
		(net 122)
	)
	(segment
		(start 179.155139 63.787501)
		(end 192.221599 63.787501)
		(width 0.125)
		(layer "In2.Cu")
		(net 122)
	)
	(segment
		(start 130.868031 76.987499)
		(end 130.868031 77.127131)
		(width 0.125)
		(layer "In2.Cu")
		(net 122)
	)
	(segment
		(start 162.958229 78.239271)
		(end 163.068229 78.239271)
		(width 0.125)
		(layer "In2.Cu")
		(net 122)
	)
	(arc
		(start 162.625729 77.906771)
		(mid 162.723116 78.141884)
		(end 162.958229 78.239271)
		(width 0.125)
		(layer "In2.Cu")
		(net 122)
	)
	(arc
		(start 163.068229 78.239271)
		(mid 163.303342 78.141884)
		(end 163.400729 77.906771)
		(width 0.125)
		(layer "In2.Cu")
		(net 122)
	)
	(arc
		(start 153.168229 77.5125)
		(mid 153.403342 77.415113)
		(end 153.500729 77.18)
		(width 0.125)
		(layer "In2.Cu")
		(net 122)
	)
	(arc
		(start 161.968229 78.239296)
		(mid 162.203342 78.141909)
		(end 162.300729 77.906796)
		(width 0.125)
		(layer "In2.Cu")
		(net 122)
	)
	(arc
		(start 153.718229 76.585704)
		(mid 153.794243 76.61719)
		(end 153.825729 76.693204)
		(width 0.125)
		(layer "In2.Cu")
		(net 122)
	)
	(arc
		(start 159.768229 78.239271)
		(mid 160.003342 78.141884)
		(end 160.100729 77.906771)
		(width 0.125)
		(layer "In2.Cu")
		(net 122)
	)
	(arc
		(start 158.225729 77.906771)
		(mid 158.323116 78.141884)
		(end 158.558229 78.239271)
		(width 0.125)
		(layer "In2.Cu")
		(net 122)
	)
	(arc
		(start 161.200729 77.188416)
		(mid 161.22975 77.118354)
		(end 161.299812 77.089333)
		(width 0.125)
		(layer "In2.Cu")
		(net 122)
	)
	(arc
		(start 162.518229 76.585704)
		(mid 162.594243 76.61719)
		(end 162.625729 76.693204)
		(width 0.125)
		(layer "In2.Cu")
		(net 122)
	)
	(arc
		(start 160.326646 77.089333)
		(mid 160.396708 77.118354)
		(end 160.425729 77.188416)
		(width 0.125)
		(layer "In2.Cu")
		(net 122)
	)
	(arc
		(start 157.018229 77.035706)
		(mid 157.094243 77.067192)
		(end 157.125729 77.143206)
		(width 0.125)
		(layer "In2.Cu")
		(net 122)
	)
	(arc
		(start 154.268229 78.239296)
		(mid 154.503342 78.141909)
		(end 154.600729 77.906796)
		(width 0.125)
		(layer "In2.Cu")
		(net 122)
	)
	(arc
		(start 155.368229 78.239296)
		(mid 155.603342 78.141909)
		(end 155.700729 77.906796)
		(width 0.125)
		(layer "In2.Cu")
		(net 122)
	)
	(arc
		(start 159.000729 77.188416)
		(mid 159.02975 77.118354)
		(end 159.099812 77.089333)
		(width 0.125)
		(layer "In2.Cu")
		(net 122)
	)
	(arc
		(start 154.600729 76.693204)
		(mid 154.632215 76.61719)
		(end 154.708229 76.585704)
		(width 0.125)
		(layer "In2.Cu")
		(net 122)
	)
	(arc
		(start 159.226646 77.089333)
		(mid 159.296708 77.118354)
		(end 159.325729 77.188416)
		(width 0.125)
		(layer "In2.Cu")
		(net 122)
	)
	(arc
		(start 154.818229 76.585704)
		(mid 154.894243 76.61719)
		(end 154.925729 76.693204)
		(width 0.125)
		(layer "In2.Cu")
		(net 122)
	)
	(arc
		(start 154.925729 77.906796)
		(mid 155.023116 78.141909)
		(end 155.258229 78.239296)
		(width 0.125)
		(layer "In2.Cu")
		(net 122)
	)
	(arc
		(start 157.125729 77.18)
		(mid 157.223116 77.415113)
		(end 157.458229 77.5125)
		(width 0.125)
		(layer "In2.Cu")
		(net 122)
	)
	(arc
		(start 155.918229 77.5125)
		(mid 155.994243 77.543986)
		(end 156.025729 77.62)
		(width 0.125)
		(layer "In2.Cu")
		(net 122)
	)
	(arc
		(start 162.300729 76.693204)
		(mid 162.332215 76.61719)
		(end 162.408229 76.585704)
		(width 0.125)
		(layer "In2.Cu")
		(net 122)
	)
	(arc
		(start 161.426646 77.089333)
		(mid 161.496708 77.118354)
		(end 161.525729 77.188416)
		(width 0.125)
		(layer "In2.Cu")
		(net 122)
	)
	(arc
		(start 158.118229 77.035706)
		(mid 158.194243 77.067192)
		(end 158.225729 77.143206)
		(width 0.125)
		(layer "In2.Cu")
		(net 122)
	)
	(arc
		(start 161.525729 77.906796)
		(mid 161.623116 78.141909)
		(end 161.858229 78.239296)
		(width 0.125)
		(layer "In2.Cu")
		(net 122)
	)
	(arc
		(start 153.825729 77.906796)
		(mid 153.923116 78.141909)
		(end 154.158229 78.239296)
		(width 0.125)
		(layer "In2.Cu")
		(net 122)
	)
	(arc
		(start 157.900729 77.143206)
		(mid 157.932215 77.067192)
		(end 158.008229 77.035706)
		(width 0.125)
		(layer "In2.Cu")
		(net 122)
	)
	(arc
		(start 163.400729 77.62)
		(mid 163.432215 77.543986)
		(end 163.508229 77.5125)
		(width 0.125)
		(layer "In2.Cu")
		(net 122)
	)
	(arc
		(start 160.868229 78.239296)
		(mid 161.103342 78.141909)
		(end 161.200729 77.906796)
		(width 0.125)
		(layer "In2.Cu")
		(net 122)
	)
	(arc
		(start 155.700729 77.62)
		(mid 155.732215 77.543986)
		(end 155.808229 77.5125)
		(width 0.125)
		(layer "In2.Cu")
		(net 122)
	)
	(arc
		(start 159.325729 77.906771)
		(mid 159.423116 78.141884)
		(end 159.658229 78.239271)
		(width 0.125)
		(layer "In2.Cu")
		(net 122)
	)
	(arc
		(start 157.568229 77.5125)
		(mid 157.803342 77.415113)
		(end 157.900729 77.18)
		(width 0.125)
		(layer "In2.Cu")
		(net 122)
	)
	(arc
		(start 153.500729 76.693204)
		(mid 153.532215 76.61719)
		(end 153.608229 76.585704)
		(width 0.125)
		(layer "In2.Cu")
		(net 122)
	)
	(arc
		(start 160.425729 77.906796)
		(mid 160.523116 78.141909)
		(end 160.758229 78.239296)
		(width 0.125)
		(layer "In2.Cu")
		(net 122)
	)
	(arc
		(start 156.800729 77.143206)
		(mid 156.832215 77.067192)
		(end 156.908229 77.035706)
		(width 0.125)
		(layer "In2.Cu")
		(net 122)
	)
	(arc
		(start 156.025729 77.906796)
		(mid 156.123116 78.141909)
		(end 156.358229 78.239296)
		(width 0.125)
		(layer "In2.Cu")
		(net 122)
	)
	(arc
		(start 160.100729 77.188416)
		(mid 160.12975 77.118354)
		(end 160.199812 77.089333)
		(width 0.125)
		(layer "In2.Cu")
		(net 122)
	)
	(arc
		(start 158.668229 78.239271)
		(mid 158.903342 78.141884)
		(end 159.000729 77.906771)
		(width 0.125)
		(layer "In2.Cu")
		(net 122)
	)
	(arc
		(start 156.468229 78.239296)
		(mid 156.703342 78.141909)
		(end 156.800729 77.906796)
		(width 0.125)
		(layer "In2.Cu")
		(net 122)
	)
	(segment
		(start 134.7 109.1)
		(end 135.52 109.1)
		(width 0.1)
		(layer "F.Cu")
		(net 123)
	)
	(via
		(at 202.8 67.5)
		(size 0.45)
		(drill 0.1)
		(layers "F.Cu" "B.Cu")
		(net 123)
	)
	(via
		(at 204 92.8)
		(size 0.45)
		(drill 0.1)
		(layers "F.Cu" "B.Cu")
		(net 123)
	)
	(via
		(at 206.8 72.8)
		(size 0.45)
		(drill 0.1)
		(layers "F.Cu" "B.Cu")
		(net 123)
	)
	(via
		(at 134.7 109.1)
		(size 0.45)
		(drill 0.1)
		(layers "F.Cu" "B.Cu")
		(net 123)
	)
	(segment
		(start 207.48 63.453001)
		(end 209.200001 63.453001)
		(width 0.1)
		(layer "B.Cu")
		(net 123)
	)
	(segment
		(start 205.5 64.2)
		(end 207.2 64.2)
		(width 0.1)
		(layer "B.Cu")
		(net 123)
	)
	(segment
		(start 204 91.8)
		(end 204.8 91)
		(width 0.1)
		(layer "B.Cu")
		(net 123)
	)
	(segment
		(start 209.201 66.954)
		(end 207.484 66.954)
		(width 0.1)
		(layer "B.Cu")
		(net 123)
	)
	(segment
		(start 204.8 91)
		(end 206.2 91)
		(width 0.1)
		(layer "B.Cu")
		(net 123)
	)
	(segment
		(start 210.8 78)
		(end 210.617631 77.817631)
		(width 0.1)
		(layer "B.Cu")
		(net 123)
	)
	(segment
		(start 205.1 64.6)
		(end 205.1 67.6)
		(width 0.1)
		(layer "B.Cu")
		(net 123)
	)
	(segment
		(start 209.200001 63.453001)
		(end 209.201 63.454)
		(width 0.1)
		(layer "B.Cu")
		(net 123)
	)
	(segment
		(start 205.3 67.7)
		(end 205.7 67.7)
		(width 0.1)
		(layer "B.Cu")
		(net 123)
	)
	(segment
		(start 205.1 67.7)
		(end 205.3 67.7)
		(width 0.1)
		(layer "B.Cu")
		(net 123)
	)
	(segment
		(start 205.9 67.5)
		(end 206.93 67.5)
		(width 0.1)
		(layer "B.Cu")
		(net 123)
	)
	(segment
		(start 207.2 64.2)
		(end 207.48 63.92)
		(width 0.1)
		(layer "B.Cu")
		(net 123)
	)
	(segment
		(start 205.2 67.7)
		(end 205.1 67.6)
		(width 0.1)
		(layer "B.Cu")
		(net 123)
	)
	(segment
		(start 205.7 67.7)
		(end 205.9 67.5)
		(width 0.1)
		(layer "B.Cu")
		(net 123)
	)
	(segment
		(start 207.484 66.954)
		(end 207.48 66.95)
		(width 0.1)
		(layer "B.Cu")
		(net 123)
	)
	(segment
		(start 204 92.8)
		(end 204 91.8)
		(width 0.1)
		(layer "B.Cu")
		(net 123)
	)
	(segment
		(start 207.48 63.453001)
		(end 207.48 63.92)
		(width 0.1)
		(layer "B.Cu")
		(net 123)
	)
	(segment
		(start 205.1 67.6)
		(end 205.1 67.7)
		(width 0.1)
		(layer "B.Cu")
		(net 123)
	)
	(segment
		(start 207.6 73.6)
		(end 206.8 72.8)
		(width 0.1)
		(layer "B.Cu")
		(net 123)
	)
	(segment
		(start 205.3 67.7)
		(end 205.2 67.7)
		(width 0.1)
		(layer "B.Cu")
		(net 123)
	)
	(segment
		(start 206.2 91)
		(end 210.8 86.4)
		(width 0.1)
		(layer "B.Cu")
		(net 123)
	)
	(segment
		(start 203 67.7)
		(end 205.1 67.7)
		(width 0.1)
		(layer "B.Cu")
		(net 123)
	)
	(segment
		(start 210.617631 77.817631)
		(end 210.617631 75.217631)
		(width 0.1)
		(layer "B.Cu")
		(net 123)
	)
	(segment
		(start 210.8 86.4)
		(end 210.8 78)
		(width 0.1)
		(layer "B.Cu")
		(net 123)
	)
	(segment
		(start 205.5 64.2)
		(end 205.1 64.6)
		(width 0.1)
		(layer "B.Cu")
		(net 123)
	)
	(segment
		(start 209 73.6)
		(end 207.6 73.6)
		(width 0.1)
		(layer "B.Cu")
		(net 123)
	)
	(segment
		(start 202.8 67.5)
		(end 203 67.7)
		(width 0.1)
		(layer "B.Cu")
		(net 123)
	)
	(segment
		(start 206.93 67.5)
		(end 207.48 66.95)
		(width 0.1)
		(layer "B.Cu")
		(net 123)
	)
	(segment
		(start 210.617631 75.217631)
		(end 209 73.6)
		(width 0.1)
		(layer "B.Cu")
		(net 123)
	)
	(segment
		(start 202.8 68.8)
		(end 206.8 72.8)
		(width 0.1)
		(layer "In5.Cu")
		(net 123)
	)
	(segment
		(start 202.8 67.5)
		(end 202.8 68.8)
		(width 0.1)
		(layer "In5.Cu")
		(net 123)
	)
	(segment
		(start 152.8 96.434314)
		(end 155.034314 94.2)
		(width 0.1)
		(layer "In7.Cu")
		(net 123)
	)
	(segment
		(start 198.562159 92.962159)
		(end 198.848975 93.248975)
		(width 0.1)
		(layer "In7.Cu")
		(net 123)
	)
	(segment
		(start 198.848975 93.248975)
		(end 203.551025 93.248975)
		(width 0.1)
		(layer "In7.Cu")
		(net 123)
	)
	(segment
		(start 135.4 108.1)
		(end 135.9 108.1)
		(width 0.1)
		(layer "In7.Cu")
		(net 123)
	)
	(segment
		(start 144.234314 106.4)
		(end 148.834314 101.8)
		(width 0.1)
		(layer "In7.Cu")
		(net 123)
	)
	(segment
		(start 203.551025 93.248975)
		(end 204 92.8)
		(width 0.1)
		(layer "In7.Cu")
		(net 123)
	)
	(segment
		(start 135.9 108.1)
		(end 137.6 106.4)
		(width 0.1)
		(layer "In7.Cu")
		(net 123)
	)
	(segment
		(start 151.6 101.8)
		(end 152.8 100.6)
		(width 0.1)
		(layer "In7.Cu")
		(net 123)
	)
	(segment
		(start 148.834314 101.8)
		(end 151.6 101.8)
		(width 0.1)
		(layer "In7.Cu")
		(net 123)
	)
	(segment
		(start 134.7 108.8)
		(end 135.4 108.1)
		(width 0.1)
		(layer "In7.Cu")
		(net 123)
	)
	(segment
		(start 152.8 100.6)
		(end 152.8 96.434314)
		(width 0.1)
		(layer "In7.Cu")
		(net 123)
	)
	(segment
		(start 155.034314 94.2)
		(end 191.2 94.2)
		(width 0.1)
		(layer "In7.Cu")
		(net 123)
	)
	(segment
		(start 192.437841 92.962159)
		(end 198.562159 92.962159)
		(width 0.1)
		(layer "In7.Cu")
		(net 123)
	)
	(segment
		(start 134.7 109.1)
		(end 134.7 108.8)
		(width 0.1)
		(layer "In7.Cu")
		(net 123)
	)
	(segment
		(start 137.6 106.4)
		(end 144.234314 106.4)
		(width 0.1)
		(layer "In7.Cu")
		(net 123)
	)
	(segment
		(start 191.2 94.2)
		(end 192.437841 92.962159)
		(width 0.1)
		(layer "In7.Cu")
		(net 123)
	)
	(via
		(at 202.3875 62.9)
		(size 0.45)
		(drill 0.1)
		(layers "F.Cu" "B.Cu")
		(net 124)
	)
	(via
		(at 127.830532 85.65)
		(size 0.45)
		(drill 0.1)
		(layers "F.Cu" "B.Cu")
		(net 124)
	)
	(segment
		(start 204.158 59.290001)
		(end 204.083 59.365001)
		(width 0.17)
		(layer "B.Cu")
		(net 124)
	)
	(segment
		(start 202.275 61.872488)
		(end 202.275 62.7875)
		(width 0.17)
		(layer "B.Cu")
		(net 124)
	)
	(segment
		(start 202.275 62.7875)
		(end 202.3875 62.9)
		(width 0.17)
		(layer "B.Cu")
		(net 124)
	)
	(segment
		(start 204.083 60.064488)
		(end 202.275 61.872488)
		(width 0.17)
		(layer "B.Cu")
		(net 124)
	)
	(segment
		(start 204.158 58.39)
		(end 204.158 59.290001)
		(width 0.17)
		(layer "B.Cu")
		(net 124)
	)
	(segment
		(start 204.083 59.365001)
		(end 204.083 60.064488)
		(width 0.17)
		(layer "B.Cu")
		(net 124)
	)
	(segment
		(start 162.581409 85.823956)
		(end 162.691409 85.823956)
		(width 0.125)
		(layer "In2.Cu")
		(net 124)
	)
	(segment
		(start 163.131409 86.75)
		(end 168.920562 86.75)
		(width 0.125)
		(layer "In2.Cu")
		(net 124)
	)
	(segment
		(start 202.212501 64.546599)
		(end 202.212501 63.074999)
		(width 0.125)
		(layer "In2.Cu")
		(net 124)
	)
	(segment
		(start 162.031409 87.67605)
		(end 162.141409 87.67605)
		(width 0.125)
		(layer "In2.Cu")
		(net 124)
	)
	(segment
		(start 195.7125 71.0466)
		(end 195.7125 66.6466)
		(width 0.125)
		(layer "In2.Cu")
		(net 124)
	)
	(segment
		(start 193.959101 72.799999)
		(end 195.7125 71.0466)
		(width 0.125)
		(layer "In2.Cu")
		(net 124)
	)
	(segment
		(start 162.473909 87.34355)
		(end 162.473909 85.931456)
		(width 0.125)
		(layer "In2.Cu")
		(net 124)
	)
	(segment
		(start 162.798909 85.931456)
		(end 162.798909 86.4175)
		(width 0.125)
		(layer "In2.Cu")
		(net 124)
	)
	(segment
		(start 158.2109 86.75)
		(end 161.591409 86.75)
		(width 0.125)
		(layer "In2.Cu")
		(net 124)
	)
	(segment
		(start 157.9234 86.4625)
		(end 158.2109 86.75)
		(width 0.125)
		(layer "In2.Cu")
		(net 124)
	)
	(segment
		(start 155.9166 86.4625)
		(end 157.9234 86.4625)
		(width 0.125)
		(layer "In2.Cu")
		(net 124)
	)
	(segment
		(start 145.2534 86.8375)
		(end 155.5416 86.8375)
		(width 0.125)
		(layer "In2.Cu")
		(net 124)
	)
	(segment
		(start 144.9284 86.5125)
		(end 145.2534 86.8375)
		(width 0.125)
		(layer "In2.Cu")
		(net 124)
	)
	(segment
		(start 127.830532 86.003553)
		(end 128.339479 86.5125)
		(width 0.125)
		(layer "In2.Cu")
		(net 124)
	)
	(segment
		(start 201.6466 65.1125)
		(end 202.212501 64.546599)
		(width 0.125)
		(layer "In2.Cu")
		(net 124)
	)
	(segment
		(start 168.920562 86.75)
		(end 182.870563 72.799999)
		(width 0.125)
		(layer "In2.Cu")
		(net 124)
	)
	(segment
		(start 161.698909 86.8575)
		(end 161.698909 87.34355)
		(width 0.125)
		(layer "In2.Cu")
		(net 124)
	)
	(segment
		(start 182.870563 72.799999)
		(end 193.959101 72.799999)
		(width 0.125)
		(layer "In2.Cu")
		(net 124)
	)
	(segment
		(start 155.5416 86.8375)
		(end 155.9166 86.4625)
		(width 0.125)
		(layer "In2.Cu")
		(net 124)
	)
	(segment
		(start 197.2466 65.1125)
		(end 201.6466 65.1125)
		(width 0.125)
		(layer "In2.Cu")
		(net 124)
	)
	(segment
		(start 195.7125 66.6466)
		(end 197.2466 65.1125)
		(width 0.125)
		(layer "In2.Cu")
		(net 124)
	)
	(segment
		(start 128.339479 86.5125)
		(end 144.9284 86.5125)
		(width 0.125)
		(layer "In2.Cu")
		(net 124)
	)
	(segment
		(start 202.212501 63.074999)
		(end 202.3875 62.9)
		(width 0.125)
		(layer "In2.Cu")
		(net 124)
	)
	(segment
		(start 127.830532 85.65)
		(end 127.830532 86.003553)
		(width 0.125)
		(layer "In2.Cu")
		(net 124)
	)
	(arc
		(start 161.698909 87.34355)
		(mid 161.796296 87.578663)
		(end 162.031409 87.67605)
		(width 0.125)
		(layer "In2.Cu")
		(net 124)
	)
	(arc
		(start 162.691409 85.823956)
		(mid 162.767423 85.855442)
		(end 162.798909 85.931456)
		(width 0.125)
		(layer "In2.Cu")
		(net 124)
	)
	(arc
		(start 162.473909 85.931456)
		(mid 162.505395 85.855442)
		(end 162.581409 85.823956)
		(width 0.125)
		(layer "In2.Cu")
		(net 124)
	)
	(arc
		(start 162.141409 87.67605)
		(mid 162.376522 87.578663)
		(end 162.473909 87.34355)
		(width 0.125)
		(layer "In2.Cu")
		(net 124)
	)
	(arc
		(start 162.798909 86.4175)
		(mid 162.896296 86.652613)
		(end 163.131409 86.75)
		(width 0.125)
		(layer "In2.Cu")
		(net 124)
	)
	(arc
		(start 161.591409 86.75)
		(mid 161.667423 86.781486)
		(end 161.698909 86.8575)
		(width 0.125)
		(layer "In2.Cu")
		(net 124)
	)
	(segment
		(start 128.093412 82)
		(end 128.196706 82.103294)
		(width 0.17)
		(layer "F.Cu")
		(net 125)
	)
	(segment
		(start 126.230532 81.15)
		(end 126.505532 81.425)
		(width 0.17)
		(layer "F.Cu")
		(net 125)
	)
	(segment
		(start 126.852512 82)
		(end 128.093412 82)
		(width 0.17)
		(layer "F.Cu")
		(net 125)
	)
	(segment
		(start 126.505532 81.65302)
		(end 126.852512 82)
		(width 0.17)
		(layer "F.Cu")
		(net 125)
	)
	(segment
		(start 126.505532 81.425)
		(end 126.505532 81.65302)
		(width 0.17)
		(layer "F.Cu")
		(net 125)
	)
	(via
		(at 128.196706 82.103294)
		(size 0.45)
		(drill 0.1)
		(layers "F.Cu" "B.Cu")
		(net 125)
	)
	(via
		(at 191.4 71.474999)
		(size 0.45)
		(drill 0.1)
		(layers "F.Cu" "B.Cu")
		(net 125)
	)
	(segment
		(start 191.627512 67.425)
		(end 192.527512 66.525)
		(width 0.17)
		(layer "B.Cu")
		(net 125)
	)
	(segment
		(start 190.572488 67.425)
		(end 191.627512 67.425)
		(width 0.17)
		(layer "B.Cu")
		(net 125)
	)
	(segment
		(start 193.672488 66.525)
		(end 194.175 67.027512)
		(width 0.17)
		(layer "B.Cu")
		(net 125)
	)
	(segment
		(start 191.5125 71.362499)
		(end 191.4 71.474999)
		(width 0.17)
		(layer "B.Cu")
		(net 125)
	)
	(segment
		(start 192.527512 66.525)
		(end 193.672488 66.525)
		(width 0.17)
		(layer "B.Cu")
		(net 125)
	)
	(segment
		(start 195.083 59.664488)
		(end 193.472488 61.275)
		(width 0.17)
		(layer "B.Cu")
		(net 125)
	)
	(segment
		(start 190.572488 61.275)
		(end 189.575 62.272488)
		(width 0.17)
		(layer "B.Cu")
		(net 125)
	)
	(segment
		(start 189.575 66.427512)
		(end 190.572488 67.425)
		(width 0.17)
		(layer "B.Cu")
		(net 125)
	)
	(segment
		(start 195.158 59.290001)
		(end 195.083 59.365001)
		(width 0.17)
		(layer "B.Cu")
		(net 125)
	)
	(segment
		(start 194.175 67.027512)
		(end 194.175 69.272488)
		(width 0.17)
		(layer "B.Cu")
		(net 125)
	)
	(segment
		(start 189.575 62.272488)
		(end 189.575 66.427512)
		(width 0.17)
		(layer "B.Cu")
		(net 125)
	)
	(segment
		(start 195.158 58.39)
		(end 195.158 59.290001)
		(width 0.17)
		(layer "B.Cu")
		(net 125)
	)
	(segment
		(start 195.083 59.365001)
		(end 195.083 59.664488)
		(width 0.17)
		(layer "B.Cu")
		(net 125)
	)
	(segment
		(start 194.175 69.272488)
		(end 192.084989 71.362499)
		(width 0.17)
		(layer "B.Cu")
		(net 125)
	)
	(segment
		(start 192.084989 71.362499)
		(end 191.5125 71.362499)
		(width 0.17)
		(layer "B.Cu")
		(net 125)
	)
	(segment
		(start 193.472488 61.275)
		(end 190.572488 61.275)
		(width 0.17)
		(layer "B.Cu")
		(net 125)
	)
	(segment
		(start 129.3034 85.0125)
		(end 128.6375 84.3466)
		(width 0.125)
		(layer "In2.Cu")
		(net 125)
	)
	(segment
		(start 191.4 71.474999)
		(end 191.225001 71.3)
		(width 0.125)
		(layer "In2.Cu")
		(net 125)
	)
	(segment
		(start 182.249243 71.299999)
		(end 168.536742 85.0125)
		(width 0.125)
		(layer "In2.Cu")
		(net 125)
	)
	(segment
		(start 182.249243 71.299999)
		(end 191.225001 71.3)
		(width 0.125)
		(layer "In2.Cu")
		(net 125)
	)
	(segment
		(start 128.6375 82.2966)
		(end 128.444194 82.103294)
		(width 0.125)
		(layer "In2.Cu")
		(net 125)
	)
	(segment
		(start 128.444194 82.103294)
		(end 128.196706 82.103294)
		(width 0.125)
		(layer "In2.Cu")
		(net 125)
	)
	(segment
		(start 128.6375 84.3466)
		(end 128.6375 82.2966)
		(width 0.125)
		(layer "In2.Cu")
		(net 125)
	)
	(segment
		(start 168.536742 85.0125)
		(end 129.3034 85.0125)
		(width 0.125)
		(layer "In2.Cu")
		(net 125)
	)
	(segment
		(start 130.4 71.1)
		(end 133.680532 71.1)
		(width 0.1)
		(layer "F.Cu")
		(net 126)
	)
	(segment
		(start 130.1 70.1)
		(end 130.1 70.8)
		(width 0.1)
		(layer "F.Cu")
		(net 126)
	)
	(segment
		(start 130.1 70.8)
		(end 130.4 71.1)
		(width 0.1)
		(layer "F.Cu")
		(net 126)
	)
	(segment
		(start 129.2 69.2)
		(end 130.1 70.1)
		(width 0.1)
		(layer "F.Cu")
		(net 126)
	)
	(segment
		(start 133.680532 71.1)
		(end 134.130532 70.65)
		(width 0.1)
		(layer "F.Cu")
		(net 126)
	)
	(via
		(at 129.2 69.2)
		(size 0.45)
		(drill 0.1)
		(layers "F.Cu" "B.Cu")
		(net 126)
	)
	(segment
		(start 127.130532 81.15)
		(end 126.855532 81.425)
		(width 0.17)
		(layer "F.Cu")
		(net 128)
	)
	(segment
		(start 128.582844 81.676256)
		(end 128.603294 81.696706)
		(width 0.17)
		(layer "F.Cu")
		(net 128)
	)
	(segment
		(start 126.855532 81.425)
		(end 126.855532 81.508044)
		(width 0.17)
		(layer "F.Cu")
		(net 128)
	)
	(segment
		(start 127.023744 81.676256)
		(end 128.582844 81.676256)
		(width 0.17)
		(layer "F.Cu")
		(net 128)
	)
	(segment
		(start 126.855532 81.508044)
		(end 127.023744 81.676256)
		(width 0.17)
		(layer "F.Cu")
		(net 128)
	)
	(via
		(at 128.603294 81.696706)
		(size 0.45)
		(drill 0.1)
		(layers "F.Cu" "B.Cu")
		(net 128)
	)
	(via
		(at 191.4 70.899999)
		(size 0.45)
		(drill 0.1)
		(layers "F.Cu" "B.Cu")
		(net 128)
	)
	(segment
		(start 189.225 66.572488)
		(end 189.225 62.127512)
		(width 0.17)
		(layer "B.Cu")
		(net 128)
	)
	(segment
		(start 193.825 67.172488)
		(end 193.527512 66.875)
		(width 0.17)
		(layer "B.Cu")
		(net 128)
	)
	(segment
		(start 190.427512 60.925)
		(end 193.327512 60.925)
		(width 0.17)
		(layer "B.Cu")
		(net 128)
	)
	(segment
		(start 193.527512 66.875)
		(end 192.672488 66.875)
		(width 0.17)
		(layer "B.Cu")
		(net 128)
	)
	(segment
		(start 194.658 59.290001)
		(end 194.658 58.39)
		(width 0.17)
		(layer "B.Cu")
		(net 128)
	)
	(segment
		(start 190.427512 67.775)
		(end 189.225 66.572488)
		(width 0.17)
		(layer "B.Cu")
		(net 128)
	)
	(segment
		(start 191.5125 71.012499)
		(end 191.940013 71.012499)
		(width 0.17)
		(layer "B.Cu")
		(net 128)
	)
	(segment
		(start 191.772488 67.775)
		(end 190.427512 67.775)
		(width 0.17)
		(layer "B.Cu")
		(net 128)
	)
	(segment
		(start 192.203262 70.167928)
		(end 192.336866 70.034325)
		(width 0.17)
		(layer "B.Cu")
		(net 128)
	)
	(segment
		(start 189.225 62.127512)
		(end 190.427512 60.925)
		(width 0.17)
		(layer "B.Cu")
		(net 128)
	)
	(segment
		(start 194.733 59.519512)
		(end 194.733 59.365001)
		(width 0.17)
		(layer "B.Cu")
		(net 128)
	)
	(segment
		(start 191.4 70.899999)
		(end 191.5125 71.012499)
		(width 0.17)
		(layer "B.Cu")
		(net 128)
	)
	(segment
		(start 193.511411 69.4411)
		(end 193.825 69.127512)
		(width 0.17)
		(layer "B.Cu")
		(net 128)
	)
	(segment
		(start 193.825 69.127512)
		(end 193.825 67.172488)
		(width 0.17)
		(layer "B.Cu")
		(net 128)
	)
	(segment
		(start 192.91819 70.034325)
		(end 193.511411 69.4411)
		(width 0.17)
		(layer "B.Cu")
		(net 128)
	)
	(segment
		(start 193.327512 60.925)
		(end 194.733 59.519512)
		(width 0.17)
		(layer "B.Cu")
		(net 128)
	)
	(segment
		(start 192.672488 66.875)
		(end 191.772488 67.775)
		(width 0.17)
		(layer "B.Cu")
		(net 128)
	)
	(segment
		(start 194.733 59.365001)
		(end 194.658 59.290001)
		(width 0.17)
		(layer "B.Cu")
		(net 128)
	)
	(segment
		(start 191.940013 71.012499)
		(end 192.203262 70.74925)
		(width 0.17)
		(layer "B.Cu")
		(net 128)
	)
	(arc
		(start 192.203262 70.74925)
		(mid 192.26346 70.60392)
		(end 192.203263 70.458588)
		(width 0.17)
		(layer "B.Cu")
		(net 128)
	)
	(arc
		(start 192.336866 70.034325)
		(mid 192.482196 69.974128)
		(end 192.627528 70.034325)
		(width 0.17)
		(layer "B.Cu")
		(net 128)
	)
	(arc
		(start 192.627528 70.034325)
		(mid 192.772858 70.094524)
		(end 192.91819 70.034325)
		(width 0.17)
		(layer "B.Cu")
		(net 128)
	)
	(arc
		(start 192.203263 70.458588)
		(mid 192.143066 70.313257)
		(end 192.203262 70.167928)
		(width 0.17)
		(layer "B.Cu")
		(net 128)
	)
	(segment
		(start 191.225001 71.074998)
		(end 191.4 70.899999)
		(width 0.125)
		(layer "In2.Cu")
		(net 128)
	)
	(segment
		(start 129.0925 82.832347)
		(end 128.9825 82.832347)
		(width 0.125)
		(layer "In2.Cu")
		(net 128)
	)
	(segment
		(start 129.3966 84.7875)
		(end 168.443544 84.7875)
		(width 0.125)
		(layer "In2.Cu")
		(net 128)
	)
	(segment
		(start 128.603294 81.696706)
		(end 128.603294 81.944194)
		(width 0.125)
		(layer "In2.Cu")
		(net 128)
	)
	(segment
		(start 128.8625 84.2534)
		(end 129.3966 84.7875)
		(width 0.125)
		(layer "In2.Cu")
		(net 128)
	)
	(segment
		(start 129.2125 82.652347)
		(end 129.2125 82.712347)
		(width 0.125)
		(layer "In2.Cu")
		(net 128)
	)
	(segment
		(start 128.8625 82.952347)
		(end 128.8625 84.2534)
		(width 0.125)
		(layer "In2.Cu")
		(net 128)
	)
	(segment
		(start 128.8625 82.2034)
		(end 128.8625 82.412347)
		(width 0.125)
		(layer "In2.Cu")
		(net 128)
	)
	(segment
		(start 168.443544 84.7875)
		(end 182.156045 71.074999)
		(width 0.125)
		(layer "In2.Cu")
		(net 128)
	)
	(segment
		(start 182.156045 71.074999)
		(end 191.225001 71.074998)
		(width 0.125)
		(layer "In2.Cu")
		(net 128)
	)
	(segment
		(start 128.9825 82.532347)
		(end 129.0925 82.532347)
		(width 0.125)
		(layer "In2.Cu")
		(net 128)
	)
	(segment
		(start 128.603294 81.944194)
		(end 128.8625 82.2034)
		(width 0.125)
		(layer "In2.Cu")
		(net 128)
	)
	(arc
		(start 129.0925 82.532347)
		(mid 129.177353 82.567494)
		(end 129.2125 82.652347)
		(width 0.125)
		(layer "In2.Cu")
		(net 128)
	)
	(arc
		(start 128.8625 82.412347)
		(mid 128.897647 82.4972)
		(end 128.9825 82.532347)
		(width 0.125)
		(layer "In2.Cu")
		(net 128)
	)
	(arc
		(start 129.2125 82.712347)
		(mid 129.177353 82.7972)
		(end 129.0925 82.832347)
		(width 0.125)
		(layer "In2.Cu")
		(net 128)
	)
	(arc
		(start 128.9825 82.832347)
		(mid 128.897647 82.867494)
		(end 128.8625 82.952347)
		(width 0.125)
		(layer "In2.Cu")
		(net 128)
	)
	(segment
		(start 105.081602 128.519973)
		(end 106.88663 130.325)
		(width 0.19)
		(layer "F.Cu")
		(net 130)
	)
	(segment
		(start 102.912132 105.712132)
		(end 102.749498 105.712132)
		(width 0.19)
		(layer "F.Cu")
		(net 130)
	)
	(segment
		(start 117.065532 83.265)
		(end 117.180532 83.15)
		(width 0.19)
		(layer "F.Cu")
		(net 130)
	)
	(segment
		(start 105.130478 127.763993)
		(end 105.201188 127.834703)
		(width 0.19)
		(layer "F.Cu")
		(net 130)
	)
	(segment
		(start 102.749498 105.712132)
		(end 102.585 105.87663)
		(width 0.19)
		(layer "F.Cu")
		(net 130)
	)
	(segment
		(start 102.585 126.02337)
		(end 104.445208 127.883578)
		(width 0.19)
		(layer "F.Cu")
		(net 130)
	)
	(segment
		(start 102.585 105.87663)
		(end 102.585 113.82337)
		(width 0.19)
		(layer "F.Cu")
		(net 130)
	)
	(segment
		(start 105.201187 128.117545)
		(end 105.081602 128.237131)
		(width 0.19)
		(layer "F.Cu")
		(net 130)
	)
	(segment
		(start 104.485 115.72337)
		(end 104.485 119.67663)
		(width 0.19)
		(layer "F.Cu")
		(net 130)
	)
	(segment
		(start 104.485 119.67663)
		(end 102.585 121.57663)
		(width 0.19)
		(layer "F.Cu")
		(net 130)
	)
	(segment
		(start 102.585 121.57663)
		(end 102.585 126.02337)
		(width 0.19)
		(layer "F.Cu")
		(net 130)
	)
	(segment
		(start 106.88663 130.325)
		(end 111.985 130.325)
		(width 0.19)
		(layer "F.Cu")
		(net 130)
	)
	(segment
		(start 117.065532 83.885)
		(end 117.065532 83.265)
		(width 0.19)
		(layer "F.Cu")
		(net 130)
	)
	(segment
		(start 117.330532 84.15)
		(end 117.065532 83.885)
		(width 0.19)
		(layer "F.Cu")
		(net 130)
	)
	(segment
		(start 102.585 113.82337)
		(end 104.485 115.72337)
		(width 0.19)
		(layer "F.Cu")
		(net 130)
	)
	(segment
		(start 104.72805 127.883578)
		(end 104.847636 127.763993)
		(width 0.19)
		(layer "F.Cu")
		(net 130)
	)
	(segment
		(start 111.985 130.325)
		(end 112.1 130.21)
		(width 0.19)
		(layer "F.Cu")
		(net 130)
	)
	(via
		(at 102.912132 105.712132)
		(size 0.45)
		(drill 0.1)
		(layers "F.Cu" "B.Cu")
		(net 130)
	)
	(via
		(at 112.1 130.21)
		(size 0.45)
		(drill 0.1)
		(layers "F.Cu" "B.Cu")
		(net 130)
	)
	(via
		(at 117.180532 83.15)
		(size 0.45)
		(drill 0.1)
		(layers "F.Cu" "B.Cu")
		(net 130)
	)
	(arc
		(start 105.081602 128.237131)
		(mid 105.023023 128.378551)
		(end 105.081602 128.519973)
		(width 0.19)
		(layer "F.Cu")
		(net 130)
	)
	(arc
		(start 105.201188 127.834703)
		(mid 105.259766 127.976125)
		(end 105.201187 128.117545)
		(width 0.19)
		(layer "F.Cu")
		(net 130)
	)
	(arc
		(start 104.445208 127.883578)
		(mid 104.58663 127.942157)
		(end 104.72805 127.883578)
		(width 0.19)
		(layer "F.Cu")
		(net 130)
	)
	(arc
		(start 104.847636 127.763993)
		(mid 104.989056 127.705414)
		(end 105.130478 127.763993)
		(width 0.19)
		(layer "F.Cu")
		(net 130)
	)
	(segment
		(start 113.711 130.26)
		(end 113.086 130.26)
		(width 0.19)
		(layer "B.Cu")
		(net 130)
	)
	(segment
		(start 113.086 130.26)
		(end 113.021 130.325)
		(width 0.19)
		(layer "B.Cu")
		(net 130)
	)
	(segment
		(start 112.215 130.325)
		(end 112.1 130.21)
		(width 0.19)
		(layer "B.Cu")
		(net 130)
	)
	(segment
		(start 113.021 130.325)
		(end 112.215 130.325)
		(width 0.19)
		(layer "B.Cu")
		(net 130)
	)
	(segment
		(start 113.077252 84.415194)
		(end 113.285912 84.623854)
		(width 0.15)
		(layer "In7.Cu")
		(net 130)
	)
	(segment
		(start 115.456956 80.6375)
		(end 114.9375 81.156956)
		(width 0.15)
		(layer "In7.Cu")
		(net 130)
	)
	(segment
		(start 116.643044 80.6375)
		(end 115.456956 80.6375)
		(width 0.15)
		(layer "In7.Cu")
		(net 130)
	)
	(segment
		(start 117.9625 81.956956)
		(end 116.643044 80.6375)
		(width 0.15)
		(layer "In7.Cu")
		(net 130)
	)
	(segment
		(start 108.156956 89.3375)
		(end 105.456956 89.3375)
		(width 0.15)
		(layer "In7.Cu")
		(net 130)
	)
	(segment
		(start 102.912132 105.482323)
		(end 102.912132 105.712132)
		(width 0.15)
		(layer "In7.Cu")
		(net 130)
	)
	(segment
		(start 113.285912 84.821844)
		(end 113.236413 84.871344)
		(width 0.15)
		(layer "In7.Cu")
		(net 130)
	)
	(segment
		(start 113.745464 84.291444)
		(end 113.695965 84.340944)
		(width 0.15)
		(layer "In7.Cu")
		(net 130)
	)
	(segment
		(start 112.299433 84.995022)
		(end 112.631774 84.662685)
		(width 0.15)
		(layer "In7.Cu")
		(net 130)
	)
	(segment
		(start 117.443044 83.7625)
		(end 117.9625 83.243044)
		(width 0.15)
		(layer "In7.Cu")
		(net 130)
	)
	(segment
		(start 105.456956 89.3375)
		(end 103.1375 91.656956)
		(width 0.15)
		(layer "In7.Cu")
		(net 130)
	)
	(segment
		(start 114.9375 81.156956)
		(end 114.9375 81.856956)
		(width 0.15)
		(layer "In7.Cu")
		(net 130)
	)
	(segment
		(start 113.077252 84.217204)
		(end 113.12675 84.167709)
		(width 0.15)
		(layer "In7.Cu")
		(net 130)
	)
	(segment
		(start 117.018032 83.523576)
		(end 117.256956 83.7625)
		(width 0.15)
		(layer "In7.Cu")
		(net 130)
	)
	(segment
		(start 111.956956 85.3375)
		(end 112.299433 84.995022)
		(width 0.15)
		(layer "In7.Cu")
		(net 130)
	)
	(segment
		(start 117.9625 83.243044)
		(end 117.9625 81.956956)
		(width 0.15)
		(layer "In7.Cu")
		(net 130)
	)
	(segment
		(start 114.9375 81.856956)
		(end 114.2375 82.556956)
		(width 0.15)
		(layer "In7.Cu")
		(net 130)
	)
	(segment
		(start 103.1375 105.256955)
		(end 102.912132 105.482323)
		(width 0.15)
		(layer "In7.Cu")
		(net 130)
	)
	(segment
		(start 109.4375 88.056956)
		(end 108.156956 89.3375)
		(width 0.15)
		(layer "In7.Cu")
		(net 130)
	)
	(segment
		(start 110.856956 85.3375)
		(end 109.4375 86.756956)
		(width 0.15)
		(layer "In7.Cu")
		(net 130)
	)
	(segment
		(start 109.4375 86.756956)
		(end 109.4375 88.056956)
		(width 0.15)
		(layer "In7.Cu")
		(net 130)
	)
	(segment
		(start 113.497975 84.340944)
		(end 113.32474 84.167709)
		(width 0.15)
		(layer "In7.Cu")
		(net 130)
	)
	(segment
		(start 113.572228 83.920218)
		(end 113.745464 84.093454)
		(width 0.15)
		(layer "In7.Cu")
		(net 130)
	)
	(segment
		(start 117.180532 83.15)
		(end 117.018032 83.3125)
		(width 0.15)
		(layer "In7.Cu")
		(net 130)
	)
	(segment
		(start 117.256956 83.7625)
		(end 117.443044 83.7625)
		(width 0.15)
		(layer "In7.Cu")
		(net 130)
	)
	(segment
		(start 113.038423 84.871344)
		(end 112.829764 84.662685)
		(width 0.15)
		(layer "In7.Cu")
		(net 130)
	)
	(segment
		(start 114.2375 83.056956)
		(end 113.572228 83.722228)
		(width 0.15)
		(layer "In7.Cu")
		(net 130)
	)
	(segment
		(start 117.018032 83.3125)
		(end 117.018032 83.523576)
		(width 0.15)
		(layer "In7.Cu")
		(net 130)
	)
	(segment
		(start 114.2375 82.556956)
		(end 114.2375 83.056956)
		(width 0.15)
		(layer "In7.Cu")
		(net 130)
	)
	(segment
		(start 103.1375 91.656956)
		(end 103.1375 105.256955)
		(width 0.15)
		(layer "In7.Cu")
		(net 130)
	)
	(segment
		(start 111.956956 85.3375)
		(end 110.856956 85.3375)
		(width 0.15)
		(layer "In7.Cu")
		(net 130)
	)
	(arc
		(start 113.572228 83.722228)
		(mid 113.531223 83.821223)
		(end 113.572228 83.920218)
		(width 0.15)
		(layer "In7.Cu")
		(net 130)
	)
	(arc
		(start 113.236413 84.871344)
		(mid 113.137418 84.912349)
		(end 113.038423 84.871344)
		(width 0.15)
		(layer "In7.Cu")
		(net 130)
	)
	(arc
		(start 113.32474 84.167709)
		(mid 113.225745 84.126704)
		(end 113.12675 84.167709)
		(width 0.15)
		(layer "In7.Cu")
		(net 130)
	)
	(arc
		(start 112.829764 84.662685)
		(mid 112.730769 84.62168)
		(end 112.631774 84.662685)
		(width 0.15)
		(layer "In7.Cu")
		(net 130)
	)
	(arc
		(start 113.695965 84.340944)
		(mid 113.59697 84.381949)
		(end 113.497975 84.340944)
		(width 0.15)
		(layer "In7.Cu")
		(net 130)
	)
	(arc
		(start 113.285912 84.623854)
		(mid 113.326917 84.722849)
		(end 113.285912 84.821844)
		(width 0.15)
		(layer "In7.Cu")
		(net 130)
	)
	(arc
		(start 113.745464 84.093454)
		(mid 113.786469 84.192449)
		(end 113.745464 84.291444)
		(width 0.15)
		(layer "In7.Cu")
		(net 130)
	)
	(arc
		(start 113.077252 84.217204)
		(mid 113.036247 84.316199)
		(end 113.077252 84.415194)
		(width 0.15)
		(layer "In7.Cu")
		(net 130)
	)
	(segment
		(start 135.1 86.9)
		(end 135.1 88)
		(width 0.1)
		(layer "F.Cu")
		(net 131)
	)
	(segment
		(start 142.46 66.6)
		(end 144.135 68.275)
		(width 0.1)
		(layer "F.Cu")
		(net 131)
	)
	(segment
		(start 135.1 86.9)
		(end 135.9 86.1)
		(width 0.1)
		(layer "F.Cu")
		(net 131)
	)
	(segment
		(start 152.225 69.525)
		(end 151.5 70.25)
		(width 0.1)
		(layer "F.Cu")
		(net 131)
	)
	(segment
		(start 66.45 96.45)
		(end 66.6 96.3)
		(width 0.1)
		(layer "F.Cu")
		(net 131)
	)
	(segment
		(start 152.025 68.275)
		(end 152.225 68.475)
		(width 0.1)
		(layer "F.Cu")
		(net 131)
	)
	(segment
		(start 66.6 96.3)
		(end 66.6 95)
		(width 0.1)
		(layer "F.Cu")
		(net 131)
	)
	(segment
		(start 135.9 86.1)
		(end 136.380532 86.1)
		(width 0.1)
		(layer "F.Cu")
		(net 131)
	)
	(segment
		(start 151.5 70.25)
		(end 151.5 84.1)
		(width 0.1)
		(layer "F.Cu")
		(net 131)
	)
	(segment
		(start 135.1 88)
		(end 136.4 89.3)
		(width 0.1)
		(layer "F.Cu")
		(net 131)
	)
	(segment
		(start 136.830532 85.65)
		(end 136.380532 86.1)
		(width 0.1)
		(layer "F.Cu")
		(net 131)
	)
	(segment
		(start 144.135 68.275)
		(end 152.025 68.275)
		(width 0.1)
		(layer "F.Cu")
		(net 131)
	)
	(segment
		(start 136.4 89.3)
		(end 145.8 89.3)
		(width 0.1)
		(layer "F.Cu")
		(net 131)
	)
	(segment
		(start 66.05 96.45)
		(end 66.45 96.45)
		(width 0.1)
		(layer "F.Cu")
		(net 131)
	)
	(segment
		(start 152.225 68.475)
		(end 152.225 69.525)
		(width 0.1)
		(layer "F.Cu")
		(net 131)
	)
	(via
		(at 66.6 95)
		(size 0.45)
		(drill 0.1)
		(layers "F.Cu" "B.Cu")
		(net 131)
	)
	(via
		(at 142.46 66.6)
		(size 0.45)
		(drill 0.1)
		(layers "F.Cu" "B.Cu")
		(net 131)
	)
	(via
		(at 151.5 84.1)
		(size 0.45)
		(drill 0.1)
		(layers "F.Cu" "B.Cu")
		(net 131)
	)
	(via
		(at 145.8 89.3)
		(size 0.45)
		(drill 0.1)
		(layers "F.Cu" "B.Cu")
		(net 131)
	)
	(segment
		(start 146.9 89.3)
		(end 151.5 84.7)
		(width 0.1)
		(layer "B.Cu")
		(net 131)
	)
	(segment
		(start 145.8 89.3)
		(end 146.9 89.3)
		(width 0.1)
		(layer "B.Cu")
		(net 131)
	)
	(segment
		(start 151.5 84.7)
		(end 151.5 84.1)
		(width 0.1)
		(layer "B.Cu")
		(net 131)
	)
	(segment
		(start 66.1 86.3)
		(end 65.2 87.2)
		(width 0.1)
		(layer "In5.Cu")
		(net 131)
	)
	(segment
		(start 142.46 65.56)
		(end 141.9 65)
		(width 0.1)
		(layer "In5.Cu")
		(net 131)
	)
	(segment
		(start 66.1 77.275736)
		(end 66.1 86.3)
		(width 0.1)
		(layer "In5.Cu")
		(net 131)
	)
	(segment
		(start 71.300001 69.875737)
		(end 71.300001 72.075735)
		(width 0.1)
		(layer "In5.Cu")
		(net 131)
	)
	(segment
		(start 124.75 67.15)
		(end 112.150002 67.15)
		(width 0.1)
		(layer "In5.Cu")
		(net 131)
	)
	(segment
		(start 98.475736 68.000002)
		(end 98.075736 68.400002)
		(width 0.1)
		(layer "In5.Cu")
		(net 131)
	)
	(segment
		(start 71.300001 72.075735)
		(end 66.1 77.275736)
		(width 0.1)
		(layer "In5.Cu")
		(net 131)
	)
	(segment
		(start 112.150002 67.15)
		(end 111.3 68.000002)
		(width 0.1)
		(layer "In5.Cu")
		(net 131)
	)
	(segment
		(start 142.46 66.6)
		(end 142.46 65.56)
		(width 0.1)
		(layer "In5.Cu")
		(net 131)
	)
	(segment
		(start 72.775736 68.400002)
		(end 71.300001 69.875737)
		(width 0.1)
		(layer "In5.Cu")
		(net 131)
	)
	(segment
		(start 65.2 93.6)
		(end 66.6 95)
		(width 0.1)
		(layer "In5.Cu")
		(net 131)
	)
	(segment
		(start 141.9 65)
		(end 126.9 65)
		(width 0.1)
		(layer "In5.Cu")
		(net 131)
	)
	(segment
		(start 126.9 65)
		(end 124.75 67.15)
		(width 0.1)
		(layer "In5.Cu")
		(net 131)
	)
	(segment
		(start 111.3 68.000002)
		(end 98.475736 68.000002)
		(width 0.1)
		(layer "In5.Cu")
		(net 131)
	)
	(segment
		(start 65.2 87.2)
		(end 65.2 93.6)
		(width 0.1)
		(layer "In5.Cu")
		(net 131)
	)
	(segment
		(start 98.075736 68.400002)
		(end 72.775736 68.400002)
		(width 0.1)
		(layer "In5.Cu")
		(net 131)
	)
	(segment
		(start 192.306 147.785)
		(end 191.24937 147.785)
		(width 0.19)
		(layer "F.Cu")
		(net 132)
	)
	(segment
		(start 189.841 146.37663)
		(end 189.841 141.515)
		(width 0.19)
		(layer "F.Cu")
		(net 132)
	)
	(segment
		(start 113.330532 75.15)
		(end 113.065532 74.885)
		(width 0.19)
		(layer "F.Cu")
		(net 132)
	)
	(segment
		(start 113.065532 74.515)
		(end 113.180532 74.4)
		(width 0.19)
		(layer "F.Cu")
		(net 132)
	)
	(segment
		(start 192.646 148.1)
		(end 192.621 148.1)
		(width 0.19)
		(layer "F.Cu")
		(net 132)
	)
	(segment
		(start 192.621 148.1)
		(end 192.306 147.785)
		(width 0.19)
		(layer "F.Cu")
		(net 132)
	)
	(segment
		(start 113.065532 74.885)
		(end 113.065532 74.515)
		(width 0.19)
		(layer "F.Cu")
		(net 132)
	)
	(segment
		(start 189.841 141.515)
		(end 189.726 141.4)
		(width 0.19)
		(layer "F.Cu")
		(net 132)
	)
	(segment
		(start 191.24937 147.785)
		(end 189.841 146.37663)
		(width 0.19)
		(layer "F.Cu")
		(net 132)
	)
	(segment
		(start 113.180532 74.4)
		(end 113.2 74.4)
		(width 0.19)
		(layer "F.Cu")
		(net 132)
	)
	(via
		(at 113.2 74.4)
		(size 0.45)
		(drill 0.1)
		(layers "F.Cu" "B.Cu")
		(net 132)
	)
	(via
		(at 189.726 141.4)
		(size 0.45)
		(drill 0.1)
		(layers "F.Cu" "B.Cu")
		(net 132)
	)
	(segment
		(start 114.715 74.777911)
		(end 114.715 76.37663)
		(width 0.19)
		(layer "B.Cu")
		(net 132)
	)
	(segment
		(start 115.415 80.07663)
		(end 115.92337 80.585)
		(width 0.19)
		(layer "B.Cu")
		(net 132)
	)
	(segment
		(start 114.715 76.37663)
		(end 116.015 77.67663)
		(width 0.19)
		(layer "B.Cu")
		(net 132)
	)
	(segment
		(start 116.015 77.67663)
		(end 116.015 78.32337)
		(width 0.19)
		(layer "B.Cu")
		(net 132)
	)
	(segment
		(start 189.841 140.67663)
		(end 189.841 141.285)
		(width 0.19)
		(layer "B.Cu")
		(net 132)
	)
	(segment
		(start 117.82337 81.985)
		(end 118.32337 81.985)
		(width 0.19)
		(layer "B.Cu")
		(net 132)
	)
	(segment
		(start 113.065532 73.396098)
		(end 113.47663 72.985)
		(width 0.19)
		(layer "B.Cu")
		(net 132)
	)
	(segment
		(start 115.92337 80.585)
		(end 116.42337 80.585)
		(width 0.19)
		(layer "B.Cu")
		(net 132)
	)
	(segment
		(start 113.065532 74.265532)
		(end 113.065532 73.396098)
		(width 0.19)
		(layer "B.Cu")
		(net 132)
	)
	(segment
		(start 114.265 74.227911)
		(end 114.265 74.337911)
		(width 0.19)
		(layer "B.Cu")
		(net 132)
	)
	(segment
		(start 152.63 132.35326)
		(end 160.16174 139.885)
		(width 0.19)
		(layer "B.Cu")
		(net 132)
	)
	(segment
		(start 189.841 141.285)
		(end 189.726 141.4)
		(width 0.19)
		(layer "B.Cu")
		(net 132)
	)
	(segment
		(start 114.12337 72.985)
		(end 114.715 73.57663)
		(width 0.19)
		(layer "B.Cu")
		(net 132)
	)
	(segment
		(start 113.47663 72.985)
		(end 114.12337 72.985)
		(width 0.19)
		(layer "B.Cu")
		(net 132)
	)
	(segment
		(start 189.04937 139.885)
		(end 189.841 140.67663)
		(width 0.19)
		(layer "B.Cu")
		(net 132)
	)
	(segment
		(start 114.495 74.007911)
		(end 114.485 74.007911)
		(width 0.19)
		(layer "B.Cu")
		(net 132)
	)
	(segment
		(start 114.485 74.557911)
		(end 114.495 74.557911)
		(width 0.19)
		(layer "B.Cu")
		(net 132)
	)
	(segment
		(start 113.2 74.4)
		(end 113.065532 74.265532)
		(width 0.19)
		(layer "B.Cu")
		(net 132)
	)
	(segment
		(start 116.42337 80.585)
		(end 117.82337 81.985)
		(width 0.19)
		(layer "B.Cu")
		(net 132)
	)
	(segment
		(start 115.415 78.92337)
		(end 115.415 80.07663)
		(width 0.19)
		(layer "B.Cu")
		(net 132)
	)
	(segment
		(start 118.32337 81.985)
		(end 121.42337 85.085)
		(width 0.19)
		(layer "B.Cu")
		(net 132)
	)
	(segment
		(start 152.63 115.29163)
		(end 152.63 132.35326)
		(width 0.19)
		(layer "B.Cu")
		(net 132)
	)
	(segment
		(start 122.42337 85.085)
		(end 152.63 115.29163)
		(width 0.19)
		(layer "B.Cu")
		(net 132)
	)
	(segment
		(start 160.16174 139.885)
		(end 189.04937 139.885)
		(width 0.19)
		(layer "B.Cu")
		(net 132)
	)
	(segment
		(start 116.015 78.32337)
		(end 115.415 78.92337)
		(width 0.19)
		(layer "B.Cu")
		(net 132)
	)
	(segment
		(start 114.715 73.57663)
		(end 114.715 73.787911)
		(width 0.19)
		(layer "B.Cu")
		(net 132)
	)
	(segment
		(start 121.42337 85.085)
		(end 122.42337 85.085)
		(width 0.19)
		(layer "B.Cu")
		(net 132)
	)
	(arc
		(start 114.715 73.787911)
		(mid 114.650563 73.943474)
		(end 114.495 74.007911)
		(width 0.19)
		(layer "B.Cu")
		(net 132)
	)
	(arc
		(start 114.485 74.007911)
		(mid 114.329437 74.072348)
		(end 114.265 74.227911)
		(width 0.19)
		(layer "B.Cu")
		(net 132)
	)
	(arc
		(start 114.495 74.557911)
		(mid 114.650563 74.622348)
		(end 114.715 74.777911)
		(width 0.19)
		(layer "B.Cu")
		(net 132)
	)
	(arc
		(start 114.265 74.337911)
		(mid 114.329437 74.493474)
		(end 114.485 74.557911)
		(width 0.19)
		(layer "B.Cu")
		(net 132)
	)
	(segment
		(start 151.230001 112.25)
		(end 150.15 112.25)
		(width 0.1)
		(layer "F.Cu")
		(net 133)
	)
	(segment
		(start 147.530001 111.949999)
		(end 147.48 112)
		(width 0.1)
		(layer "F.Cu")
		(net 133)
	)
	(segment
		(start 148.5 114.6)
		(end 149.15 113.95)
		(width 0.1)
		(layer "F.Cu")
		(net 133)
	)
	(segment
		(start 150.15 112.25)
		(end 149.849999 111.949999)
		(width 0.1)
		(layer "F.Cu")
		(net 133)
	)
	(segment
		(start 131.5 87.1)
		(end 134.480532 87.1)
		(width 0.1)
		(layer "F.Cu")
		(net 133)
	)
	(segment
		(start 149.15 113.95)
		(end 149.15 113.1)
		(width 0.1)
		(layer "F.Cu")
		(net 133)
	)
	(segment
		(start 143.4 114.6)
		(end 148.5 114.6)
		(width 0.1)
		(layer "F.Cu")
		(net 133)
	)
	(segment
		(start 148.45 111.949999)
		(end 147.530001 111.949999)
		(width 0.1)
		(layer "F.Cu")
		(net 133)
	)
	(segment
		(start 149.849999 111.949999)
		(end 148.45 111.949999)
		(width 0.1)
		(layer "F.Cu")
		(net 133)
	)
	(segment
		(start 134.480532 87.1)
		(end 135.930532 85.65)
		(width 0.1)
		(layer "F.Cu")
		(net 133)
	)
	(via
		(at 148.45 111.949999)
		(size 0.45)
		(drill 0.1)
		(layers "F.Cu" "B.Cu")
		(net 133)
	)
	(via
		(at 143.4 114.6)
		(size 0.45)
		(drill 0.1)
		(layers "F.Cu" "B.Cu")
		(net 133)
	)
	(via
		(at 131.5 87.1)
		(size 0.45)
		(drill 0.1)
		(layers "F.Cu" "B.Cu")
		(net 133)
	)
	(via
		(at 128.7 115.5)
		(size 0.45)
		(drill 0.1)
		(layers "F.Cu" "B.Cu")
		(net 133)
	)
	(via
		(at 149.15 113.1)
		(size 0.45)
		(drill 0.1)
		(layers "F.Cu" "B.Cu")
		(net 133)
	)
	(segment
		(start 149.15 113.1)
		(end 148.75 112.7)
		(width 0.1)
		(layer "B.Cu")
		(net 133)
	)
	(segment
		(start 141.9 116.1)
		(end 130.7 116.1)
		(width 0.1)
		(layer "B.Cu")
		(net 133)
	)
	(segment
		(start 143.4 114.6)
		(end 141.9 116.1)
		(width 0.1)
		(layer "B.Cu")
		(net 133)
	)
	(segment
		(start 130.05 114.9)
		(end 129.3 114.9)
		(width 0.1)
		(layer "B.Cu")
		(net 133)
	)
	(segment
		(start 148.7 112.7)
		(end 148.45 112.45)
		(width 0.1)
		(layer "B.Cu")
		(net 133)
	)
	(segment
		(start 129.3 114.9)
		(end 128.7 115.5)
		(width 0.1)
		(layer "B.Cu")
		(net 133)
	)
	(segment
		(start 130.475 115.875)
		(end 130.475 115.325)
		(width 0.1)
		(layer "B.Cu")
		(net 133)
	)
	(segment
		(start 130.7 116.1)
		(end 130.475 115.875)
		(width 0.1)
		(layer "B.Cu")
		(net 133)
	)
	(segment
		(start 148.45 112.45)
		(end 148.45 111.949999)
		(width 0.1)
		(layer "B.Cu")
		(net 133)
	)
	(segment
		(start 148.75 112.7)
		(end 148.7 112.7)
		(width 0.1)
		(layer "B.Cu")
		(net 133)
	)
	(segment
		(start 130.475 115.325)
		(end 130.05 114.9)
		(width 0.1)
		(layer "B.Cu")
		(net 133)
	)
	(segment
		(start 131.5 87.5)
		(end 131.5 87.1)
		(width 0.1)
		(layer "In5.Cu")
		(net 133)
	)
	(segment
		(start 128.9 90.9)
		(end 131.35 88.45)
		(width 0.1)
		(layer "In5.Cu")
		(net 133)
	)
	(segment
		(start 131.35 88.45)
		(end 131.35 87.65)
		(width 0.1)
		(layer "In5.Cu")
		(net 133)
	)
	(segment
		(start 128.9 115.3)
		(end 128.9 90.9)
		(width 0.1)
		(layer "In5.Cu")
		(net 133)
	)
	(segment
		(start 131.35 87.65)
		(end 131.5 87.5)
		(width 0.1)
		(layer "In5.Cu")
		(net 133)
	)
	(segment
		(start 128.7 115.5)
		(end 128.9 115.3)
		(width 0.1)
		(layer "In5.Cu")
		(net 133)
	)
	(segment
		(start 125.755532 77.175)
		(end 125.880532 77.3)
		(width 0.17)
		(layer "F.Cu")
		(net 134)
	)
	(segment
		(start 125.755532 76.925)
		(end 125.755532 77.175)
		(width 0.17)
		(layer "F.Cu")
		(net 134)
	)
	(segment
		(start 126.030532 76.65)
		(end 125.755532 76.925)
		(width 0.17)
		(layer "F.Cu")
		(net 134)
	)
	(via
		(at 61.9125 104.3)
		(size 0.45)
		(drill 0.1)
		(layers "F.Cu" "B.Cu")
		(net 134)
	)
	(via
		(at 125.880532 77.3)
		(size 0.45)
		(drill 0.1)
		(layers "F.Cu" "B.Cu")
		(net 134)
	)
	(segment
		(start 64.59 105.96)
		(end 63.689999 105.96)
		(width 0.17)
		(layer "B.Cu")
		(net 134)
	)
	(segment
		(start 62.025 104.4125)
		(end 61.9125 104.3)
		(width 0.17)
		(layer "B.Cu")
		(net 134)
	)
	(segment
		(start 63.614999 105.885)
		(end 62.637512 105.885)
		(width 0.17)
		(layer "B.Cu")
		(net 134)
	)
	(segment
		(start 62.637512 105.885)
		(end 62.025 105.272488)
		(width 0.17)
		(layer "B.Cu")
		(net 134)
	)
	(segment
		(start 63.689999 105.96)
		(end 63.614999 105.885)
		(width 0.17)
		(layer "B.Cu")
		(net 134)
	)
	(segment
		(start 62.025 105.272488)
		(end 62.025 104.4125)
		(width 0.17)
		(layer "B.Cu")
		(net 134)
	)
	(segment
		(start 109.6534 74.1875)
		(end 111.1534 72.6875)
		(width 0.125)
		(layer "In2.Cu")
		(net 134)
	)
	(segment
		(start 97.614082 74.1875)
		(end 98.1534 74.1875)
		(width 0.125)
		(layer "In2.Cu")
		(net 134)
	)
	(segment
		(start 84.8534 74.1875)
		(end 89.014082 74.1875)
		(width 0.125)
		(layer "In2.Cu")
		(net 134)
	)
	(segment
		(start 124.7125 75.1534)
		(end 124.7125 75.7534)
		(width 0.125)
		(layer "In2.Cu")
		(net 134)
	)
	(segment
		(start 124.9466 75.9875)
		(end 125.3466 75.9875)
		(width 0.125)
		(layer "In2.Cu")
		(net 134)
	)
	(segment
		(start 94.846582 73.473553)
		(end 94.846582 74.526449)
		(width 0.125)
		(layer "In2.Cu")
		(net 134)
	)
	(segment
		(start 111.1534 72.6875)
		(end 118.4466 72.6875)
		(width 0.125)
		(layer "In2.Cu")
		(net 134)
	)
	(segment
		(start 103.4466 74.0875)
		(end 105.7534 74.0875)
		(width 0.125)
		(layer "In2.Cu")
		(net 134)
	)
	(segment
		(start 99.126617 74.538463)
		(end 99.204398 74.460681)
		(width 0.125)
		(layer "In2.Cu")
		(net 134)
	)
	(segment
		(start 125.3466 75.9875)
		(end 125.693033 76.333933)
		(width 0.125)
		(layer "In2.Cu")
		(net 134)
	)
	(segment
		(start 99.3534 72.9875)
		(end 99.4466 72.9875)
		(width 0.125)
		(layer "In2.Cu")
		(net 134)
	)
	(segment
		(start 97.064082 74.5375)
		(end 97.264082 74.5375)
		(width 0.125)
		(layer "In2.Cu")
		(net 134)
	)
	(segment
		(start 91.564082 74.5375)
		(end 91.764082 74.5375)
		(width 0.125)
		(layer "In2.Cu")
		(net 134)
	)
	(segment
		(start 101.5366 72.9875)
		(end 102.3466 72.9875)
		(width 0.125)
		(layer "In2.Cu")
		(net 134)
	)
	(segment
		(start 92.114082 74.1875)
		(end 92.314082 74.1875)
		(width 0.125)
		(layer "In2.Cu")
		(net 134)
	)
	(segment
		(start 105.7534 74.0875)
		(end 106.2534 73.5875)
		(width 0.125)
		(layer "In2.Cu")
		(net 134)
	)
	(segment
		(start 123.7466 74.1875)
		(end 124.7125 75.1534)
		(width 0.125)
		(layer "In2.Cu")
		(net 134)
	)
	(segment
		(start 98.853434 73.487463)
		(end 98.931217 73.409683)
		(width 0.125)
		(layer "In2.Cu")
		(net 134)
	)
	(segment
		(start 100.9866 71.951164)
		(end 101.0966 71.951164)
		(width 0.125)
		(layer "In2.Cu")
		(net 134)
	)
	(segment
		(start 94.404082 73.141053)
		(end 94.514082 73.141053)
		(width 0.125)
		(layer "In2.Cu")
		(net 134)
	)
	(segment
		(start 98.623626 74.1875)
		(end 98.974589 74.538463)
		(width 0.125)
		(layer "In2.Cu")
		(net 134)
	)
	(segment
		(start 81.3875 79.0534)
		(end 81.3875 77.6534)
		(width 0.125)
		(layer "In2.Cu")
		(net 134)
	)
	(segment
		(start 95.171582 74.526449)
		(end 95.171582 74.52)
		(width 0.125)
		(layer "In2.Cu")
		(net 134)
	)
	(segment
		(start 91.104082 74.1875)
		(end 91.214082 74.1875)
		(width 0.125)
		(layer "In2.Cu")
		(net 134)
	)
	(segment
		(start 93.304082 74.1875)
		(end 93.414082 74.1875)
		(width 0.125)
		(layer "In2.Cu")
		(net 134)
	)
	(segment
		(start 94.071582 75.126447)
		(end 94.071582 73.473553)
		(width 0.125)
		(layer "In2.Cu")
		(net 134)
	)
	(segment
		(start 62.087499 104.125001)
		(end 62.0875 86.0534)
		(width 0.125)
		(layer "In2.Cu")
		(net 134)
	)
	(segment
		(start 80.9534 79.4875)
		(end 81.3875 79.0534)
		(width 0.125)
		(layer "In2.Cu")
		(net 134)
	)
	(segment
		(start 125.693033 77.112501)
		(end 125.880532 77.3)
		(width 0.125)
		(layer "In2.Cu")
		(net 134)
	)
	(segment
		(start 61.9125 104.3)
		(end 62.087499 104.125001)
		(width 0.125)
		(layer "In2.Cu")
		(net 134)
	)
	(segment
		(start 99.88015 72.55395)
		(end 99.9966 72.55395)
		(width 0.125)
		(layer "In2.Cu")
		(net 134)
	)
	(segment
		(start 98.931217 73.409683)
		(end 99.3534 72.9875)
		(width 0.125)
		(layer "In2.Cu")
		(net 134)
	)
	(segment
		(start 68.6534 79.4875)
		(end 80.9534 79.4875)
		(width 0.125)
		(layer "In2.Cu")
		(net 134)
	)
	(segment
		(start 93.854082 75.233947)
		(end 93.964082 75.233947)
		(width 0.125)
		(layer "In2.Cu")
		(net 134)
	)
	(segment
		(start 100.43015 72.9875)
		(end 100.5466 72.9875)
		(width 0.125)
		(layer "In2.Cu")
		(net 134)
	)
	(segment
		(start 62.0875 86.0534)
		(end 68.6534 79.4875)
		(width 0.125)
		(layer "In2.Cu")
		(net 134)
	)
	(segment
		(start 90.771582 75.132346)
		(end 90.771582 74.52)
		(width 0.125)
		(layer "In2.Cu")
		(net 134)
	)
	(segment
		(start 92.754082 75.233947)
		(end 92.864082 75.233947)
		(width 0.125)
		(layer "In2.Cu")
		(net 134)
	)
	(segment
		(start 95.977814 74.551232)
		(end 96.164082 74.551232)
		(width 0.125)
		(layer "In2.Cu")
		(net 134)
	)
	(segment
		(start 119.9466 74.1875)
		(end 123.7466 74.1875)
		(width 0.125)
		(layer "In2.Cu")
		(net 134)
	)
	(segment
		(start 95.504082 74.1875)
		(end 95.614082 74.1875)
		(width 0.125)
		(layer "In2.Cu")
		(net 134)
	)
	(segment
		(start 93.746582 74.52)
		(end 93.746582 75.126447)
		(width 0.125)
		(layer "In2.Cu")
		(net 134)
	)
	(segment
		(start 81.3875 77.6534)
		(end 84.8534 74.1875)
		(width 0.125)
		(layer "In2.Cu")
		(net 134)
	)
	(segment
		(start 90.554082 75.239846)
		(end 90.664082 75.239846)
		(width 0.125)
		(layer "In2.Cu")
		(net 134)
	)
	(segment
		(start 92.971582 75.126447)
		(end 92.971582 74.52)
		(width 0.125)
		(layer "In2.Cu")
		(net 134)
	)
	(segment
		(start 107.4466 73.5875)
		(end 108.0466 74.1875)
		(width 0.125)
		(layer "In2.Cu")
		(net 134)
	)
	(segment
		(start 96.527814 74.1875)
		(end 96.714082 74.1875)
		(width 0.125)
		(layer "In2.Cu")
		(net 134)
	)
	(segment
		(start 108.0466 74.1875)
		(end 109.6534 74.1875)
		(width 0.125)
		(layer "In2.Cu")
		(net 134)
	)
	(segment
		(start 102.3466 72.9875)
		(end 103.4466 74.0875)
		(width 0.125)
		(layer "In2.Cu")
		(net 134)
	)
	(segment
		(start 89.914082 74.1875)
		(end 90.114082 74.1875)
		(width 0.125)
		(layer "In2.Cu")
		(net 134)
	)
	(segment
		(start 125.693033 76.333933)
		(end 125.693033 77.112501)
		(width 0.125)
		(layer "In2.Cu")
		(net 134)
	)
	(segment
		(start 124.7125 75.7534)
		(end 124.9466 75.9875)
		(width 0.125)
		(layer "In2.Cu")
		(net 134)
	)
	(segment
		(start 118.4466 72.6875)
		(end 119.9466 74.1875)
		(width 0.125)
		(layer "In2.Cu")
		(net 134)
	)
	(segment
		(start 94.954082 74.633949)
		(end 95.064082 74.633949)
		(width 0.125)
		(layer "In2.Cu")
		(net 134)
	)
	(segment
		(start 92.646582 74.52)
		(end 92.646582 75.126447)
		(width 0.125)
		(layer "In2.Cu")
		(net 134)
	)
	(segment
		(start 101.4291 72.283664)
		(end 101.4291 72.88)
		(width 0.125)
		(layer "In2.Cu")
		(net 134)
	)
	(segment
		(start 106.2534 73.5875)
		(end 107.4466 73.5875)
		(width 0.125)
		(layer "In2.Cu")
		(net 134)
	)
	(segment
		(start 99.204398 74.308653)
		(end 98.853434 73.957689)
		(width 0.125)
		(layer "In2.Cu")
		(net 134)
	)
	(segment
		(start 90.446582 74.52)
		(end 90.446582 75.132346)
		(width 0.125)
		(layer "In2.Cu")
		(net 134)
	)
	(segment
		(start 100.6541 72.88)
		(end 100.6541 72.283664)
		(width 0.125)
		(layer "In2.Cu")
		(net 134)
	)
	(segment
		(start 89.364082 74.5375)
		(end 89.564082 74.5375)
		(width 0.125)
		(layer "In2.Cu")
		(net 134)
	)
	(arc
		(start 90.114082 74.1875)
		(mid 90.349195 74.284887)
		(end 90.446582 74.52)
		(width 0.125)
		(layer "In2.Cu")
		(net 134)
	)
	(arc
		(start 90.664082 75.239846)
		(mid 90.740096 75.20836)
		(end 90.771582 75.132346)
		(width 0.125)
		(layer "In2.Cu")
		(net 134)
	)
	(arc
		(start 97.264082 74.5375)
		(mid 97.308276 74.519194)
		(end 97.326582 74.475)
		(width 0.125)
		(layer "In2.Cu")
		(net 134)
	)
	(arc
		(start 100.6541 72.283664)
		(mid 100.751487 72.048551)
		(end 100.9866 71.951164)
		(width 0.125)
		(layer "In2.Cu")
		(net 134)
	)
	(arc
		(start 89.301582 74.475)
		(mid 89.319888 74.519194)
		(end 89.364082 74.5375)
		(width 0.125)
		(layer "In2.Cu")
		(net 134)
	)
	(arc
		(start 100.5466 72.9875)
		(mid 100.622614 72.956014)
		(end 100.6541 72.88)
		(width 0.125)
		(layer "In2.Cu")
		(net 134)
	)
	(arc
		(start 99.4466 72.9875)
		(mid 99.520334 72.956959)
		(end 99.550875 72.883225)
		(width 0.125)
		(layer "In2.Cu")
		(net 134)
	)
	(arc
		(start 91.501582 74.475)
		(mid 91.519888 74.519194)
		(end 91.564082 74.5375)
		(width 0.125)
		(layer "In2.Cu")
		(net 134)
	)
	(arc
		(start 97.326582 74.475)
		(mid 97.410789 74.271707)
		(end 97.614082 74.1875)
		(width 0.125)
		(layer "In2.Cu")
		(net 134)
	)
	(arc
		(start 98.853434 73.957689)
		(mid 98.756047 73.722576)
		(end 98.853434 73.487463)
		(width 0.125)
		(layer "In2.Cu")
		(net 134)
	)
	(arc
		(start 89.626582 74.475)
		(mid 89.710789 74.271707)
		(end 89.914082 74.1875)
		(width 0.125)
		(layer "In2.Cu")
		(net 134)
	)
	(arc
		(start 91.214082 74.1875)
		(mid 91.417375 74.271707)
		(end 91.501582 74.475)
		(width 0.125)
		(layer "In2.Cu")
		(net 134)
	)
	(arc
		(start 91.826582 74.475)
		(mid 91.910789 74.271707)
		(end 92.114082 74.1875)
		(width 0.125)
		(layer "In2.Cu")
		(net 134)
	)
	(arc
		(start 93.414082 74.1875)
		(mid 93.649195 74.284887)
		(end 93.746582 74.52)
		(width 0.125)
		(layer "In2.Cu")
		(net 134)
	)
	(arc
		(start 95.171582 74.52)
		(mid 95.268969 74.284887)
		(end 95.504082 74.1875)
		(width 0.125)
		(layer "In2.Cu")
		(net 134)
	)
	(arc
		(start 96.164082 74.551232)
		(mid 96.213131 74.530915)
		(end 96.233448 74.481866)
		(width 0.125)
		(layer "In2.Cu")
		(net 134)
	)
	(arc
		(start 92.314082 74.1875)
		(mid 92.549195 74.284887)
		(end 92.646582 74.52)
		(width 0.125)
		(layer "In2.Cu")
		(net 134)
	)
	(arc
		(start 98.974589 74.538463)
		(mid 99.050603 74.569949)
		(end 99.126617 74.538463)
		(width 0.125)
		(layer "In2.Cu")
		(net 134)
	)
	(arc
		(start 101.0966 71.951164)
		(mid 101.331713 72.048551)
		(end 101.4291 72.283664)
		(width 0.125)
		(layer "In2.Cu")
		(net 134)
	)
	(arc
		(start 89.564082 74.5375)
		(mid 89.608276 74.519194)
		(end 89.626582 74.475)
		(width 0.125)
		(layer "In2.Cu")
		(net 134)
	)
	(arc
		(start 96.233448 74.481866)
		(mid 96.319666 74.273718)
		(end 96.527814 74.1875)
		(width 0.125)
		(layer "In2.Cu")
		(net 134)
	)
	(arc
		(start 99.9966 72.55395)
		(mid 100.229433 72.650392)
		(end 100.325875 72.883225)
		(width 0.125)
		(layer "In2.Cu")
		(net 134)
	)
	(arc
		(start 98.1534 74.1875)
		(mid 98.388513 74.090113)
		(end 98.623626 74.1875)
		(width 0.125)
		(layer "In2.Cu")
		(net 134)
	)
	(arc
		(start 89.014082 74.1875)
		(mid 89.217375 74.271707)
		(end 89.301582 74.475)
		(width 0.125)
		(layer "In2.Cu")
		(net 134)
	)
	(arc
		(start 93.746582 75.126447)
		(mid 93.778068 75.202461)
		(end 93.854082 75.233947)
		(width 0.125)
		(layer "In2.Cu")
		(net 134)
	)
	(arc
		(start 95.614082 74.1875)
		(mid 95.82223 74.273718)
		(end 95.908448 74.481866)
		(width 0.125)
		(layer "In2.Cu")
		(net 134)
	)
	(arc
		(start 101.4291 72.88)
		(mid 101.460586 72.956014)
		(end 101.5366 72.9875)
		(width 0.125)
		(layer "In2.Cu")
		(net 134)
	)
	(arc
		(start 99.550875 72.883225)
		(mid 99.647317 72.650392)
		(end 99.88015 72.55395)
		(width 0.125)
		(layer "In2.Cu")
		(net 134)
	)
	(arc
		(start 94.071582 73.473553)
		(mid 94.168969 73.23844)
		(end 94.404082 73.141053)
		(width 0.125)
		(layer "In2.Cu")
		(net 134)
	)
	(arc
		(start 96.714082 74.1875)
		(mid 96.917375 74.271707)
		(end 97.001582 74.475)
		(width 0.125)
		(layer "In2.Cu")
		(net 134)
	)
	(arc
		(start 90.771582 74.52)
		(mid 90.868969 74.284887)
		(end 91.104082 74.1875)
		(width 0.125)
		(layer "In2.Cu")
		(net 134)
	)
	(arc
		(start 94.846582 74.526449)
		(mid 94.878068 74.602463)
		(end 94.954082 74.633949)
		(width 0.125)
		(layer "In2.Cu")
		(net 134)
	)
	(arc
		(start 100.325875 72.883225)
		(mid 100.356416 72.956959)
		(end 100.43015 72.9875)
		(width 0.125)
		(layer "In2.Cu")
		(net 134)
	)
	(arc
		(start 93.964082 75.233947)
		(mid 94.040096 75.202461)
		(end 94.071582 75.126447)
		(width 0.125)
		(layer "In2.Cu")
		(net 134)
	)
	(arc
		(start 90.446582 75.132346)
		(mid 90.478068 75.20836)
		(end 90.554082 75.239846)
		(width 0.125)
		(layer "In2.Cu")
		(net 134)
	)
	(arc
		(start 94.514082 73.141053)
		(mid 94.749195 73.23844)
		(end 94.846582 73.473553)
		(width 0.125)
		(layer "In2.Cu")
		(net 134)
	)
	(arc
		(start 92.971582 74.52)
		(mid 93.068969 74.284887)
		(end 93.304082 74.1875)
		(width 0.125)
		(layer "In2.Cu")
		(net 134)
	)
	(arc
		(start 99.204398 74.460681)
		(mid 99.235884 74.384667)
		(end 99.204398 74.308653)
		(width 0.125)
		(layer "In2.Cu")
		(net 134)
	)
	(arc
		(start 97.001582 74.475)
		(mid 97.019888 74.519194)
		(end 97.064082 74.5375)
		(width 0.125)
		(layer "In2.Cu")
		(net 134)
	)
	(arc
		(start 95.064082 74.633949)
		(mid 95.140096 74.602463)
		(end 95.171582 74.526449)
		(width 0.125)
		(layer "In2.Cu")
		(net 134)
	)
	(arc
		(start 95.908448 74.481866)
		(mid 95.928765 74.530915)
		(end 95.977814 74.551232)
		(width 0.125)
		(layer "In2.Cu")
		(net 134)
	)
	(arc
		(start 92.864082 75.233947)
		(mid 92.940096 75.202461)
		(end 92.971582 75.126447)
		(width 0.125)
		(layer "In2.Cu")
		(net 134)
	)
	(arc
		(start 92.646582 75.126447)
		(mid 92.678068 75.202461)
		(end 92.754082 75.233947)
		(width 0.125)
		(layer "In2.Cu")
		(net 134)
	)
	(arc
		(start 91.764082 74.5375)
		(mid 91.808276 74.519194)
		(end 91.826582 74.475)
		(width 0.125)
		(layer "In2.Cu")
		(net 134)
	)
	(via
		(at 127.130532 72.15)
		(size 0.45)
		(drill 0.1)
		(layers "F.Cu" "B.Cu")
		(net 135)
	)
	(via
		(at 205.6125 60.1)
		(size 0.45)
		(drill 0.1)
		(layers "F.Cu" "B.Cu")
		(net 135)
	)
	(segment
		(start 205.725 59.707)
		(end 205.725 59.9875)
		(width 0.17)
		(layer "B.Cu")
		(net 135)
	)
	(segment
		(start 205.658 59.290001)
		(end 205.732 59.364001)
		(width 0.17)
		(layer "B.Cu")
		(net 135)
	)
	(segment
		(start 205.732 59.364001)
		(end 205.732 59.7)
		(width 0.17)
		(layer "B.Cu")
		(net 135)
	)
	(segment
		(start 205.725 59.9875)
		(end 205.6125 60.1)
		(width 0.17)
		(layer "B.Cu")
		(net 135)
	)
	(segment
		(start 205.732 59.7)
		(end 205.725 59.707)
		(width 0.17)
		(layer "B.Cu")
		(net 135)
	)
	(segment
		(start 205.658 58.39)
		(end 205.658 59.290001)
		(width 0.17)
		(layer "B.Cu")
		(net 135)
	)
	(segment
		(start 156.364864 73.0125)
		(end 156.474864 73.0125)
		(width 0.125)
		(layer "In2.Cu")
		(net 135)
	)
	(segment
		(start 152.182364 72.7875)
		(end 152.182364 73.0125)
		(width 0.125)
		(layer "In2.Cu")
		(net 135)
	)
	(segment
		(start 155.157364 73.581624)
		(end 155.157364 73.0125)
		(width 0.125)
		(layer "In2.Cu")
		(net 135)
	)
	(segment
		(start 153.282364 72.518393)
		(end 153.282364 72.68)
		(width 0.125)
		(layer "In2.Cu")
		(net 135)
	)
	(segment
		(start 151.082364 73.12)
		(end 151.082364 73.581603)
		(width 0.125)
		(layer "In2.Cu")
		(net 135)
	)
	(segment
		(start 168.005169 68.573511)
		(end 177.278679 59.300001)
		(width 0.125)
		(layer "In2.Cu")
		(net 135)
	)
	(segment
		(start 205.340901 59.300001)
		(end 205.787499 59.746599)
		(width 0.125)
		(layer "In2.Cu")
		(net 135)
	)
	(segment
		(start 151.857364 72.7875)
		(end 151.857364 72.518393)
		(width 0.125)
		(layer "In2.Cu")
		(net 135)
	)
	(segment
		(start 152.514864 73.914103)
		(end 152.624864 73.914103)
		(width 0.125)
		(layer "In2.Cu")
		(net 135)
	)
	(segment
		(start 205.787499 59.746599)
		(end 205.787499 59.925001)
		(width 0.125)
		(layer "In2.Cu")
		(net 135)
	)
	(segment
		(start 155.157364 72.7875)
		(end 155.157364 72.518393)
		(width 0.125)
		(layer "In2.Cu")
		(net 135)
	)
	(segment
		(start 155.482364 72.7875)
		(end 155.482364 73.12)
		(width 0.125)
		(layer "In2.Cu")
		(net 135)
	)
	(segment
		(start 154.382364 72.518393)
		(end 154.382364 72.68)
		(width 0.125)
		(layer "In2.Cu")
		(net 135)
	)
	(segment
		(start 153.614864 73.0125)
		(end 153.724864 73.0125)
		(width 0.125)
		(layer "In2.Cu")
		(net 135)
	)
	(segment
		(start 154.382364 73.0125)
		(end 154.382364 73.581624)
		(width 0.125)
		(layer "In2.Cu")
		(net 135)
	)
	(segment
		(start 153.064864 72.410893)
		(end 153.174864 72.410893)
		(width 0.125)
		(layer "In2.Cu")
		(net 135)
	)
	(segment
		(start 156.257364 73.581603)
		(end 156.257364 73.12)
		(width 0.125)
		(layer "In2.Cu")
		(net 135)
	)
	(segment
		(start 163.56618 73.0125)
		(end 168.005169 68.573511)
		(width 0.125)
		(layer "In2.Cu")
		(net 135)
	)
	(segment
		(start 151.414864 73.914103)
		(end 151.524864 73.914103)
		(width 0.125)
		(layer "In2.Cu")
		(net 135)
	)
	(segment
		(start 127.130532 72.15)
		(end 127.468031 72.487499)
		(width 0.125)
		(layer "In2.Cu")
		(net 135)
	)
	(segment
		(start 151.857364 73.12)
		(end 151.857364 72.7875)
		(width 0.125)
		(layer "In2.Cu")
		(net 135)
	)
	(segment
		(start 127.468031 72.677131)
		(end 127.8034 73.0125)
		(width 0.125)
		(layer "In2.Cu")
		(net 135)
	)
	(segment
		(start 151.964864 72.410893)
		(end 152.074864 72.410893)
		(width 0.125)
		(layer "In2.Cu")
		(net 135)
	)
	(segment
		(start 155.814864 73.914103)
		(end 155.924864 73.914103)
		(width 0.125)
		(layer "In2.Cu")
		(net 135)
	)
	(segment
		(start 155.157364 73.0125)
		(end 155.157364 72.7875)
		(width 0.125)
		(layer "In2.Cu")
		(net 135)
	)
	(segment
		(start 127.468031 72.487499)
		(end 127.468031 72.677131)
		(width 0.125)
		(layer "In2.Cu")
		(net 135)
	)
	(segment
		(start 156.474864 73.0125)
		(end 163.56618 73.0125)
		(width 0.125)
		(layer "In2.Cu")
		(net 135)
	)
	(segment
		(start 154.057364 72.68)
		(end 154.057364 72.518393)
		(width 0.125)
		(layer "In2.Cu")
		(net 135)
	)
	(segment
		(start 155.264864 72.410893)
		(end 155.374864 72.410893)
		(width 0.125)
		(layer "In2.Cu")
		(net 135)
	)
	(segment
		(start 155.482364 72.518393)
		(end 155.482364 72.7875)
		(width 0.125)
		(layer "In2.Cu")
		(net 135)
	)
	(segment
		(start 155.482364 73.12)
		(end 155.482364 73.581603)
		(width 0.125)
		(layer "In2.Cu")
		(net 135)
	)
	(segment
		(start 127.8034 73.0125)
		(end 150.974864 73.0125)
		(width 0.125)
		(layer "In2.Cu")
		(net 135)
	)
	(segment
		(start 152.957364 73.581603)
		(end 152.957364 73.0125)
		(width 0.125)
		(layer "In2.Cu")
		(net 135)
	)
	(segment
		(start 205.787499 59.925001)
		(end 205.6125 60.1)
		(width 0.125)
		(layer "In2.Cu")
		(net 135)
	)
	(segment
		(start 152.182364 72.518393)
		(end 152.182364 72.7875)
		(width 0.125)
		(layer "In2.Cu")
		(net 135)
	)
	(segment
		(start 152.182364 73.0125)
		(end 152.182364 73.581603)
		(width 0.125)
		(layer "In2.Cu")
		(net 135)
	)
	(segment
		(start 152.957364 73.0125)
		(end 152.957364 72.68)
		(width 0.125)
		(layer "In2.Cu")
		(net 135)
	)
	(segment
		(start 154.714864 73.914124)
		(end 154.824864 73.914124)
		(width 0.125)
		(layer "In2.Cu")
		(net 135)
	)
	(segment
		(start 154.382364 72.68)
		(end 154.382364 73.0125)
		(width 0.125)
		(layer "In2.Cu")
		(net 135)
	)
	(segment
		(start 151.857364 73.581603)
		(end 151.857364 73.12)
		(width 0.125)
		(layer "In2.Cu")
		(net 135)
	)
	(segment
		(start 152.957364 72.68)
		(end 152.957364 72.518393)
		(width 0.125)
		(layer "In2.Cu")
		(net 135)
	)
	(segment
		(start 154.164864 72.410893)
		(end 154.274864 72.410893)
		(width 0.125)
		(layer "In2.Cu")
		(net 135)
	)
	(segment
		(start 177.278679 59.300001)
		(end 205.340901 59.300001)
		(width 0.125)
		(layer "In2.Cu")
		(net 135)
	)
	(arc
		(start 151.857364 72.518393)
		(mid 151.88885 72.442379)
		(end 151.964864 72.410893)
		(width 0.125)
		(layer "In2.Cu")
		(net 135)
	)
	(arc
		(start 154.274864 72.410893)
		(mid 154.350878 72.442379)
		(end 154.382364 72.518393)
		(width 0.125)
		(layer "In2.Cu")
		(net 135)
	)
	(arc
		(start 152.182364 73.581603)
		(mid 152.279751 73.816716)
		(end 152.514864 73.914103)
		(width 0.125)
		(layer "In2.Cu")
		(net 135)
	)
	(arc
		(start 150.974864 73.0125)
		(mid 151.050878 73.043986)
		(end 151.082364 73.12)
		(width 0.125)
		(layer "In2.Cu")
		(net 135)
	)
	(arc
		(start 152.074864 72.410893)
		(mid 152.150878 72.442379)
		(end 152.182364 72.518393)
		(width 0.125)
		(layer "In2.Cu")
		(net 135)
	)
	(arc
		(start 154.824864 73.914124)
		(mid 155.059977 73.816737)
		(end 155.157364 73.581624)
		(width 0.125)
		(layer "In2.Cu")
		(net 135)
	)
	(arc
		(start 154.382364 73.581624)
		(mid 154.479751 73.816737)
		(end 154.714864 73.914124)
		(width 0.125)
		(layer "In2.Cu")
		(net 135)
	)
	(arc
		(start 156.257364 73.12)
		(mid 156.28885 73.043986)
		(end 156.364864 73.0125)
		(width 0.125)
		(layer "In2.Cu")
		(net 135)
	)
	(arc
		(start 152.957364 72.518393)
		(mid 152.98885 72.442379)
		(end 153.064864 72.410893)
		(width 0.125)
		(layer "In2.Cu")
		(net 135)
	)
	(arc
		(start 155.482364 73.581603)
		(mid 155.579751 73.816716)
		(end 155.814864 73.914103)
		(width 0.125)
		(layer "In2.Cu")
		(net 135)
	)
	(arc
		(start 154.057364 72.518393)
		(mid 154.08885 72.442379)
		(end 154.164864 72.410893)
		(width 0.125)
		(layer "In2.Cu")
		(net 135)
	)
	(arc
		(start 151.082364 73.581603)
		(mid 151.179751 73.816716)
		(end 151.414864 73.914103)
		(width 0.125)
		(layer "In2.Cu")
		(net 135)
	)
	(arc
		(start 153.724864 73.0125)
		(mid 153.959977 72.915113)
		(end 154.057364 72.68)
		(width 0.125)
		(layer "In2.Cu")
		(net 135)
	)
	(arc
		(start 155.374864 72.410893)
		(mid 155.450878 72.442379)
		(end 155.482364 72.518393)
		(width 0.125)
		(layer "In2.Cu")
		(net 135)
	)
	(arc
		(start 155.157364 72.518393)
		(mid 155.18885 72.442379)
		(end 155.264864 72.410893)
		(width 0.125)
		(layer "In2.Cu")
		(net 135)
	)
	(arc
		(start 151.524864 73.914103)
		(mid 151.759977 73.816716)
		(end 151.857364 73.581603)
		(width 0.125)
		(layer "In2.Cu")
		(net 135)
	)
	(arc
		(start 155.924864 73.914103)
		(mid 156.159977 73.816716)
		(end 156.257364 73.581603)
		(width 0.125)
		(layer "In2.Cu")
		(net 135)
	)
	(arc
		(start 153.282364 72.68)
		(mid 153.379751 72.915113)
		(end 153.614864 73.0125)
		(width 0.125)
		(layer "In2.Cu")
		(net 135)
	)
	(arc
		(start 153.174864 72.410893)
		(mid 153.250878 72.442379)
		(end 153.282364 72.518393)
		(width 0.125)
		(layer "In2.Cu")
		(net 135)
	)
	(arc
		(start 152.624864 73.914103)
		(mid 152.859977 73.816716)
		(end 152.957364 73.581603)
		(width 0.125)
		(layer "In2.Cu")
		(net 135)
	)
	(segment
		(start 126.980532 77.6)
		(end 126.980532 78)
		(width 0.17)
		(layer "F.Cu")
		(net 136)
	)
	(segment
		(start 126.980532 78)
		(end 127.130532 78.15)
		(width 0.17)
		(layer "F.Cu")
		(net 136)
	)
	(via
		(at 126.980532 77.6)
		(size 0.45)
		(drill 0.1)
		(layers "F.Cu" "B.Cu")
		(net 136)
	)
	(via
		(at 63.425 101.325)
		(size 0.45)
		(drill 0.1)
		(layers "F.Cu" "B.Cu")
		(net 136)
	)
	(segment
		(start 64.065 102.036)
		(end 63.461 102.036)
		(width 0.17)
		(layer "B.Cu")
		(net 136)
	)
	(segment
		(start 63.3 101.45)
		(end 63.425 101.325)
		(width 0.17)
		(layer "B.Cu")
		(net 136)
	)
	(segment
		(start 63.461 102.036)
		(end 63.3 101.875)
		(width 0.17)
		(layer "B.Cu")
		(net 136)
	)
	(segment
		(start 64.59 101.961)
		(end 64.14 101.961)
		(width 0.17)
		(layer "B.Cu")
		(net 136)
	)
	(segment
		(start 63.3 101.875)
		(end 63.3 101.45)
		(width 0.17)
		(layer "B.Cu")
		(net 136)
	)
	(segment
		(start 64.14 101.961)
		(end 64.065 102.036)
		(width 0.17)
		(layer "B.Cu")
		(net 136)
	)
	(segment
		(start 97.7875 76.1966)
		(end 98.0534 76.4625)
		(width 0.125)
		(layer "In2.Cu")
		(net 136)
	)
	(segment
		(start 82.9125 78.2466)
		(end 83.30955 77.84955)
		(width 0.125)
		(layer "In2.Cu")
		(net 136)
	)
	(segment
		(start 108.0125 75.7466)
		(end 108.4466 75.3125)
		(width 0.125)
		(layer "In2.Cu")
		(net 136)
	)
	(segment
		(start 117.17285 75.287163)
		(end 117.28285 75.287163)
		(width 0.125)
		(layer "In2.Cu")
		(net 136)
	)
	(segment
		(start 114.42285 77.087837)
		(end 114.53285 77.087837)
		(width 0.125)
		(layer "In2.Cu")
		(net 136)
	)
	(segment
		(start 107.3466 76.8125)
		(end 108.0125 76.1466)
		(width 0.125)
		(layer "In2.Cu")
		(net 136)
	)
	(segment
		(start 113.54035 75.194684)
		(end 113.54035 75.78)
		(width 0.125)
		(layer "In2.Cu")
		(net 136)
	)
	(segment
		(start 117.94035 76.22)
		(end 117.94035 76.755317)
		(width 0.125)
		(layer "In2.Cu")
		(net 136)
	)
	(segment
		(start 100.9366 76.1125)
		(end 101.0466 76.1125)
		(width 0.125)
		(layer "In2.Cu")
		(net 136)
	)
	(segment
		(start 95.9125 76.1466)
		(end 95.9125 75.8466)
		(width 0.125)
		(layer "In2.Cu")
		(net 136)
	)
	(segment
		(start 114.963499 75.691201)
		(end 115.092201 75.691201)
		(width 0.125)
		(layer "In2.Cu")
		(net 136)
	)
	(segment
		(start 108.0125 76.1466)
		(end 108.0125 75.7466)
		(width 0.125)
		(layer "In2.Cu")
		(net 136)
	)
	(segment
		(start 101.4866 75.433764)
		(end 101.5966 75.433764)
		(width 0.125)
		(layer "In2.Cu")
		(net 136)
	)
	(segment
		(start 82.4466 80.9125)
		(end 82.9125 80.4466)
		(width 0.125)
		(layer "In2.Cu")
		(net 136)
	)
	(segment
		(start 115.96535 76.210649)
		(end 115.96535 75.694673)
		(width 0.125)
		(layer "In2.Cu")
		(net 136)
	)
	(segment
		(start 110.79035 75.81865)
		(end 110.79035 76.70874)
		(width 0.125)
		(layer "In2.Cu")
		(net 136)
	)
	(segment
		(start 106.3534 76.8125)
		(end 107.3466 76.8125)
		(width 0.125)
		(layer "In2.Cu")
		(net 136)
	)
	(segment
		(start 83.30955 77.379324)
		(end 83.070028 77.139802)
		(width 0.125)
		(layer "In2.Cu")
		(net 136)
	)
	(segment
		(start 100.3866 75.083758)
		(end 100.4966 75.083758)
		(width 0.125)
		(layer "In2.Cu")
		(net 136)
	)
	(segment
		(start 112.44035 75.391253)
		(end 112.44035 76.175)
		(width 0.125)
		(layer "In2.Cu")
		(net 136)
	)
	(segment
		(start 110.5093 75.7498)
		(end 110.7215 75.7498)
		(width 0.125)
		(layer "In2.Cu")
		(net 136)
	)
	(segment
		(start 115.19035 75.78935)
		(end 115.19035 76.210649)
		(width 0.125)
		(layer "In2.Cu")
		(net 136)
	)
	(segment
		(start 100.6041 75.191258)
		(end 100.6041 75.78)
		(width 0.125)
		(layer "In2.Cu")
		(net 136)
	)
	(segment
		(start 84.865184 76.293916)
		(end 85.1466 76.0125)
		(width 0.125)
		(layer "In2.Cu")
		(net 136)
	)
	(segment
		(start 93.6534 76.0125)
		(end 94.3534 76.7125)
		(width 0.125)
		(layer "In2.Cu")
		(net 136)
	)
	(segment
		(start 114.86535 76.755337)
		(end 114.86535 75.78935)
		(width 0.125)
		(layer "In2.Cu")
		(net 136)
	)
	(segment
		(start 100.2791 75.78)
		(end 100.2791 75.191258)
		(width 0.125)
		(layer "In2.Cu")
		(net 136)
	)
	(segment
		(start 116.29035 75.694673)
		(end 116.29035 75.78)
		(width 0.125)
		(layer "In2.Cu")
		(net 136)
	)
	(segment
		(start 97.3534 75.3125)
		(end 97.7875 75.7466)
		(width 0.125)
		(layer "In2.Cu")
		(net 136)
	)
	(segment
		(start 113.87285 76.1125)
		(end 113.98285 76.1125)
		(width 0.125)
		(layer "In2.Cu")
		(net 136)
	)
	(segment
		(start 103.049894 76.1125)
		(end 105.6534 76.1125)
		(width 0.125)
		(layer "In2.Cu")
		(net 136)
	)
	(segment
		(start 105.6534 76.1125)
		(end 106.3534 76.8125)
		(width 0.125)
		(layer "In2.Cu")
		(net 136)
	)
	(segment
		(start 126.793033 78.066067)
		(end 126.793033 77.787499)
		(width 0.125)
		(layer "In2.Cu")
		(net 136)
	)
	(segment
		(start 63.452501 100.049698)
		(end 63.622555 100.049698)
		(width 0.125)
		(layer "In2.Cu")
		(net 136)
	)
	(segment
		(start 108.4466 75.3125)
		(end 109.2534 75.3125)
		(width 0.125)
		(layer "In2.Cu")
		(net 136)
	)
	(segment
		(start 63.312501 99.559698)
		(end 63.312501 86.546599)
		(width 0.125)
		(layer "In2.Cu")
		(net 136)
	)
	(segment
		(start 98.0534 76.4625)
		(end 99.5966 76.4625)
		(width 0.125)
		(layer "In2.Cu")
		(net 136)
	)
	(segment
		(start 113.32285 75.087184)
		(end 113.43285 75.087184)
		(width 0.125)
		(layer "In2.Cu")
		(net 136)
	)
	(segment
		(start 99.5966 76.4625)
		(end 99.9466 76.1125)
		(width 0.125)
		(layer "In2.Cu")
		(net 136)
	)
	(segment
		(start 113.21535 76.175)
		(end 113.21535 75.194684)
		(width 0.125)
		(layer "In2.Cu")
		(net 136)
	)
	(segment
		(start 118.82285 76.1125)
		(end 122.2534 76.1125)
		(width 0.125)
		(layer "In2.Cu")
		(net 136)
	)
	(segment
		(start 124.9534 78.8125)
		(end 126.0466 78.8125)
		(width 0.125)
		(layer "In2.Cu")
		(net 136)
	)
	(segment
		(start 63.425 101.075)
		(end 63.312501 100.962501)
		(width 0.125)
		(layer "In2.Cu")
		(net 136)
	)
	(segment
		(start 111.12285 77.04124)
		(end 111.23285 77.04124)
		(width 0.125)
		(layer "In2.Cu")
		(net 136)
	)
	(segment
		(start 122.2534 76.1125)
		(end 124.9534 78.8125)
		(width 0.125)
		(layer "In2.Cu")
		(net 136)
	)
	(segment
		(start 112.22285 75.283753)
		(end 112.33285 75.283753)
		(width 0.125)
		(layer "In2.Cu")
		(net 136)
	)
	(segment
		(start 63.762555 99.909698)
		(end 63.762555 99.839698)
		(width 0.125)
		(layer "In2.Cu")
		(net 136)
	)
	(segment
		(start 102.0366 76.1125)
		(end 102.1466 76.1125)
		(width 0.125)
		(layer "In2.Cu")
		(net 136)
	)
	(segment
		(start 84.009588 77.149515)
		(end 84.087367 77.071733)
		(width 0.125)
		(layer "In2.Cu")
		(net 136)
	)
	(segment
		(start 126.0466 78.8125)
		(end 126.793033 78.066067)
		(width 0.125)
		(layer "In2.Cu")
		(net 136)
	)
	(segment
		(start 94.3534 76.7125)
		(end 95.3466 76.7125)
		(width 0.125)
		(layer "In2.Cu")
		(net 136)
	)
	(segment
		(start 85.1466 76.0125)
		(end 93.6534 76.0125)
		(width 0.125)
		(layer "In2.Cu")
		(net 136)
	)
	(segment
		(start 117.06535 75.78)
		(end 117.06535 75.394663)
		(width 0.125)
		(layer "In2.Cu")
		(net 136)
	)
	(segment
		(start 84.077646 76.132165)
		(end 84.317179 76.371698)
		(width 0.125)
		(layer "In2.Cu")
		(net 136)
	)
	(segment
		(start 110.0534 76.1125)
		(end 110.1466 76.1125)
		(width 0.125)
		(layer "In2.Cu")
		(net 136)
	)
	(segment
		(start 84.087367 76.601507)
		(end 83.847835 76.361975)
		(width 0.125)
		(layer "In2.Cu")
		(net 136)
	)
	(segment
		(start 118.71535 76.755317)
		(end 118.71535 76.22)
		(width 0.125)
		(layer "In2.Cu")
		(net 136)
	)
	(segment
		(start 96.4466 75.3125)
		(end 97.3534 75.3125)
		(width 0.125)
		(layer "In2.Cu")
		(net 136)
	)
	(segment
		(start 82.9125 80.4466)
		(end 82.9125 78.2466)
		(width 0.125)
		(layer "In2.Cu")
		(net 136)
	)
	(segment
		(start 111.67285 76.1125)
		(end 111.78285 76.1125)
		(width 0.125)
		(layer "In2.Cu")
		(net 136)
	)
	(segment
		(start 118.27285 77.087817)
		(end 118.38285 77.087817)
		(width 0.125)
		(layer "In2.Cu")
		(net 136)
	)
	(segment
		(start 111.56535 76.70874)
		(end 111.56535 76.22)
		(width 0.125)
		(layer "In2.Cu")
		(net 136)
	)
	(segment
		(start 95.3466 76.7125)
		(end 95.9125 76.1466)
		(width 0.125)
		(layer "In2.Cu")
		(net 136)
	)
	(segment
		(start 101.7041 75.541264)
		(end 101.7041 75.78)
		(width 0.125)
		(layer "In2.Cu")
		(net 136)
	)
	(segment
		(start 102.499894 75.759206)
		(end 102.6966 75.759206)
		(width 0.125)
		(layer "In2.Cu")
		(net 136)
	)
	(segment
		(start 83.070028 76.987774)
		(end 83.147811 76.909992)
		(width 0.125)
		(layer "In2.Cu")
		(net 136)
	)
	(segment
		(start 109.2534 75.3125)
		(end 110.0534 76.1125)
		(width 0.125)
		(layer "In2.Cu")
		(net 136)
	)
	(segment
		(start 84.787405 76.371698)
		(end 84.865184 76.293916)
		(width 0.125)
		(layer "In2.Cu")
		(net 136)
	)
	(segment
		(start 63.622555 99.699698)
		(end 63.452501 99.699698)
		(width 0.125)
		(layer "In2.Cu")
		(net 136)
	)
	(segment
		(start 117.72285 76.1125)
		(end 117.83285 76.1125)
		(width 0.125)
		(layer "In2.Cu")
		(net 136)
	)
	(segment
		(start 112.11535 75.78)
		(end 112.11535 75.391253)
		(width 0.125)
		(layer "In2.Cu")
		(net 136)
	)
	(segment
		(start 83.847835 76.209947)
		(end 83.925618 76.132165)
		(width 0.125)
		(layer "In2.Cu")
		(net 136)
	)
	(segment
		(start 68.9466 80.9125)
		(end 82.4466 80.9125)
		(width 0.125)
		(layer "In2.Cu")
		(net 136)
	)
	(segment
		(start 63.312501 100.962501)
		(end 63.312501 100.189698)
		(width 0.125)
		(layer "In2.Cu")
		(net 136)
	)
	(segment
		(start 112.72785 76.4625)
		(end 112.92785 76.4625)
		(width 0.125)
		(layer "In2.Cu")
		(net 136)
	)
	(segment
		(start 63.312501 86.546599)
		(end 68.9466 80.9125)
		(width 0.125)
		(layer "In2.Cu")
		(net 136)
	)
	(segment
		(start 97.7875 75.7466)
		(end 97.7875 76.1966)
		(width 0.125)
		(layer "In2.Cu")
		(net 136)
	)
	(segment
		(start 115.513498 76.533797)
		(end 115.642202 76.533797)
		(width 0.125)
		(layer "In2.Cu")
		(net 136)
	)
	(segment
		(start 101.3791 75.78)
		(end 101.3791 75.541264)
		(width 0.125)
		(layer "In2.Cu")
		(net 136)
	)
	(segment
		(start 63.425 101.325)
		(end 63.425 101.075)
		(width 0.125)
		(layer "In2.Cu")
		(net 136)
	)
	(segment
		(start 116.07285 75.587173)
		(end 116.18285 75.587173)
		(width 0.125)
		(layer "In2.Cu")
		(net 136)
	)
	(segment
		(start 117.39035 75.394663)
		(end 117.39035 75.78)
		(width 0.125)
		(layer "In2.Cu")
		(net 136)
	)
	(segment
		(start 114.09035 76.22)
		(end 114.09035 76.755337)
		(width 0.125)
		(layer "In2.Cu")
		(net 136)
	)
	(segment
		(start 126.793033 77.787499)
		(end 126.980532 77.6)
		(width 0.125)
		(layer "In2.Cu")
		(net 136)
	)
	(segment
		(start 95.9125 75.8466)
		(end 96.4466 75.3125)
		(width 0.125)
		(layer "In2.Cu")
		(net 136)
	)
	(segment
		(start 83.299839 76.909992)
		(end 83.539362 77.149515)
		(width 0.125)
		(layer "In2.Cu")
		(net 136)
	)
	(segment
		(start 116.62285 76.1125)
		(end 116.73285 76.1125)
		(width 0.125)
		(layer "In2.Cu")
		(net 136)
	)
	(arc
		(start 117.28285 75.287163)
		(mid 117.358864 75.318649)
		(end 117.39035 75.394663)
		(width 0.125)
		(layer "In2.Cu")
		(net 136)
	)
	(arc
		(start 110.1466 76.1125)
		(mid 110.354383 76.026433)
		(end 110.44045 75.81865)
		(width 0.125)
		(layer "In2.Cu")
		(net 136)
	)
	(arc
		(start 118.71535 76.22)
		(mid 118.746836 76.143986)
		(end 118.82285 76.1125)
		(width 0.125)
		(layer "In2.Cu")
		(net 136)
	)
	(arc
		(start 83.925618 76.132165)
		(mid 84.001632 76.100679)
		(end 84.077646 76.132165)
		(width 0.125)
		(layer "In2.Cu")
		(net 136)
	)
	(arc
		(start 110.79035 76.70874)
		(mid 110.887737 76.943853)
		(end 111.12285 77.04124)
		(width 0.125)
		(layer "In2.Cu")
		(net 136)
	)
	(arc
		(start 99.9466 76.1125)
		(mid 100.181713 76.015113)
		(end 100.2791 75.78)
		(width 0.125)
		(layer "In2.Cu")
		(net 136)
	)
	(arc
		(start 115.19035 76.210649)
		(mid 115.284998 76.439149)
		(end 115.513498 76.533797)
		(width 0.125)
		(layer "In2.Cu")
		(net 136)
	)
	(arc
		(start 83.070028 77.139802)
		(mid 83.038542 77.063788)
		(end 83.070028 76.987774)
		(width 0.125)
		(layer "In2.Cu")
		(net 136)
	)
	(arc
		(start 83.30955 77.84955)
		(mid 83.406937 77.614437)
		(end 83.30955 77.379324)
		(width 0.125)
		(layer "In2.Cu")
		(net 136)
	)
	(arc
		(start 101.5966 75.433764)
		(mid 101.672614 75.46525)
		(end 101.7041 75.541264)
		(width 0.125)
		(layer "In2.Cu")
		(net 136)
	)
	(arc
		(start 63.312501 100.189698)
		(mid 63.353506 100.090703)
		(end 63.452501 100.049698)
		(width 0.125)
		(layer "In2.Cu")
		(net 136)
	)
	(arc
		(start 100.6041 75.78)
		(mid 100.701487 76.015113)
		(end 100.9366 76.1125)
		(width 0.125)
		(layer "In2.Cu")
		(net 136)
	)
	(arc
		(start 84.087367 77.071733)
		(mid 84.184754 76.83662)
		(end 84.087367 76.601507)
		(width 0.125)
		(layer "In2.Cu")
		(net 136)
	)
	(arc
		(start 101.3791 75.541264)
		(mid 101.410586 75.46525)
		(end 101.4866 75.433764)
		(width 0.125)
		(layer "In2.Cu")
		(net 136)
	)
	(arc
		(start 116.73285 76.1125)
		(mid 116.967963 76.015113)
		(end 117.06535 75.78)
		(width 0.125)
		(layer "In2.Cu")
		(net 136)
	)
	(arc
		(start 114.53285 77.087837)
		(mid 114.767963 76.99045)
		(end 114.86535 76.755337)
		(width 0.125)
		(layer "In2.Cu")
		(net 136)
	)
	(arc
		(start 63.762555 99.839698)
		(mid 63.72155 99.740703)
		(end 63.622555 99.699698)
		(width 0.125)
		(layer "In2.Cu")
		(net 136)
	)
	(arc
		(start 117.83285 76.1125)
		(mid 117.908864 76.143986)
		(end 117.94035 76.22)
		(width 0.125)
		(layer "In2.Cu")
		(net 136)
	)
	(arc
		(start 116.18285 75.587173)
		(mid 116.258864 75.618659)
		(end 116.29035 75.694673)
		(width 0.125)
		(layer "In2.Cu")
		(net 136)
	)
	(arc
		(start 83.847835 76.361975)
		(mid 83.816349 76.285961)
		(end 83.847835 76.209947)
		(width 0.125)
		(layer "In2.Cu")
		(net 136)
	)
	(arc
		(start 115.642202 76.533797)
		(mid 115.870702 76.439149)
		(end 115.96535 76.210649)
		(width 0.125)
		(layer "In2.Cu")
		(net 136)
	)
	(arc
		(start 111.78285 76.1125)
		(mid 112.017963 76.015113)
		(end 112.11535 75.78)
		(width 0.125)
		(layer "In2.Cu")
		(net 136)
	)
	(arc
		(start 115.96535 75.694673)
		(mid 115.996836 75.618659)
		(end 116.07285 75.587173)
		(width 0.125)
		(layer "In2.Cu")
		(net 136)
	)
	(arc
		(start 118.38285 77.087817)
		(mid 118.617963 76.99043)
		(end 118.71535 76.755317)
		(width 0.125)
		(layer "In2.Cu")
		(net 136)
	)
	(arc
		(start 63.622555 100.049698)
		(mid 63.72155 100.008693)
		(end 63.762555 99.909698)
		(width 0.125)
		(layer "In2.Cu")
		(net 136)
	)
	(arc
		(start 115.092201 75.691201)
		(mid 115.161603 75.719948)
		(end 115.19035 75.78935)
		(width 0.125)
		(layer "In2.Cu")
		(net 136)
	)
	(arc
		(start 101.0466 76.1125)
		(mid 101.281713 76.015113)
		(end 101.3791 75.78)
		(width 0.125)
		(layer "In2.Cu")
		(net 136)
	)
	(arc
		(start 102.6966 75.759206)
		(mid 102.741959 75.777994)
		(end 102.760747 75.823353)
		(width 0.125)
		(layer "In2.Cu")
		(net 136)
	)
	(arc
		(start 83.147811 76.909992)
		(mid 83.223825 76.878506)
		(end 83.299839 76.909992)
		(width 0.125)
		(layer "In2.Cu")
		(net 136)
	)
	(arc
		(start 102.435747 75.823353)
		(mid 102.454535 75.777994)
		(end 102.499894 75.759206)
		(width 0.125)
		(layer "In2.Cu")
		(net 136)
	)
	(arc
		(start 110.7215 75.7498)
		(mid 110.770184 75.769966)
		(end 110.79035 75.81865)
		(width 0.125)
		(layer "In2.Cu")
		(net 136)
	)
	(arc
		(start 111.56535 76.22)
		(mid 111.596836 76.143986)
		(end 111.67285 76.1125)
		(width 0.125)
		(layer "In2.Cu")
		(net 136)
	)
	(arc
		(start 102.1466 76.1125)
		(mid 102.351058 76.027811)
		(end 102.435747 75.823353)
		(width 0.125)
		(layer "In2.Cu")
		(net 136)
	)
	(arc
		(start 113.98285 76.1125)
		(mid 114.058864 76.143986)
		(end 114.09035 76.22)
		(width 0.125)
		(layer "In2.Cu")
		(net 136)
	)
	(arc
		(start 100.2791 75.191258)
		(mid 100.310586 75.115244)
		(end 100.3866 75.083758)
		(width 0.125)
		(layer "In2.Cu")
		(net 136)
	)
	(arc
		(start 113.43285 75.087184)
		(mid 113.508864 75.11867)
		(end 113.54035 75.194684)
		(width 0.125)
		(layer "In2.Cu")
		(net 136)
	)
	(arc
		(start 112.44035 76.175)
		(mid 112.524557 76.378293)
		(end 112.72785 76.4625)
		(width 0.125)
		(layer "In2.Cu")
		(net 136)
	)
	(arc
		(start 114.86535 75.78935)
		(mid 114.894097 75.719948)
		(end 114.963499 75.691201)
		(width 0.125)
		(layer "In2.Cu")
		(net 136)
	)
	(arc
		(start 112.33285 75.283753)
		(mid 112.408864 75.315239)
		(end 112.44035 75.391253)
		(width 0.125)
		(layer "In2.Cu")
		(net 136)
	)
	(arc
		(start 113.21535 75.194684)
		(mid 113.246836 75.11867)
		(end 113.32285 75.087184)
		(width 0.125)
		(layer "In2.Cu")
		(net 136)
	)
	(arc
		(start 84.317179 76.371698)
		(mid 84.552292 76.469085)
		(end 84.787405 76.371698)
		(width 0.125)
		(layer "In2.Cu")
		(net 136)
	)
	(arc
		(start 117.39035 75.78)
		(mid 117.487737 76.015113)
		(end 117.72285 76.1125)
		(width 0.125)
		(layer "In2.Cu")
		(net 136)
	)
	(arc
		(start 100.4966 75.083758)
		(mid 100.572614 75.115244)
		(end 100.6041 75.191258)
		(width 0.125)
		(layer "In2.Cu")
		(net 136)
	)
	(arc
		(start 83.539362 77.149515)
		(mid 83.774475 77.246902)
		(end 84.009588 77.149515)
		(width 0.125)
		(layer "In2.Cu")
		(net 136)
	)
	(arc
		(start 112.11535 75.391253)
		(mid 112.146836 75.315239)
		(end 112.22285 75.283753)
		(width 0.125)
		(layer "In2.Cu")
		(net 136)
	)
	(arc
		(start 110.44045 75.81865)
		(mid 110.460616 75.769966)
		(end 110.5093 75.7498)
		(width 0.125)
		(layer "In2.Cu")
		(net 136)
	)
	(arc
		(start 111.23285 77.04124)
		(mid 111.467963 76.943853)
		(end 111.56535 76.70874)
		(width 0.125)
		(layer "In2.Cu")
		(net 136)
	)
	(arc
		(start 113.54035 75.78)
		(mid 113.637737 76.015113)
		(end 113.87285 76.1125)
		(width 0.125)
		(layer "In2.Cu")
		(net 136)
	)
	(arc
		(start 116.29035 75.78)
		(mid 116.387737 76.015113)
		(end 116.62285 76.1125)
		(width 0.125)
		(layer "In2.Cu")
		(net 136)
	)
	(arc
		(start 112.92785 76.4625)
		(mid 113.131143 76.378293)
		(end 113.21535 76.175)
		(width 0.125)
		(layer "In2.Cu")
		(net 136)
	)
	(arc
		(start 117.94035 76.755317)
		(mid 118.037737 76.99043)
		(end 118.27285 77.087817)
		(width 0.125)
		(layer "In2.Cu")
		(net 136)
	)
	(arc
		(start 114.09035 76.755337)
		(mid 114.187737 76.99045)
		(end 114.42285 77.087837)
		(width 0.125)
		(layer "In2.Cu")
		(net 136)
	)
	(arc
		(start 63.452501 99.699698)
		(mid 63.353506 99.658693)
		(end 63.312501 99.559698)
		(width 0.125)
		(layer "In2.Cu")
		(net 136)
	)
	(arc
		(start 117.06535 75.394663)
		(mid 117.096836 75.318649)
		(end 117.17285 75.287163)
		(width 0.125)
		(layer "In2.Cu")
		(net 136)
	)
	(arc
		(start 101.7041 75.78)
		(mid 101.801487 76.015113)
		(end 102.0366 76.1125)
		(width 0.125)
		(layer "In2.Cu")
		(net 136)
	)
	(arc
		(start 102.760747 75.823353)
		(mid 102.845436 76.027811)
		(end 103.049894 76.1125)
		(width 0.125)
		(layer "In2.Cu")
		(net 136)
	)
	(segment
		(start 116 131.3)
		(end 114 133.3)
		(width 0.1)
		(layer "F.Cu")
		(net 137)
	)
	(segment
		(start 121.330532 84.669468)
		(end 120.8 85.2)
		(width 0.1)
		(layer "F.Cu")
		(net 137)
	)
	(segment
		(start 120.8 85.2)
		(end 120.8 90.7)
		(width 0.1)
		(layer "F.Cu")
		(net 137)
	)
	(segment
		(start 120.35 91.15)
		(end 120.8 90.7)
		(width 0.1)
		(layer "F.Cu")
		(net 137)
	)
	(segment
		(start 107.6 134.1)
		(end 107.6 134.7)
		(width 0.1)
		(layer "F.Cu")
		(net 137)
	)
	(segment
		(start 121.330532 84.15)
		(end 121.330532 84.669468)
		(width 0.1)
		(layer "F.Cu")
		(net 137)
	)
	(segment
		(start 120.35 105.85)
		(end 120.35 91.15)
		(width 0.1)
		(layer "F.Cu")
		(net 137)
	)
	(segment
		(start 120.35 105.85)
		(end 116 110.2)
		(width 0.1)
		(layer "F.Cu")
		(net 137)
	)
	(segment
		(start 108.4 133.3)
		(end 107.6 134.1)
		(width 0.1)
		(layer "F.Cu")
		(net 137)
	)
	(segment
		(start 116 110.2)
		(end 116 131.3)
		(width 0.1)
		(layer "F.Cu")
		(net 137)
	)
	(segment
		(start 114 133.3)
		(end 108.4 133.3)
		(width 0.1)
		(layer "F.Cu")
		(net 137)
	)
	(via
		(at 107.6 134.7)
		(size 0.45)
		(drill 0.1)
		(layers "F.Cu" "B.Cu")
		(net 137)
	)
	(segment
		(start 107.6 134)
		(end 108.3 133.3)
		(width 0.1)
		(layer "B.Cu")
		(net 137)
	)
	(segment
		(start 109.34 133.3)
		(end 108.3 133.3)
		(width 0.1)
		(layer "B.Cu")
		(net 137)
	)
	(segment
		(start 107.6 134)
		(end 107.6 134.7)
		(width 0.1)
		(layer "B.Cu")
		(net 137)
	)
	(segment
		(start 135.4 71.6)
		(end 135.95 72.15)
		(width 0.1)
		(layer "F.Cu")
		(net 138)
	)
	(segment
		(start 135.4 71.6)
		(end 134.7 71.6)
		(width 0.1)
		(layer "F.Cu")
		(net 138)
	)
	(segment
		(start 136.130532 72.15)
		(end 135.95 72.15)
		(width 0.1)
		(layer "F.Cu")
		(net 138)
	)
	(via
		(at 134.7 71.6)
		(size 0.45)
		(drill 0.1)
		(layers "F.Cu" "B.Cu")
		(net 138)
	)
	(segment
		(start 134.8 72.6)
		(end 134.8 71.7)
		(width 0.1)
		(layer "B.Cu")
		(net 138)
	)
	(segment
		(start 134.8 71.7)
		(end 134.7 71.6)
		(width 0.1)
		(layer "B.Cu")
		(net 138)
	)
	(segment
		(start 149.9 111.15)
		(end 150.5 111.15)
		(width 0.1)
		(layer "F.Cu")
		(net 139)
	)
	(segment
		(start 149.8 111)
		(end 149.8 111.05)
		(width 0.1)
		(layer "F.Cu")
		(net 139)
	)
	(segment
		(start 149.8 111.15)
		(end 149.9 111.15)
		(width 0.1)
		(layer "F.Cu")
		(net 139)
	)
	(segment
		(start 149.8 111.05)
		(end 149.9 111.15)
		(width 0.1)
		(layer "F.Cu")
		(net 139)
	)
	(segment
		(start 149.8 110.6)
		(end 149.8 111)
		(width 0.1)
		(layer "F.Cu")
		(net 139)
	)
	(segment
		(start 150.6 111.25)
		(end 151.23 111.25)
		(width 0.1)
		(layer "F.Cu")
		(net 139)
	)
	(segment
		(start 150.5 111.15)
		(end 150.6 111.25)
		(width 0.1)
		(layer "F.Cu")
		(net 139)
	)
	(segment
		(start 149.7 111.15)
		(end 149.46 111.15)
		(width 0.1)
		(layer "F.Cu")
		(net 139)
	)
	(segment
		(start 147.48 110)
		(end 148.31 110)
		(width 0.1)
		(layer "F.Cu")
		(net 139)
	)
	(segment
		(start 149.8 111)
		(end 149.8 111.15)
		(width 0.1)
		(layer "F.Cu")
		(net 139)
	)
	(segment
		(start 149.7 111.15)
		(end 149.8 111.15)
		(width 0.1)
		(layer "F.Cu")
		(net 139)
	)
	(segment
		(start 143.130532 73.65)
		(end 143.15 73.65)
		(width 0.1)
		(layer "F.Cu")
		(net 139)
	)
	(segment
		(start 148.31 110)
		(end 149.46 111.15)
		(width 0.1)
		(layer "F.Cu")
		(net 139)
	)
	(segment
		(start 149.8 111.05)
		(end 149.7 111.15)
		(width 0.1)
		(layer "F.Cu")
		(net 139)
	)
	(via
		(at 140.25 99.2)
		(size 0.45)
		(drill 0.1)
		(layers "F.Cu" "B.Cu")
		(net 139)
	)
	(via
		(at 143.15 73.65)
		(size 0.45)
		(drill 0.1)
		(layers "F.Cu" "B.Cu")
		(net 139)
	)
	(via
		(at 149.8 110.6)
		(size 0.45)
		(drill 0.1)
		(layers "F.Cu" "B.Cu")
		(net 139)
	)
	(segment
		(start 146.45 106.075)
		(end 146.45 106.45)
		(width 0.1)
		(layer "In4.Cu")
		(net 139)
	)
	(segment
		(start 147.725 107.725)
		(end 148.875 107.725)
		(width 0.1)
		(layer "In4.Cu")
		(net 139)
	)
	(segment
		(start 146.45 106.45)
		(end 147.725 107.725)
		(width 0.1)
		(layer "In4.Cu")
		(net 139)
	)
	(segment
		(start 149.9 108.75)
		(end 149.9 109.8)
		(width 0.1)
		(layer "In4.Cu")
		(net 139)
	)
	(segment
		(start 148.875 107.725)
		(end 149.9 108.75)
		(width 0.1)
		(layer "In4.Cu")
		(net 139)
	)
	(segment
		(start 149.9 109.8)
		(end 149.8 109.9)
		(width 0.1)
		(layer "In4.Cu")
		(net 139)
	)
	(segment
		(start 140.25 99.2)
		(end 140.25 99.875)
		(width 0.1)
		(layer "In4.Cu")
		(net 139)
	)
	(segment
		(start 149.8 109.9)
		(end 149.8 110.6)
		(width 0.1)
		(layer "In4.Cu")
		(net 139)
	)
	(segment
		(start 140.25 99.875)
		(end 146.45 106.075)
		(width 0.1)
		(layer "In4.Cu")
		(net 139)
	)
	(segment
		(start 145.7 73.85)
		(end 144.95 73.1)
		(width 0.1)
		(layer "In5.Cu")
		(net 139)
	)
	(segment
		(start 144.975 86.226213)
		(end 144.554532 85.805745)
		(width 0.1)
		(layer "In5.Cu")
		(net 139)
	)
	(segment
		(start 144.95 73.1)
		(end 143.7 73.1)
		(width 0.1)
		(layer "In5.Cu")
		(net 139)
	)
	(segment
		(start 147.4 80.9)
		(end 145.7 79.2)
		(width 0.1)
		(layer "In5.Cu")
		(net 139)
	)
	(segment
		(start 145.126 86.661413)
		(end 144.975 86.510413)
		(width 0.1)
		(layer "In5.Cu")
		(net 139)
	)
	(segment
		(start 145.126 87.163159)
		(end 145.126 86.661413)
		(width 0.1)
		(layer "In5.Cu")
		(net 139)
	)
	(segment
		(start 140.25 92.85)
		(end 143.95 89.15)
		(width 0.1)
		(layer "In5.Cu")
		(net 139)
	)
	(segment
		(start 144.975 86.510413)
		(end 144.975 86.226213)
		(width 0.1)
		(layer "In5.Cu")
		(net 139)
	)
	(segment
		(start 143.95 88.192157)
		(end 144.520156 87.622001)
		(width 0.1)
		(layer "In5.Cu")
		(net 139)
	)
	(segment
		(start 145.243155 85.274)
		(end 145.317157 85.2)
		(width 0.1)
		(layer "In5.Cu")
		(net 139)
	)
	(segment
		(start 144.554532 85.494255)
		(end 144.774787 85.274)
		(width 0.1)
		(layer "In5.Cu")
		(net 139)
	)
	(segment
		(start 144.774787 85.274)
		(end 145.243155 85.274)
		(width 0.1)
		(layer "In5.Cu")
		(net 139)
	)
	(segment
		(start 145.617158 85.2)
		(end 147.4 83.417158)
		(width 0.1)
		(layer "In5.Cu")
		(net 139)
	)
	(segment
		(start 144.554532 85.805745)
		(end 144.554532 85.494255)
		(width 0.1)
		(layer "In5.Cu")
		(net 139)
	)
	(segment
		(start 147.4 83.417158)
		(end 147.4 80.9)
		(width 0.1)
		(layer "In5.Cu")
		(net 139)
	)
	(segment
		(start 144.520156 87.622001)
		(end 144.667158 87.622001)
		(width 0.1)
		(layer "In5.Cu")
		(net 139)
	)
	(segment
		(start 143.7 73.1)
		(end 143.15 73.65)
		(width 0.1)
		(layer "In5.Cu")
		(net 139)
	)
	(segment
		(start 140.25 99.2)
		(end 140.25 92.85)
		(width 0.1)
		(layer "In5.Cu")
		(net 139)
	)
	(segment
		(start 145.7 79.2)
		(end 145.7 73.85)
		(width 0.1)
		(layer "In5.Cu")
		(net 139)
	)
	(segment
		(start 143.95 89.15)
		(end 143.95 88.192157)
		(width 0.1)
		(layer "In5.Cu")
		(net 139)
	)
	(segment
		(start 144.667158 87.622001)
		(end 145.126 87.163159)
		(width 0.1)
		(layer "In5.Cu")
		(net 139)
	)
	(segment
		(start 145.317157 85.2)
		(end 145.617158 85.2)
		(width 0.1)
		(layer "In5.Cu")
		(net 139)
	)
	(segment
		(start 222.201633 88.587)
		(end 221.789132 88.587)
		(width 0.17)
		(layer "F.Cu")
		(net 140)
	)
	(segment
		(start 222.86 88.665)
		(end 222.857 88.662)
		(width 0.17)
		(layer "F.Cu")
		(net 140)
	)
	(segment
		(start 220.529631 88.662)
		(end 219.825 88.662)
		(width 0.17)
		(layer "F.Cu")
		(net 140)
	)
	(segment
		(start 232.430532 89.439468)
		(end 232.930532 88.939468)
		(width 0.17)
		(layer "F.Cu")
		(net 140)
	)
	(segment
		(start 222.276633 88.662)
		(end 222.201633 88.587)
		(width 0.17)
		(layer "F.Cu")
		(net 140)
	)
	(segment
		(start 232.930532 88.939468)
		(end 232.930532 88.0725)
		(width 0.17)
		(layer "F.Cu")
		(net 140)
	)
	(segment
		(start 220.604631 88.587)
		(end 220.529631 88.662)
		(width 0.17)
		(layer "F.Cu")
		(net 140)
	)
	(segment
		(start 224.287868 88.414644)
		(end 224.037512 88.665)
		(width 0.17)
		(layer "F.Cu")
		(net 140)
	)
	(segment
		(start 224.287868 88.237868)
		(end 224.287868 88.414644)
		(width 0.17)
		(layer "F.Cu")
		(net 140)
	)
	(segment
		(start 94.705532 81.875)
		(end 94.580532 81.75)
		(width 0.17)
		(layer "F.Cu")
		(net 140)
	)
	(segment
		(start 221.017132 88.587)
		(end 220.604631 88.587)
		(width 0.17)
		(layer "F.Cu")
		(net 140)
	)
	(segment
		(start 219.825 88.662)
		(end 219.7 88.537)
		(width 0.17)
		(layer "F.Cu")
		(net 140)
	)
	(segment
		(start 94.430532 82.65)
		(end 94.705532 82.375)
		(width 0.17)
		(layer "F.Cu")
		(net 140)
	)
	(segment
		(start 221.789132 88.587)
		(end 221.017132 88.587)
		(width 0.17)
		(layer "F.Cu")
		(net 140)
	)
	(segment
		(start 232.430532 90.3475)
		(end 232.430532 89.439468)
		(width 0.17)
		(layer "F.Cu")
		(net 140)
	)
	(segment
		(start 94.705532 82.375)
		(end 94.705532 81.875)
		(width 0.17)
		(layer "F.Cu")
		(net 140)
	)
	(segment
		(start 224.037512 88.665)
		(end 222.86 88.665)
		(width 0.17)
		(layer "F.Cu")
		(net 140)
	)
	(segment
		(start 232.930532 88.0725)
		(end 232.930532 86.939468)
		(width 0.17)
		(layer "F.Cu")
		(net 140)
	)
	(segment
		(start 222.857 88.662)
		(end 222.276633 88.662)
		(width 0.17)
		(layer "F.Cu")
		(net 140)
	)
	(segment
		(start 232.930532 86.939468)
		(end 232.97 86.9)
		(width 0.17)
		(layer "F.Cu")
		(net 140)
	)
	(via
		(at 232.97 86.9)
		(size 0.45)
		(drill 0.1)
		(layers "F.Cu" "B.Cu")
		(net 140)
	)
	(via
		(at 224.287868 88.237868)
		(size 0.45)
		(drill 0.1)
		(layers "F.Cu" "B.Cu")
		(net 140)
	)
	(via
		(at 94.580532 81.75)
		(size 0.45)
		(drill 0.1)
		(layers "F.Cu" "B.Cu")
		(net 140)
	)
	(via
		(at 219.7 88.537)
		(size 0.45)
		(drill 0.1)
		(layers "F.Cu" "B.Cu")
		(net 140)
	)
	(segment
		(start 228.589455 84.375)
		(end 228.709455 84.375)
		(width 0.17)
		(layer "B.Cu")
		(net 140)
	)
	(segment
		(start 229.549455 84.110338)
		(end 229.549455 84.135)
		(width 0.17)
		(layer "B.Cu")
		(net 140)
	)
	(segment
		(start 229.189455 83.870338)
		(end 229.309455 83.870338)
		(width 0.17)
		(layer "B.Cu")
		(net 140)
	)
	(segment
		(start 224.287868 88.237868)
		(end 224.464644 88.237868)
		(width 0.17)
		(layer "B.Cu")
		(net 140)
	)
	(segment
		(start 232.487052 85.049564)
		(end 232.845 85.407512)
		(width 0.17)
		(layer "B.Cu")
		(net 140)
	)
	(segment
		(start 227.749455 84.135)
		(end 227.749455 84.110313)
		(width 0.17)
		(layer "B.Cu")
		(net 140)
	)
	(segment
		(start 224.464644 88.237868)
		(end 224.975 87.727512)
		(width 0.17)
		(layer "B.Cu")
		(net 140)
	)
	(segment
		(start 230.389455 83.870313)
		(end 230.509455 83.870313)
		(width 0.17)
		(layer "B.Cu")
		(net 140)
	)
	(segment
		(start 231.812488 84.375)
		(end 232.487052 85.049564)
		(width 0.17)
		(layer "B.Cu")
		(net 140)
	)
	(segment
		(start 232.845 86.775)
		(end 232.97 86.9)
		(width 0.17)
		(layer "B.Cu")
		(net 140)
	)
	(segment
		(start 227.989455 83.870313)
		(end 228.109455 83.870313)
		(width 0.17)
		(layer "B.Cu")
		(net 140)
	)
	(segment
		(start 231.109455 84.375)
		(end 231.812488 84.375)
		(width 0.17)
		(layer "B.Cu")
		(net 140)
	)
	(segment
		(start 228.949455 84.135)
		(end 228.949455 84.110338)
		(width 0.17)
		(layer "B.Cu")
		(net 140)
	)
	(segment
		(start 228.349455 84.110313)
		(end 228.349455 84.135)
		(width 0.17)
		(layer "B.Cu")
		(net 140)
	)
	(segment
		(start 230.749455 84.110313)
		(end 230.749455 84.135)
		(width 0.17)
		(layer "B.Cu")
		(net 140)
	)
	(segment
		(start 230.989455 84.375)
		(end 231.109455 84.375)
		(width 0.17)
		(layer "B.Cu")
		(net 140)
	)
	(segment
		(start 224.975 87.727512)
		(end 224.975 86.077512)
		(width 0.17)
		(layer "B.Cu")
		(net 140)
	)
	(segment
		(start 232.845 85.407512)
		(end 232.845 86.775)
		(width 0.17)
		(layer "B.Cu")
		(net 140)
	)
	(segment
		(start 224.975 86.077512)
		(end 226.677512 84.375)
		(width 0.17)
		(layer "B.Cu")
		(net 140)
	)
	(segment
		(start 226.677512 84.375)
		(end 227.509455 84.375)
		(width 0.17)
		(layer "B.Cu")
		(net 140)
	)
	(segment
		(start 230.149455 84.135)
		(end 230.149455 84.110313)
		(width 0.17)
		(layer "B.Cu")
		(net 140)
	)
	(segment
		(start 229.789455 84.375)
		(end 229.909455 84.375)
		(width 0.17)
		(layer "B.Cu")
		(net 140)
	)
	(arc
		(start 228.109455 83.870313)
		(mid 228.279161 83.940607)
		(end 228.349455 84.110313)
		(width 0.17)
		(layer "B.Cu")
		(net 140)
	)
	(arc
		(start 229.909455 84.375)
		(mid 230.079161 84.304706)
		(end 230.149455 84.135)
		(width 0.17)
		(layer "B.Cu")
		(net 140)
	)
	(arc
		(start 227.509455 84.375)
		(mid 227.679161 84.304706)
		(end 227.749455 84.135)
		(width 0.17)
		(layer "B.Cu")
		(net 140)
	)
	(arc
		(start 229.309455 83.870338)
		(mid 229.479161 83.940632)
		(end 229.549455 84.110338)
		(width 0.17)
		(layer "B.Cu")
		(net 140)
	)
	(arc
		(start 230.509455 83.870313)
		(mid 230.679161 83.940607)
		(end 230.749455 84.110313)
		(width 0.17)
		(layer "B.Cu")
		(net 140)
	)
	(arc
		(start 228.349455 84.135)
		(mid 228.419749 84.304706)
		(end 228.589455 84.375)
		(width 0.17)
		(layer "B.Cu")
		(net 140)
	)
	(arc
		(start 227.749455 84.110313)
		(mid 227.819749 83.940607)
		(end 227.989455 83.870313)
		(width 0.17)
		(layer "B.Cu")
		(net 140)
	)
	(arc
		(start 229.549455 84.135)
		(mid 229.619749 84.304706)
		(end 229.789455 84.375)
		(width 0.17)
		(layer "B.Cu")
		(net 140)
	)
	(arc
		(start 228.709455 84.375)
		(mid 228.879161 84.304706)
		(end 228.949455 84.135)
		(width 0.17)
		(layer "B.Cu")
		(net 140)
	)
	(arc
		(start 230.149455 84.110313)
		(mid 230.219749 83.940607)
		(end 230.389455 83.870313)
		(width 0.17)
		(layer "B.Cu")
		(net 140)
	)
	(arc
		(start 230.749455 84.135)
		(mid 230.819749 84.304706)
		(end 230.989455 84.375)
		(width 0.17)
		(layer "B.Cu")
		(net 140)
	)
	(arc
		(start 228.949455 84.110338)
		(mid 229.019749 83.940632)
		(end 229.189455 83.870338)
		(width 0.17)
		(layer "B.Cu")
		(net 140)
	)
	(segment
		(start 194.3466 72.7125)
		(end 194.8966 72.1625)
		(width 0.125)
		(layer "In7.Cu")
		(net 140)
	)
	(segment
		(start 176.1784 69.4375)
		(end 176.6784 69.9375)
		(width 0.125)
		(layer "In7.Cu")
		(net 140)
	)
	(segment
		(start 149.3534 69.9125)
		(end 162.5534 69.9125)
		(width 0.125)
		(layer "In7.Cu")
		(net 140)
	)
	(segment
		(start 216.6534 82.2125)
		(end 217.8534 82.2125)
		(width 0.125)
		(layer "In7.Cu")
		(net 140)
	)
	(segment
		(start 215.2875 78.8466)
		(end 215.2875 80.8466)
		(width 0.125)
		(layer "In7.Cu")
		(net 140)
	)
	(segment
		(start 94.580532 81.75)
		(end 94.768031 81.937499)
		(width 0.125)
		(layer "In7.Cu")
		(net 140)
	)
	(segment
		(start 101.1125 74.9966)
		(end 101.1125 72.4966)
		(width 0.125)
		(layer "In7.Cu")
		(net 140)
	)
	(segment
		(start 194.8966 72.1625)
		(end 208.6034 72.1625)
		(width 0.125)
		(layer "In7.Cu")
		(net 140)
	)
	(segment
		(start 114.355698 58.0625)
		(end 139.8534 58.0625)
		(width 0.125)
		(layer "In7.Cu")
		(net 140)
	)
	(segment
		(start 176.6784 69.9375)
		(end 186.9784 69.9375)
		(width 0.125)
		(layer "In7.Cu")
		(net 140)
	)
	(segment
		(start 96.9966 80.5625)
		(end 97.5466 80.5625)
		(width 0.125)
		(layer "In7.Cu")
		(net 140)
	)
	(segment
		(start 96.1125 81.9466)
		(end 96.1125 81.4466)
		(width 0.125)
		(layer "In7.Cu")
		(net 140)
	)
	(segment
		(start 220.3375 88.5034)
		(end 220.116401 88.724499)
		(width 0.125)
		(layer "In7.Cu")
		(net 140)
	)
	(segment
		(start 220.116401 88.724499)
		(end 219.887499 88.724499)
		(width 0.125)
		(layer "In7.Cu")
		(net 140)
	)
	(segment
		(start 217.8534 82.2125)
		(end 218.36805 82.72715)
		(width 0.125)
		(layer "In7.Cu")
		(net 140)
	)
	(segment
		(start 215.2875 80.8466)
		(end 216.6534 82.2125)
		(width 0.125)
		(layer "In7.Cu")
		(net 140)
	)
	(segment
		(start 219.887499 88.724499)
		(end 219.7 88.537)
		(width 0.125)
		(layer "In7.Cu")
		(net 140)
	)
	(segment
		(start 220.3375 84.6966)
		(end 220.3375 88.5034)
		(width 0.125)
		(layer "In7.Cu")
		(net 140)
	)
	(segment
		(start 98.9125 77.9466)
		(end 99.6625 77.1966)
		(width 0.125)
		(layer "In7.Cu")
		(net 140)
	)
	(segment
		(start 147.3375 65.5466)
		(end 147.3375 67.8966)
		(width 0.125)
		(layer "In7.Cu")
		(net 140)
	)
	(segment
		(start 218.596721 83.191441)
		(end 218.615536 83.172625)
		(width 0.125)
		(layer "In7.Cu")
		(net 140)
	)
	(segment
		(start 98.9125 79.1966)
		(end 98.9125 77.9466)
		(width 0.125)
		(layer "In7.Cu")
		(net 140)
	)
	(segment
		(start 97.5466 80.5625)
		(end 98.9125 79.1966)
		(width 0.125)
		(layer "In7.Cu")
		(net 140)
	)
	(segment
		(start 105.7625 64.7966)
		(end 107.3066 63.2525)
		(width 0.125)
		(layer "In7.Cu")
		(net 140)
	)
	(segment
		(start 94.768031 82.177131)
		(end 95.0034 82.4125)
		(width 0.125)
		(layer "In7.Cu")
		(net 140)
	)
	(segment
		(start 147.3375 67.8966)
		(end 149.3534 69.9125)
		(width 0.125)
		(layer "In7.Cu")
		(net 140)
	)
	(segment
		(start 139.8534 58.0625)
		(end 147.3375 65.5466)
		(width 0.125)
		(layer "In7.Cu")
		(net 140)
	)
	(segment
		(start 95.0034 82.4125)
		(end 95.6466 82.4125)
		(width 0.125)
		(layer "In7.Cu")
		(net 140)
	)
	(segment
		(start 109.165698 63.2525)
		(end 114.355698 58.0625)
		(width 0.125)
		(layer "In7.Cu")
		(net 140)
	)
	(segment
		(start 189.7534 72.7125)
		(end 194.3466 72.7125)
		(width 0.125)
		(layer "In7.Cu")
		(net 140)
	)
	(segment
		(start 107.3066 63.2525)
		(end 109.165698 63.2525)
		(width 0.125)
		(layer "In7.Cu")
		(net 140)
	)
	(segment
		(start 99.6625 77.1966)
		(end 99.6625 76.4466)
		(width 0.125)
		(layer "In7.Cu")
		(net 140)
	)
	(segment
		(start 101.1125 72.4966)
		(end 105.7625 67.8466)
		(width 0.125)
		(layer "In7.Cu")
		(net 140)
	)
	(segment
		(start 95.6466 82.4125)
		(end 96.1125 81.9466)
		(width 0.125)
		(layer "In7.Cu")
		(net 140)
	)
	(segment
		(start 167.9966 69.4375)
		(end 176.1784 69.4375)
		(width 0.125)
		(layer "In7.Cu")
		(net 140)
	)
	(segment
		(start 162.5534 69.9125)
		(end 162.7284 70.0875)
		(width 0.125)
		(layer "In7.Cu")
		(net 140)
	)
	(segment
		(start 96.1125 81.4466)
		(end 96.9966 80.5625)
		(width 0.125)
		(layer "In7.Cu")
		(net 140)
	)
	(segment
		(start 218.349234 83.141944)
		(end 218.398731 83.191441)
		(width 0.125)
		(layer "In7.Cu")
		(net 140)
	)
	(segment
		(start 208.6034 72.1625)
		(end 215.2875 78.8466)
		(width 0.125)
		(layer "In7.Cu")
		(net 140)
	)
	(segment
		(start 162.7284 70.0875)
		(end 167.3466 70.0875)
		(width 0.125)
		(layer "In7.Cu")
		(net 140)
	)
	(segment
		(start 218.813526 83.172625)
		(end 220.3375 84.6966)
		(width 0.125)
		(layer "In7.Cu")
		(net 140)
	)
	(segment
		(start 99.6625 76.4466)
		(end 101.1125 74.9966)
		(width 0.125)
		(layer "In7.Cu")
		(net 140)
	)
	(segment
		(start 167.3466 70.0875)
		(end 167.9966 69.4375)
		(width 0.125)
		(layer "In7.Cu")
		(net 140)
	)
	(segment
		(start 218.36805 82.925139)
		(end 218.349234 82.943954)
		(width 0.125)
		(layer "In7.Cu")
		(net 140)
	)
	(segment
		(start 94.768031 81.937499)
		(end 94.768031 82.177131)
		(width 0.125)
		(layer "In7.Cu")
		(net 140)
	)
	(segment
		(start 105.7625 67.8466)
		(end 105.7625 64.7966)
		(width 0.125)
		(layer "In7.Cu")
		(net 140)
	)
	(segment
		(start 186.9784 69.9375)
		(end 189.7534 72.7125)
		(width 0.125)
		(layer "In7.Cu")
		(net 140)
	)
	(arc
		(start 218.398731 83.191441)
		(mid 218.497726 83.232446)
		(end 218.596721 83.191441)
		(width 0.125)
		(layer "In7.Cu")
		(net 140)
	)
	(arc
		(start 218.615536 83.172625)
		(mid 218.714531 83.13162)
		(end 218.813526 83.172625)
		(width 0.125)
		(layer "In7.Cu")
		(net 140)
	)
	(arc
		(start 218.36805 82.72715)
		(mid 218.409054 82.826145)
		(end 218.36805 82.925139)
		(width 0.125)
		(layer "In7.Cu")
		(net 140)
	)
	(arc
		(start 218.349234 82.943954)
		(mid 218.308229 83.042949)
		(end 218.349234 83.141944)
		(width 0.125)
		(layer "In7.Cu")
		(net 140)
	)
	(segment
		(start 101.330532 75.15)
		(end 101.330532 74.430532)
		(width 0.1)
		(layer "F.Cu")
		(net 141)
	)
	(segment
		(start 97.4 71.5)
		(end 96.9 71)
		(width 0.1)
		(layer "F.Cu")
		(net 141)
	)
	(segment
		(start 100.9 74)
		(end 100.9 71.7)
		(width 0.1)
		(layer "F.Cu")
		(net 141)
	)
	(segment
		(start 101.330532 74.430532)
		(end 100.9 74)
		(width 0.1)
		(layer "F.Cu")
		(net 141)
	)
	(segment
		(start 100.7 71.5)
		(end 97.4 71.5)
		(width 0.1)
		(layer "F.Cu")
		(net 141)
	)
	(segment
		(start 100.9 71.7)
		(end 100.7 71.5)
		(width 0.1)
		(layer "F.Cu")
		(net 141)
	)
	(via
		(at 96.9 71)
		(size 0.45)
		(drill 0.1)
		(layers "F.Cu" "B.Cu")
		(net 141)
	)
	(via
		(at 75.775532 96.725)
		(size 0.45)
		(drill 0.1)
		(layers "F.Cu" "B.Cu")
		(net 141)
	)
	(segment
		(start 75.775532 96.725)
		(end 75 95.949468)
		(width 0.1)
		(layer "In5.Cu")
		(net 141)
	)
	(segment
		(start 74.7 79.4)
		(end 79.8 79.4)
		(width 0.1)
		(layer "In5.Cu")
		(net 141)
	)
	(segment
		(start 89.5 74.1)
		(end 91 74.1)
		(width 0.1)
		(layer "In5.Cu")
		(net 141)
	)
	(segment
		(start 94.45 71.65)
		(end 94.7 71.4)
		(width 0.1)
		(layer "In5.Cu")
		(net 141)
	)
	(segment
		(start 88.6 73.2)
		(end 89.5 74.1)
		(width 0.1)
		(layer "In5.Cu")
		(net 141)
	)
	(segment
		(start 74.1 82.9)
		(end 74.1 80)
		(width 0.1)
		(layer "In5.Cu")
		(net 141)
	)
	(segment
		(start 75 95.949468)
		(end 75 83.8)
		(width 0.1)
		(layer "In5.Cu")
		(net 141)
	)
	(segment
		(start 91.3 72.8)
		(end 92.45 71.65)
		(width 0.1)
		(layer "In5.Cu")
		(net 141)
	)
	(segment
		(start 94.7 71.4)
		(end 96.5 71.4)
		(width 0.1)
		(layer "In5.Cu")
		(net 141)
	)
	(segment
		(start 79.8 79.4)
		(end 86 73.2)
		(width 0.1)
		(layer "In5.Cu")
		(net 141)
	)
	(segment
		(start 96.5 71.4)
		(end 96.9 71)
		(width 0.1)
		(layer "In5.Cu")
		(net 141)
	)
	(segment
		(start 75 83.8)
		(end 74.1 82.9)
		(width 0.1)
		(layer "In5.Cu")
		(net 141)
	)
	(segment
		(start 92.45 71.65)
		(end 94.45 71.65)
		(width 0.1)
		(layer "In5.Cu")
		(net 141)
	)
	(segment
		(start 74.1 80)
		(end 74.7 79.4)
		(width 0.1)
		(layer "In5.Cu")
		(net 141)
	)
	(segment
		(start 91.3 73.8)
		(end 91.3 72.8)
		(width 0.1)
		(layer "In5.Cu")
		(net 141)
	)
	(segment
		(start 86 73.2)
		(end 88.6 73.2)
		(width 0.1)
		(layer "In5.Cu")
		(net 141)
	)
	(segment
		(start 91 74.1)
		(end 91.3 73.8)
		(width 0.1)
		(layer "In5.Cu")
		(net 141)
	)
	(segment
		(start 81.3 101.42482)
		(end 81.3 101.48482)
		(width 0.1)
		(layer "F.Cu")
		(net 142)
	)
	(segment
		(start 80.646006 103.62482)
		(end 80.646006 103.68482)
		(width 0.1)
		(layer "F.Cu")
		(net 142)
	)
	(segment
		(start 80.646006 101.72482)
		(end 80.646006 101.78482)
		(width 0.1)
		(layer "F.Cu")
		(net 142)
	)
	(segment
		(start 81.3 102.02482)
		(end 81.3 102.08482)
		(width 0.1)
		(layer "F.Cu")
		(net 142)
	)
	(segment
		(start 81.18 101.00482)
		(end 80.616003 101.00482)
		(width 0.1)
		(layer "F.Cu")
		(net 142)
	)
	(segment
		(start 121.5 78.75)
		(end 121.75 78.75)
		(width 0.1)
		(layer "F.Cu")
		(net 142)
	)
	(segment
		(start 81.3 105.82482)
		(end 81.3 105.88482)
		(width 0.1)
		(layer "F.Cu")
		(net 142)
	)
	(segment
		(start 85.85 112.2)
		(end 86.45 112.8)
		(width 0.1)
		(layer "F.Cu")
		(net 142)
	)
	(segment
		(start 120.425 80.375)
		(end 120.7 80.1)
		(width 0.1)
		(layer "F.Cu")
		(net 142)
	)
	(segment
		(start 75.425736 92.399998)
		(end 75.925736 92.399998)
		(width 0.1)
		(layer "F.Cu")
		(net 142)
	)
	(segment
		(start 81.18 105.40482)
		(end 80.766006 105.40482)
		(width 0.1)
		(layer "F.Cu")
		(net 142)
	)
	(segment
		(start 80.765991 102.50482)
		(end 81.18 102.50482)
		(width 0.1)
		(layer "F.Cu")
		(net 142)
	)
	(segment
		(start 81.3 100.82482)
		(end 81.3 100.88482)
		(width 0.1)
		(layer "F.Cu")
		(net 142)
	)
	(segment
		(start 81.3 103.92482)
		(end 81.3 103.98482)
		(width 0.1)
		(layer "F.Cu")
		(net 142)
	)
	(segment
		(start 121.75 78.75)
		(end 121.830532 78.669468)
		(width 0.1)
		(layer "F.Cu")
		(net 142)
	)
	(segment
		(start 81.3 107.68482)
		(end 81.3 109.750001)
		(width 0.1)
		(layer "F.Cu")
		(net 142)
	)
	(segment
		(start 80.465997 100.10482)
		(end 81.18 100.10482)
		(width 0.1)
		(layer "F.Cu")
		(net 142)
	)
	(segment
		(start 81.18 104.80482)
		(end 80.766006 104.80482)
		(width 0.1)
		(layer "F.Cu")
		(net 142)
	)
	(segment
		(start 80.766006 105.70482)
		(end 81.18 105.70482)
		(width 0.1)
		(layer "F.Cu")
		(net 142)
	)
	(segment
		(start 122.430532 77.119468)
		(end 122.430532 76.65)
		(width 0.1)
		(layer "F.Cu")
		(net 142)
	)
	(segment
		(start 85.85 110.9)
		(end 85.85 111.035535)
		(width 0.1)
		(layer "F.Cu")
		(net 142)
	)
	(segment
		(start 85.15 110.2)
		(end 85.85 110.9)
		(width 0.1)
		(layer "F.Cu")
		(net 142)
	)
	(segment
		(start 121.830532 77.719468)
		(end 122.430532 77.119468)
		(width 0.1)
		(layer "F.Cu")
		(net 142)
	)
	(segment
		(start 85.85 111.035535)
		(end 85.85 112.2)
		(width 0.1)
		(layer "F.Cu")
		(net 142)
	)
	(segment
		(start 81.3 103.03482)
		(end 81.3 103.38482)
		(width 0.1)
		(layer "F.Cu")
		(net 142)
	)
	(segment
		(start 81.3 105.22482)
		(end 81.3 105.28482)
		(width 0.1)
		(layer "F.Cu")
		(net 142)
	)
	(segment
		(start 81.18 107.20482)
		(end 80.766006 107.20482)
		(width 0.1)
		(layer "F.Cu")
		(net 142)
	)
	(segment
		(start 81.18 99.80482)
		(end 80.465997 99.80482)
		(width 0.1)
		(layer "F.Cu")
		(net 142)
	)
	(segment
		(start 81.3 102.68482)
		(end 81.3 103.03482)
		(width 0.1)
		(layer "F.Cu")
		(net 142)
	)
	(segment
		(start 80.766006 107.50482)
		(end 81.18 107.50482)
		(width 0.1)
		(layer "F.Cu")
		(net 142)
	)
	(segment
		(start 80.646006 107.32482)
		(end 80.646006 107.38482)
		(width 0.1)
		(layer "F.Cu")
		(net 142)
	)
	(segment
		(start 76.300002 92.774264)
		(end 76.300002 97.400002)
		(width 0.1)
		(layer "F.Cu")
		(net 142)
	)
	(segment
		(start 81.3 102.62482)
		(end 81.3 102.68482)
		(width 0.1)
		(layer "F.Cu")
		(net 142)
	)
	(segment
		(start 80.766006 106.90482)
		(end 81.18 106.90482)
		(width 0.1)
		(layer "F.Cu")
		(net 142)
	)
	(segment
		(start 75.000002 88.050002)
		(end 75.000002 91.974264)
		(width 0.1)
		(layer "F.Cu")
		(net 142)
	)
	(segment
		(start 81.3 106.42482)
		(end 81.3 106.48482)
		(width 0.1)
		(layer "F.Cu")
		(net 142)
	)
	(segment
		(start 80.496003 101.12482)
		(end 80.496003 101.18482)
		(width 0.1)
		(layer "F.Cu")
		(net 142)
	)
	(segment
		(start 81.749999 110.2)
		(end 85.15 110.2)
		(width 0.1)
		(layer "F.Cu")
		(net 142)
	)
	(segment
		(start 80.646006 106.72482)
		(end 80.646006 106.78482)
		(width 0.1)
		(layer "F.Cu")
		(net 142)
	)
	(segment
		(start 81.1 98.75)
		(end 81.3 98.95)
		(width 0.1)
		(layer "F.Cu")
		(net 142)
	)
	(segment
		(start 81.3 104.33482)
		(end 81.3 104.68482)
		(width 0.1)
		(layer "F.Cu")
		(net 142)
	)
	(segment
		(start 81.3 98.95)
		(end 81.3 99.68482)
		(width 0.1)
		(layer "F.Cu")
		(net 142)
	)
	(segment
		(start 120.7 79.55)
		(end 121.5 78.75)
		(width 0.1)
		(layer "F.Cu")
		(net 142)
	)
	(segment
		(start 81.3 107.62482)
		(end 81.3 107.68482)
		(width 0.1)
		(layer "F.Cu")
		(net 142)
	)
	(segment
		(start 80.766006 101.90482)
		(end 81.18 101.90482)
		(width 0.1)
		(layer "F.Cu")
		(net 142)
	)
	(segment
		(start 81.18 102.20482)
		(end 80.765991 102.20482)
		(width 0.1)
		(layer "F.Cu")
		(net 142)
	)
	(segment
		(start 81.3 109.750001)
		(end 81.749999 110.2)
		(width 0.1)
		(layer "F.Cu")
		(net 142)
	)
	(segment
		(start 81.18 101.60482)
		(end 80.766006 101.60482)
		(width 0.1)
		(layer "F.Cu")
		(net 142)
	)
	(segment
		(start 118.325 80.375)
		(end 120.425 80.375)
		(width 0.1)
		(layer "F.Cu")
		(net 142)
	)
	(segment
		(start 81.3 107.02482)
		(end 81.3 107.08482)
		(width 0.1)
		(layer "F.Cu")
		(net 142)
	)
	(segment
		(start 80.465997 100.70482)
		(end 81.18 100.70482)
		(width 0.1)
		(layer "F.Cu")
		(net 142)
	)
	(segment
		(start 80.646006 104.92482)
		(end 80.646006 104.98482)
		(width 0.1)
		(layer "F.Cu")
		(net 142)
	)
	(segment
		(start 80.766006 105.10482)
		(end 81.18 105.10482)
		(width 0.1)
		(layer "F.Cu")
		(net 142)
	)
	(segment
		(start 80.646006 105.52482)
		(end 80.646006 105.58482)
		(width 0.1)
		(layer "F.Cu")
		(net 142)
	)
	(segment
		(start 81.18 100.40482)
		(end 80.465997 100.40482)
		(width 0.1)
		(layer "F.Cu")
		(net 142)
	)
	(segment
		(start 80.766006 106.30482)
		(end 81.18 106.30482)
		(width 0.1)
		(layer "F.Cu")
		(net 142)
	)
	(segment
		(start 80.645991 102.32482)
		(end 80.645991 102.38482)
		(width 0.1)
		(layer "F.Cu")
		(net 142)
	)
	(segment
		(start 81.3 100.22482)
		(end 81.3 100.28482)
		(width 0.1)
		(layer "F.Cu")
		(net 142)
	)
	(segment
		(start 75.925736 92.399998)
		(end 76.300002 92.774264)
		(width 0.1)
		(layer "F.Cu")
		(net 142)
	)
	(segment
		(start 86.45 112.8)
		(end 86.8 112.8)
		(width 0.1)
		(layer "F.Cu")
		(net 142)
	)
	(segment
		(start 75.000002 91.974264)
		(end 75.425736 92.399998)
		(width 0.1)
		(layer "F.Cu")
		(net 142)
	)
	(segment
		(start 80.345997 100.52482)
		(end 80.345997 100.58482)
		(width 0.1)
		(layer "F.Cu")
		(net 142)
	)
	(segment
		(start 80.766006 103.80482)
		(end 81.18 103.80482)
		(width 0.1)
		(layer "F.Cu")
		(net 142)
	)
	(segment
		(start 80.646006 106.12482)
		(end 80.646006 106.18482)
		(width 0.1)
		(layer "F.Cu")
		(net 142)
	)
	(segment
		(start 80.345997 99.92482)
		(end 80.345997 99.98482)
		(width 0.1)
		(layer "F.Cu")
		(net 142)
	)
	(segment
		(start 76.300002 97.400002)
		(end 77.65 98.75)
		(width 0.1)
		(layer "F.Cu")
		(net 142)
	)
	(segment
		(start 80.616003 101.30482)
		(end 81.18 101.30482)
		(width 0.1)
		(layer "F.Cu")
		(net 142)
	)
	(segment
		(start 77.65 98.75)
		(end 81.1 98.75)
		(width 0.1)
		(layer "F.Cu")
		(net 142)
	)
	(segment
		(start 81.18 106.60482)
		(end 80.766006 106.60482)
		(width 0.1)
		(layer "F.Cu")
		(net 142)
	)
	(segment
		(start 81.18 106.00482)
		(end 80.766006 106.00482)
		(width 0.1)
		(layer "F.Cu")
		(net 142)
	)
	(segment
		(start 74.775 87.825)
		(end 75.000002 88.050002)
		(width 0.1)
		(layer "F.Cu")
		(net 142)
	)
	(segment
		(start 121.830532 78.669468)
		(end 121.830532 77.719468)
		(width 0.1)
		(layer "F.Cu")
		(net 142)
	)
	(segment
		(start 81.18 103.50482)
		(end 80.766006 103.50482)
		(width 0.1)
		(layer "F.Cu")
		(net 142)
	)
	(segment
		(start 74.5 87.825)
		(end 74.775 87.825)
		(width 0.1)
		(layer "F.Cu")
		(net 142)
	)
	(segment
		(start 81.3 103.98482)
		(end 81.3 104.33482)
		(width 0.1)
		(layer "F.Cu")
		(net 142)
	)
	(segment
		(start 120.7 80.1)
		(end 120.7 79.55)
		(width 0.1)
		(layer "F.Cu")
		(net 142)
	)
	(via
		(at 118.325 80.375)
		(size 0.45)
		(drill 0.1)
		(layers "F.Cu" "B.Cu")
		(net 142)
	)
	(via
		(at 74.5 87.825)
		(size 0.45)
		(drill 0.1)
		(layers "F.Cu" "B.Cu")
		(net 142)
	)
	(via
		(at 86.8 112.8)
		(size 0.45)
		(drill 0.1)
		(layers "F.Cu" "B.Cu")
		(net 142)
	)
	(arc
		(start 81.18 100.70482)
		(mid 81.264853 100.739967)
		(end 81.3 100.82482)
		(width 0.1)
		(layer "F.Cu")
		(net 142)
	)
	(arc
		(start 81.3 105.28482)
		(mid 81.264853 105.369673)
		(end 81.18 105.40482)
		(width 0.1)
		(layer "F.Cu")
		(net 142)
	)
	(arc
		(start 80.766006 106.60482)
		(mid 80.681153 106.639967)
		(end 80.646006 106.72482)
		(width 0.1)
		(layer "F.Cu")
		(net 142)
	)
	(arc
		(start 81.18 100.10482)
		(mid 81.264853 100.139967)
		(end 81.3 100.22482)
		(width 0.1)
		(layer "F.Cu")
		(net 142)
	)
	(arc
		(start 80.465997 100.40482)
		(mid 80.381144 100.439967)
		(end 80.345997 100.52482)
		(width 0.1)
		(layer "F.Cu")
		(net 142)
	)
	(arc
		(start 81.18 103.80482)
		(mid 81.264853 103.839967)
		(end 81.3 103.92482)
		(width 0.1)
		(layer "F.Cu")
		(net 142)
	)
	(arc
		(start 81.18 105.10482)
		(mid 81.264853 105.139967)
		(end 81.3 105.22482)
		(width 0.1)
		(layer "F.Cu")
		(net 142)
	)
	(arc
		(start 81.3 103.38482)
		(mid 81.264853 103.469673)
		(end 81.18 103.50482)
		(width 0.1)
		(layer "F.Cu")
		(net 142)
	)
	(arc
		(start 80.765991 102.20482)
		(mid 80.681138 102.239967)
		(end 80.645991 102.32482)
		(width 0.1)
		(layer "F.Cu")
		(net 142)
	)
	(arc
		(start 80.465997 99.80482)
		(mid 80.381144 99.839967)
		(end 80.345997 99.92482)
		(width 0.1)
		(layer "F.Cu")
		(net 142)
	)
	(arc
		(start 80.646006 104.98482)
		(mid 80.681153 105.069673)
		(end 80.766006 105.10482)
		(width 0.1)
		(layer "F.Cu")
		(net 142)
	)
	(arc
		(start 80.645991 102.38482)
		(mid 80.681138 102.469673)
		(end 80.765991 102.50482)
		(width 0.1)
		(layer "F.Cu")
		(net 142)
	)
	(arc
		(start 81.3 100.88482)
		(mid 81.264853 100.969673)
		(end 81.18 101.00482)
		(width 0.1)
		(layer "F.Cu")
		(net 142)
	)
	(arc
		(start 80.766006 103.50482)
		(mid 80.681153 103.539967)
		(end 80.646006 103.62482)
		(width 0.1)
		(layer "F.Cu")
		(net 142)
	)
	(arc
		(start 81.3 104.68482)
		(mid 81.264853 104.769673)
		(end 81.18 104.80482)
		(width 0.1)
		(layer "F.Cu")
		(net 142)
	)
	(arc
		(start 81.18 105.70482)
		(mid 81.264853 105.739967)
		(end 81.3 105.82482)
		(width 0.1)
		(layer "F.Cu")
		(net 142)
	)
	(arc
		(start 81.3 100.28482)
		(mid 81.264853 100.369673)
		(end 81.18 100.40482)
		(width 0.1)
		(layer "F.Cu")
		(net 142)
	)
	(arc
		(start 81.3 102.08482)
		(mid 81.264853 102.169673)
		(end 81.18 102.20482)
		(width 0.1)
		(layer "F.Cu")
		(net 142)
	)
	(arc
		(start 80.766006 105.40482)
		(mid 80.681153 105.439967)
		(end 80.646006 105.52482)
		(width 0.1)
		(layer "F.Cu")
		(net 142)
	)
	(arc
		(start 80.646006 105.58482)
		(mid 80.681153 105.669673)
		(end 80.766006 105.70482)
		(width 0.1)
		(layer "F.Cu")
		(net 142)
	)
	(arc
		(start 81.3 101.48482)
		(mid 81.264853 101.569673)
		(end 81.18 101.60482)
		(width 0.1)
		(layer "F.Cu")
		(net 142)
	)
	(arc
		(start 81.3 106.48482)
		(mid 81.264853 106.569673)
		(end 81.18 106.60482)
		(width 0.1)
		(layer "F.Cu")
		(net 142)
	)
	(arc
		(start 80.616003 101.00482)
		(mid 80.53115 101.039967)
		(end 80.496003 101.12482)
		(width 0.1)
		(layer "F.Cu")
		(net 142)
	)
	(arc
		(start 81.18 106.30482)
		(mid 81.264853 106.339967)
		(end 81.3 106.42482)
		(width 0.1)
		(layer "F.Cu")
		(net 142)
	)
	(arc
		(start 81.18 106.90482)
		(mid 81.264853 106.939967)
		(end 81.3 107.02482)
		(width 0.1)
		(layer "F.Cu")
		(net 142)
	)
	(arc
		(start 80.345997 99.98482)
		(mid 80.381144 100.069673)
		(end 80.465997 100.10482)
		(width 0.1)
		(layer "F.Cu")
		(net 142)
	)
	(arc
		(start 80.766006 101.60482)
		(mid 80.681153 101.639967)
		(end 80.646006 101.72482)
		(width 0.1)
		(layer "F.Cu")
		(net 142)
	)
	(arc
		(start 80.646006 107.38482)
		(mid 80.681153 107.469673)
		(end 80.766006 107.50482)
		(width 0.1)
		(layer "F.Cu")
		(net 142)
	)
	(arc
		(start 80.496003 101.18482)
		(mid 80.53115 101.269673)
		(end 80.616003 101.30482)
		(width 0.1)
		(layer "F.Cu")
		(net 142)
	)
	(arc
		(start 80.345997 100.58482)
		(mid 80.381144 100.669673)
		(end 80.465997 100.70482)
		(width 0.1)
		(layer "F.Cu")
		(net 142)
	)
	(arc
		(start 80.646006 106.78482)
		(mid 80.681153 106.869673)
		(end 80.766006 106.90482)
		(width 0.1)
		(layer "F.Cu")
		(net 142)
	)
	(arc
		(start 81.18 102.50482)
		(mid 81.264853 102.539967)
		(end 81.3 102.62482)
		(width 0.1)
		(layer "F.Cu")
		(net 142)
	)
	(arc
		(start 81.18 101.30482)
		(mid 81.264853 101.339967)
		(end 81.3 101.42482)
		(width 0.1)
		(layer "F.Cu")
		(net 142)
	)
	(arc
		(start 81.3 105.88482)
		(mid 81.264853 105.969673)
		(end 81.18 106.00482)
		(width 0.1)
		(layer "F.Cu")
		(net 142)
	)
	(arc
		(start 80.766006 107.20482)
		(mid 80.681153 107.239967)
		(end 80.646006 107.32482)
		(width 0.1)
		(layer "F.Cu")
		(net 142)
	)
	(arc
		(start 80.766006 104.80482)
		(mid 80.681153 104.839967)
		(end 80.646006 104.92482)
		(width 0.1)
		(layer "F.Cu")
		(net 142)
	)
	(arc
		(start 80.646006 103.68482)
		(mid 80.681153 103.769673)
		(end 80.766006 103.80482)
		(width 0.1)
		(layer "F.Cu")
		(net 142)
	)
	(arc
		(start 80.646006 106.18482)
		(mid 80.681153 106.269673)
		(end 80.766006 106.30482)
		(width 0.1)
		(layer "F.Cu")
		(net 142)
	)
	(arc
		(start 81.3 107.08482)
		(mid 81.264853 107.169673)
		(end 81.18 107.20482)
		(width 0.1)
		(layer "F.Cu")
		(net 142)
	)
	(arc
		(start 81.18 101.90482)
		(mid 81.264853 101.939967)
		(end 81.3 102.02482)
		(width 0.1)
		(layer "F.Cu")
		(net 142)
	)
	(arc
		(start 81.3 99.68482)
		(mid 81.264853 99.769673)
		(end 81.18 99.80482)
		(width 0.1)
		(layer "F.Cu")
		(net 142)
	)
	(arc
		(start 81.18 107.50482)
		(mid 81.264853 107.539967)
		(end 81.3 107.62482)
		(width 0.1)
		(layer "F.Cu")
		(net 142)
	)
	(arc
		(start 80.646006 101.78482)
		(mid 80.681153 101.869673)
		(end 80.766006 101.90482)
		(width 0.1)
		(layer "F.Cu")
		(net 142)
	)
	(arc
		(start 80.766006 106.00482)
		(mid 80.681153 106.039967)
		(end 80.646006 106.12482)
		(width 0.1)
		(layer "F.Cu")
		(net 142)
	)
	(segment
		(start 117.125 81.05)
		(end 116.25 81.05)
		(width 0.1)
		(layer "In5.Cu")
		(net 142)
	)
	(segment
		(start 96.300001 102.851473)
		(end 96.300001 109.375733)
		(width 0.1)
		(layer "In5.Cu")
		(net 142)
	)
	(segment
		(start 98.6 100.551474)
		(end 96.300001 102.851473)
		(width 0.1)
		(layer "In5.Cu")
		(net 142)
	)
	(segment
		(start 87.15 112.8)
		(end 86.8 112.8)
		(width 0.1)
		(layer "In5.Cu")
		(net 142)
	)
	(segment
		(start 95.937867 109.737867)
		(end 95.937867 110.971231)
		(width 0.1)
		(layer "In5.Cu")
		(net 142)
	)
	(segment
		(start 118.325 80.375)
		(end 117.8 80.375)
		(width 0.1)
		(layer "In5.Cu")
		(net 142)
	)
	(segment
		(start 95.937867 110.971231)
		(end 93.134467 113.774631)
		(width 0.1)
		(layer "In5.Cu")
		(net 142)
	)
	(segment
		(start 102.798839 93.902635)
		(end 99.598839 93.902635)
		(width 0.1)
		(layer "In5.Cu")
		(net 142)
	)
	(segment
		(start 90.365533 112.774631)
		(end 87.175369 112.774631)
		(width 0.1)
		(layer "In5.Cu")
		(net 142)
	)
	(segment
		(start 91.365533 113.774631)
		(end 90.365533 112.774631)
		(width 0.1)
		(layer "In5.Cu")
		(net 142)
	)
	(segment
		(start 117.8 80.375)
		(end 117.125 81.05)
		(width 0.1)
		(layer "In5.Cu")
		(net 142)
	)
	(segment
		(start 93.134467 113.774631)
		(end 91.365533 113.774631)
		(width 0.1)
		(layer "In5.Cu")
		(net 142)
	)
	(segment
		(start 96.300001 109.375733)
		(end 95.937867 109.737867)
		(width 0.1)
		(layer "In5.Cu")
		(net 142)
	)
	(segment
		(start 116.25 81.05)
		(end 113.85 83.45)
		(width 0.1)
		(layer "In5.Cu")
		(net 142)
	)
	(segment
		(start 87.175369 112.774631)
		(end 87.15 112.8)
		(width 0.1)
		(layer "In5.Cu")
		(net 142)
	)
	(segment
		(start 99.598839 93.902635)
		(end 98.6 94.901474)
		(width 0.1)
		(layer "In5.Cu")
		(net 142)
	)
	(segment
		(start 113.251474 83.45)
		(end 102.798839 93.902635)
		(width 0.1)
		(layer "In5.Cu")
		(net 142)
	)
	(segment
		(start 98.6 94.901474)
		(end 98.6 100.551474)
		(width 0.1)
		(layer "In5.Cu")
		(net 142)
	)
	(segment
		(start 113.85 83.45)
		(end 113.251474 83.45)
		(width 0.1)
		(layer "In5.Cu")
		(net 142)
	)
	(segment
		(start 126.030532 73.65)
		(end 125.755532 73.925)
		(width 0.17)
		(layer "F.Cu")
		(net 143)
	)
	(segment
		(start 125.755532 74.175)
		(end 125.880532 74.3)
		(width 0.17)
		(layer "F.Cu")
		(net 143)
	)
	(segment
		(start 125.755532 73.925)
		(end 125.755532 74.175)
		(width 0.17)
		(layer "F.Cu")
		(net 143)
	)
	(via
		(at 125.880532 74.3)
		(size 0.45)
		(drill 0.1)
		(layers "F.Cu" "B.Cu")
		(net 143)
	)
	(via
		(at 60.9125 105.2)
		(size 0.45)
		(drill 0.1)
		(layers "F.Cu" "B.Cu")
		(net 143)
	)
	(segment
		(start 63.614999 106.885)
		(end 61.837512 106.885)
		(width 0.17)
		(layer "B.Cu")
		(net 143)
	)
	(segment
		(start 61.837512 106.885)
		(end 61.025 106.072488)
		(width 0.17)
		(layer "B.Cu")
		(net 143)
	)
	(segment
		(start 63.689999 106.96)
		(end 63.614999 106.885)
		(width 0.17)
		(layer "B.Cu")
		(net 143)
	)
	(segment
		(start 61.025 106.072488)
		(end 61.025 105.3125)
		(width 0.17)
		(layer "B.Cu")
		(net 143)
	)
	(segment
		(start 64.59 106.96)
		(end 63.689999 106.96)
		(width 0.17)
		(layer "B.Cu")
		(net 143)
	)
	(segment
		(start 61.025 105.3125)
		(end 60.9125 105.2)
		(width 0.17)
		(layer "B.Cu")
		(net 143)
	)
	(segment
		(start 91.8775 71.764946)
		(end 91.8775 71.235054)
		(width 0.125)
		(layer "In2.Cu")
		(net 143)
	)
	(segment
		(start 90.56 70.452554)
		(end 90.67 70.452554)
		(width 0.125)
		(layer "In2.Cu")
		(net 143)
	)
	(segment
		(start 94.0775 71.914936)
		(end 94.0775 70.785054)
		(width 0.125)
		(layer "In2.Cu")
		(net 143)
	)
	(segment
		(start 86.0034 71.3875)
		(end 89.02 71.3875)
		(width 0.125)
		(layer "In2.Cu")
		(net 143)
	)
	(segment
		(start 114.7775 70.2534)
		(end 115.2434 69.7875)
		(width 0.125)
		(layer "In2.Cu")
		(net 143)
	)
	(segment
		(start 90.01 72.472447)
		(end 90.12 72.472447)
		(width 0.125)
		(layer "In2.Cu")
		(net 143)
	)
	(segment
		(start 94.96 71.3875)
		(end 114.4434 71.3875)
		(width 0.125)
		(layer "In2.Cu")
		(net 143)
	)
	(segment
		(start 89.9025 70.785054)
		(end 89.9025 72.364947)
		(width 0.125)
		(layer "In2.Cu")
		(net 143)
	)
	(segment
		(start 119.5375 71.3875)
		(end 120.0466 71.3875)
		(width 0.125)
		(layer "In2.Cu")
		(net 143)
	)
	(segment
		(start 61.087499 105.025001)
		(end 61.087499 85.453401)
		(width 0.125)
		(layer "In2.Cu")
		(net 143)
	)
	(segment
		(start 125.693033 73.333933)
		(end 125.693033 74.112501)
		(width 0.125)
		(layer "In2.Cu")
		(net 143)
	)
	(segment
		(start 61.087499 85.453401)
		(end 68.7534 77.7875)
		(width 0.125)
		(layer "In2.Cu")
		(net 143)
	)
	(segment
		(start 93.7525 70.785054)
		(end 93.7525 71.914936)
		(width 0.125)
		(layer "In2.Cu")
		(net 143)
	)
	(segment
		(start 121.4466 72.7875)
		(end 125.1466 72.7875)
		(width 0.125)
		(layer "In2.Cu")
		(net 143)
	)
	(segment
		(start 79.6034 77.7875)
		(end 86.0034 71.3875)
		(width 0.125)
		(layer "In2.Cu")
		(net 143)
	)
	(segment
		(start 90.2275 72.364947)
		(end 90.2275 70.785054)
		(width 0.125)
		(layer "In2.Cu")
		(net 143)
	)
	(segment
		(start 125.1466 72.7875)
		(end 125.693033 73.333933)
		(width 0.125)
		(layer "In2.Cu")
		(net 143)
	)
	(segment
		(start 91.66 71.872446)
		(end 91.77 71.872446)
		(width 0.125)
		(layer "In2.Cu")
		(net 143)
	)
	(segment
		(start 117.9375 69.7875)
		(end 119.5375 71.3875)
		(width 0.125)
		(layer "In2.Cu")
		(net 143)
	)
	(segment
		(start 91.5525 71.72)
		(end 91.5525 71.764946)
		(width 0.125)
		(layer "In2.Cu")
		(net 143)
	)
	(segment
		(start 92.9775 71.28)
		(end 92.9775 70.785054)
		(width 0.125)
		(layer "In2.Cu")
		(net 143)
	)
	(segment
		(start 93.86 72.022436)
		(end 93.97 72.022436)
		(width 0.125)
		(layer "In2.Cu")
		(net 143)
	)
	(segment
		(start 115.2434 69.7875)
		(end 117.9375 69.7875)
		(width 0.125)
		(layer "In2.Cu")
		(net 143)
	)
	(segment
		(start 60.9125 105.2)
		(end 61.087499 105.025001)
		(width 0.125)
		(layer "In2.Cu")
		(net 143)
	)
	(segment
		(start 120.0466 71.3875)
		(end 121.4466 72.7875)
		(width 0.125)
		(layer "In2.Cu")
		(net 143)
	)
	(segment
		(start 125.693033 74.112501)
		(end 125.880532 74.3)
		(width 0.125)
		(layer "In2.Cu")
		(net 143)
	)
	(segment
		(start 91.11 71.3875)
		(end 91.22 71.3875)
		(width 0.125)
		(layer "In2.Cu")
		(net 143)
	)
	(segment
		(start 114.4434 71.3875)
		(end 114.7775 71.0534)
		(width 0.125)
		(layer "In2.Cu")
		(net 143)
	)
	(segment
		(start 92.6525 71.235054)
		(end 92.6525 71.28)
		(width 0.125)
		(layer "In2.Cu")
		(net 143)
	)
	(segment
		(start 68.7534 77.7875)
		(end 79.6034 77.7875)
		(width 0.125)
		(layer "In2.Cu")
		(net 143)
	)
	(segment
		(start 89.1275 71.28)
		(end 89.1275 70.785054)
		(width 0.125)
		(layer "In2.Cu")
		(net 143)
	)
	(segment
		(start 94.41 70.452554)
		(end 94.52 70.452554)
		(width 0.125)
		(layer "In2.Cu")
		(net 143)
	)
	(segment
		(start 114.7775 71.0534)
		(end 114.7775 70.2534)
		(width 0.125)
		(layer "In2.Cu")
		(net 143)
	)
	(segment
		(start 89.46 70.452554)
		(end 89.57 70.452554)
		(width 0.125)
		(layer "In2.Cu")
		(net 143)
	)
	(segment
		(start 94.8525 70.785054)
		(end 94.8525 71.28)
		(width 0.125)
		(layer "In2.Cu")
		(net 143)
	)
	(segment
		(start 92.76 71.3875)
		(end 92.87 71.3875)
		(width 0.125)
		(layer "In2.Cu")
		(net 143)
	)
	(segment
		(start 93.31 70.452554)
		(end 93.42 70.452554)
		(width 0.125)
		(layer "In2.Cu")
		(net 143)
	)
	(segment
		(start 91.0025 70.785054)
		(end 91.0025 71.28)
		(width 0.125)
		(layer "In2.Cu")
		(net 143)
	)
	(segment
		(start 92.21 70.902554)
		(end 92.32 70.902554)
		(width 0.125)
		(layer "In2.Cu")
		(net 143)
	)
	(arc
		(start 94.0775 70.785054)
		(mid 94.174887 70.549941)
		(end 94.41 70.452554)
		(width 0.125)
		(layer "In2.Cu")
		(net 143)
	)
	(arc
		(start 91.22 71.3875)
		(mid 91.455113 71.484887)
		(end 91.5525 71.72)
		(width 0.125)
		(layer "In2.Cu")
		(net 143)
	)
	(arc
		(start 89.1275 70.785054)
		(mid 89.224887 70.549941)
		(end 89.46 70.452554)
		(width 0.125)
		(layer "In2.Cu")
		(net 143)
	)
	(arc
		(start 90.12 72.472447)
		(mid 90.196014 72.440961)
		(end 90.2275 72.364947)
		(width 0.125)
		(layer "In2.Cu")
		(net 143)
	)
	(arc
		(start 93.42 70.452554)
		(mid 93.655113 70.549941)
		(end 93.7525 70.785054)
		(width 0.125)
		(layer "In2.Cu")
		(net 143)
	)
	(arc
		(start 90.67 70.452554)
		(mid 90.905113 70.549941)
		(end 91.0025 70.785054)
		(width 0.125)
		(layer "In2.Cu")
		(net 143)
	)
	(arc
		(start 89.02 71.3875)
		(mid 89.096014 71.356014)
		(end 89.1275 71.28)
		(width 0.125)
		(layer "In2.Cu")
		(net 143)
	)
	(arc
		(start 89.9025 72.364947)
		(mid 89.933986 72.440961)
		(end 90.01 72.472447)
		(width 0.125)
		(layer "In2.Cu")
		(net 143)
	)
	(arc
		(start 93.7525 71.914936)
		(mid 93.783986 71.99095)
		(end 93.86 72.022436)
		(width 0.125)
		(layer "In2.Cu")
		(net 143)
	)
	(arc
		(start 92.87 71.3875)
		(mid 92.946014 71.356014)
		(end 92.9775 71.28)
		(width 0.125)
		(layer "In2.Cu")
		(net 143)
	)
	(arc
		(start 92.9775 70.785054)
		(mid 93.074887 70.549941)
		(end 93.31 70.452554)
		(width 0.125)
		(layer "In2.Cu")
		(net 143)
	)
	(arc
		(start 92.32 70.902554)
		(mid 92.555113 70.999941)
		(end 92.6525 71.235054)
		(width 0.125)
		(layer "In2.Cu")
		(net 143)
	)
	(arc
		(start 94.8525 71.28)
		(mid 94.883986 71.356014)
		(end 94.96 71.3875)
		(width 0.125)
		(layer "In2.Cu")
		(net 143)
	)
	(arc
		(start 92.6525 71.28)
		(mid 92.683986 71.356014)
		(end 92.76 71.3875)
		(width 0.125)
		(layer "In2.Cu")
		(net 143)
	)
	(arc
		(start 94.52 70.452554)
		(mid 94.755113 70.549941)
		(end 94.8525 70.785054)
		(width 0.125)
		(layer "In2.Cu")
		(net 143)
	)
	(arc
		(start 89.57 70.452554)
		(mid 89.805113 70.549941)
		(end 89.9025 70.785054)
		(width 0.125)
		(layer "In2.Cu")
		(net 143)
	)
	(arc
		(start 91.77 71.872446)
		(mid 91.846014 71.84096)
		(end 91.8775 71.764946)
		(width 0.125)
		(layer "In2.Cu")
		(net 143)
	)
	(arc
		(start 93.97 72.022436)
		(mid 94.046014 71.99095)
		(end 94.0775 71.914936)
		(width 0.125)
		(layer "In2.Cu")
		(net 143)
	)
	(arc
		(start 91.0025 71.28)
		(mid 91.033986 71.356014)
		(end 91.11 71.3875)
		(width 0.125)
		(layer "In2.Cu")
		(net 143)
	)
	(arc
		(start 91.5525 71.764946)
		(mid 91.583986 71.84096)
		(end 91.66 71.872446)
		(width 0.125)
		(layer "In2.Cu")
		(net 143)
	)
	(arc
		(start 91.8775 71.235054)
		(mid 91.974887 70.999941)
		(end 92.21 70.902554)
		(width 0.125)
		(layer "In2.Cu")
		(net 143)
	)
	(arc
		(start 90.2275 70.785054)
		(mid 90.324887 70.549941)
		(end 90.56 70.452554)
		(width 0.125)
		(layer "In2.Cu")
		(net 143)
	)
	(via
		(at 131.430532 76.65)
		(size 0.45)
		(drill 0.1)
		(layers "F.Cu" "B.Cu")
		(net 144)
	)
	(via
		(at 192.2625 62.85)
		(size 0.45)
		(drill 0.1)
		(layers "F.Cu" "B.Cu")
		(net 144)
	)
	(segment
		(start 197.158 59.290001)
		(end 197.158 58.39)
		(width 0.17)
		(layer "B.Cu")
		(net 144)
	)
	(segment
		(start 194.372488 63.875)
		(end 197.083 61.164488)
		(width 0.17)
		(layer "B.Cu")
		(net 144)
	)
	(segment
		(start 192.877512 63.875)
		(end 194.372488 63.875)
		(width 0.17)
		(layer "B.Cu")
		(net 144)
	)
	(segment
		(start 192.375 63.372488)
		(end 192.877512 63.875)
		(width 0.17)
		(layer "B.Cu")
		(net 144)
	)
	(segment
		(start 197.083 61.164488)
		(end 197.083 59.365001)
		(width 0.17)
		(layer "B.Cu")
		(net 144)
	)
	(segment
		(start 192.375 62.9625)
		(end 192.375 63.372488)
		(width 0.17)
		(layer "B.Cu")
		(net 144)
	)
	(segment
		(start 197.083 59.365001)
		(end 197.158 59.290001)
		(width 0.17)
		(layer "B.Cu")
		(net 144)
	)
	(segment
		(start 192.2625 62.85)
		(end 192.375 62.9625)
		(width 0.17)
		(layer "B.Cu")
		(net 144)
	)
	(segment
		(start 160.975729 77.5125)
		(end 160.975729 77.2875)
		(width 0.125)
		(layer "In2.Cu")
		(net 144)
	)
	(segment
		(start 156.575729 77.18)
		(end 156.575729 77.143206)
		(width 0.125)
		(layer "In2.Cu")
		(net 144)
	)
	(segment
		(start 157.675729 77.18)
		(end 157.675729 77.143206)
		(width 0.125)
		(layer "In2.Cu")
		(net 144)
	)
	(segment
		(start 159.550729 77.188416)
		(end 159.550729 77.2875)
		(width 0.125)
		(layer "In2.Cu")
		(net 144)
	)
	(segment
		(start 154.050729 76.693204)
		(end 154.050729 77.18)
		(width 0.125)
		(layer "In2.Cu")
		(net 144)
	)
	(segment
		(start 156.358229 78.014296)
		(end 156.468229 78.014296)
		(width 0.125)
		(layer "In2.Cu")
		(net 144)
	)
	(segment
		(start 159.658229 78.014271)
		(end 159.768229 78.014271)
		(width 0.125)
		(layer "In2.Cu")
		(net 144)
	)
	(segment
		(start 154.050729 77.5125)
		(end 154.050729 77.906796)
		(width 0.125)
		(layer "In2.Cu")
		(net 144)
	)
	(segment
		(start 155.258229 78.014296)
		(end 155.368229 78.014296)
		(width 0.125)
		(layer "In2.Cu")
		(net 144)
	)
	(segment
		(start 154.375729 77.5125)
		(end 154.375729 77.2875)
		(width 0.125)
		(layer "In2.Cu")
		(net 144)
	)
	(segment
		(start 160.199812 76.864333)
		(end 160.326646 76.864333)
		(width 0.125)
		(layer "In2.Cu")
		(net 144)
	)
	(segment
		(start 161.750729 77.188416)
		(end 161.750729 77.2875)
		(width 0.125)
		(layer "In2.Cu")
		(net 144)
	)
	(segment
		(start 158.775729 77.906771)
		(end 158.775729 77.5125)
		(width 0.125)
		(layer "In2.Cu")
		(net 144)
	)
	(segment
		(start 160.758229 78.014296)
		(end 160.868229 78.014296)
		(width 0.125)
		(layer "In2.Cu")
		(net 144)
	)
	(segment
		(start 158.450729 77.18)
		(end 158.450729 77.5125)
		(width 0.125)
		(layer "In2.Cu")
		(net 144)
	)
	(segment
		(start 159.099812 76.864333)
		(end 159.226646 76.864333)
		(width 0.125)
		(layer "In2.Cu")
		(net 144)
	)
	(segment
		(start 162.075729 77.5125)
		(end 162.075729 77.2875)
		(width 0.125)
		(layer "In2.Cu")
		(net 144)
	)
	(segment
		(start 192.437499 63.024999)
		(end 192.2625 62.85)
		(width 0.125)
		(layer "In2.Cu")
		(net 144)
	)
	(segment
		(start 156.908229 76.810706)
		(end 157.018229 76.810706)
		(width 0.125)
		(layer "In2.Cu")
		(net 144)
	)
	(segment
		(start 154.050729 77.18)
		(end 154.050729 77.5125)
		(width 0.125)
		(layer "In2.Cu")
		(net 144)
	)
	(segment
		(start 158.558229 78.014271)
		(end 158.668229 78.014271)
		(width 0.125)
		(layer "In2.Cu")
		(net 144)
	)
	(segment
		(start 131.093033 77.033933)
		(end 131.3466 77.2875)
		(width 0.125)
		(layer "In2.Cu")
		(net 144)
	)
	(segment
		(start 154.375729 77.906796)
		(end 154.375729 77.5125)
		(width 0.125)
		(layer "In2.Cu")
		(net 144)
	)
	(segment
		(start 163.175729 77.906771)
		(end 163.175729 77.62)
		(width 0.125)
		(layer "In2.Cu")
		(net 144)
	)
	(segment
		(start 159.875729 77.2875)
		(end 159.875729 77.188416)
		(width 0.125)
		(layer "In2.Cu")
		(net 144)
	)
	(segment
		(start 192.128401 63.562499)
		(end 192.437499 63.253401)
		(width 0.125)
		(layer "In2.Cu")
		(net 144)
	)
	(segment
		(start 162.958229 78.014271)
		(end 163.068229 78.014271)
		(width 0.125)
		(layer "In2.Cu")
		(net 144)
	)
	(segment
		(start 162.850729 77.2875)
		(end 162.850729 77.62)
		(width 0.125)
		(layer "In2.Cu")
		(net 144)
	)
	(segment
		(start 155.150729 77.62)
		(end 155.150729 77.906796)
		(width 0.125)
		(layer "In2.Cu")
		(net 144)
	)
	(segment
		(start 167.457221 75.167221)
		(end 179.061943 63.562499)
		(width 0.125)
		(layer "In2.Cu")
		(net 144)
	)
	(segment
		(start 155.475729 77.906796)
		(end 155.475729 77.62)
		(width 0.125)
		(layer "In2.Cu")
		(net 144)
	)
	(segment
		(start 154.158229 78.014296)
		(end 154.268229 78.014296)
		(width 0.125)
		(layer "In2.Cu")
		(net 144)
	)
	(segment
		(start 165.336942 77.2875)
		(end 167.457221 75.167221)
		(width 0.125)
		(layer "In2.Cu")
		(net 144)
	)
	(segment
		(start 162.075729 77.2875)
		(end 162.075729 76.693204)
		(width 0.125)
		(layer "In2.Cu")
		(net 144)
	)
	(segment
		(start 131.093033 76.987499)
		(end 131.093033 77.033933)
		(width 0.125)
		(layer "In2.Cu")
		(net 144)
	)
	(segment
		(start 131.3466 77.2875)
		(end 153.168229 77.2875)
		(width 0.125)
		(layer "In2.Cu")
		(net 144)
	)
	(segment
		(start 153.608229 76.360704)
		(end 153.718229 76.360704)
		(width 0.125)
		(layer "In2.Cu")
		(net 144)
	)
	(segment
		(start 158.450729 77.5125)
		(end 158.450729 77.906771)
		(width 0.125)
		(layer "In2.Cu")
		(net 144)
	)
	(segment
		(start 160.975729 77.2875)
		(end 160.975729 77.188416)
		(width 0.125)
		(layer "In2.Cu")
		(net 144)
	)
	(segment
		(start 159.550729 77.5125)
		(end 159.550729 77.906771)
		(width 0.125)
		(layer "In2.Cu")
		(net 144)
	)
	(segment
		(start 158.008229 76.810706)
		(end 158.118229 76.810706)
		(width 0.125)
		(layer "In2.Cu")
		(net 144)
	)
	(segment
		(start 157.458229 77.2875)
		(end 157.568229 77.2875)
		(width 0.125)
		(layer "In2.Cu")
		(net 144)
	)
	(segment
		(start 160.975729 77.906796)
		(end 160.975729 77.5125)
		(width 0.125)
		(layer "In2.Cu")
		(net 144)
	)
	(segment
		(start 153.275729 77.18)
		(end 153.275729 76.693204)
		(width 0.125)
		(layer "In2.Cu")
		(net 144)
	)
	(segment
		(start 162.850729 76.693204)
		(end 162.850729 77.2875)
		(width 0.125)
		(layer "In2.Cu")
		(net 144)
	)
	(segment
		(start 192.437499 63.253401)
		(end 192.437499 63.024999)
		(width 0.125)
		(layer "In2.Cu")
		(net 144)
	)
	(segment
		(start 157.350729 77.143206)
		(end 157.350729 77.18)
		(width 0.125)
		(layer "In2.Cu")
		(net 144)
	)
	(segment
		(start 163.508229 77.2875)
		(end 163.618229 77.2875)
		(width 0.125)
		(layer "In2.Cu")
		(net 144)
	)
	(segment
		(start 155.808229 77.2875)
		(end 155.918229 77.2875)
		(width 0.125)
		(layer "In2.Cu")
		(net 144)
	)
	(segment
		(start 159.550729 77.2875)
		(end 159.550729 77.5125)
		(width 0.125)
		(layer "In2.Cu")
		(net 144)
	)
	(segment
		(start 160.650729 77.5125)
		(end 160.650729 77.906796)
		(width 0.125)
		(layer "In2.Cu")
		(net 144)
	)
	(segment
		(start 155.150729 77.2875)
		(end 155.150729 77.62)
		(width 0.125)
		(layer "In2.Cu")
		(net 144)
	)
	(segment
		(start 161.750729 77.5125)
		(end 161.750729 77.906796)
		(width 0.125)
		(layer "In2.Cu")
		(net 144)
	)
	(segment
		(start 155.150729 76.693204)
		(end 155.150729 77.2875)
		(width 0.125)
		(layer "In2.Cu")
		(net 144)
	)
	(segment
		(start 131.430532 76.65)
		(end 131.093033 76.987499)
		(width 0.125)
		(layer "In2.Cu")
		(net 144)
	)
	(segment
		(start 156.575729 77.62)
		(end 156.575729 77.18)
		(width 0.125)
		(layer "In2.Cu")
		(net 144)
	)
	(segment
		(start 163.618229 77.2875)
		(end 165.336942 77.2875)
		(width 0.125)
		(layer "In2.Cu")
		(net 144)
	)
	(segment
		(start 158.450729 77.143206)
		(end 158.450729 77.18)
		(width 0.125)
		(layer "In2.Cu")
		(net 144)
	)
	(segment
		(start 179.061943 63.562499)
		(end 192.128401 63.562499)
		(width 0.125)
		(layer "In2.Cu")
		(net 144)
	)
	(segment
		(start 158.775729 77.2875)
		(end 158.775729 77.188416)
		(width 0.125)
		(layer "In2.Cu")
		(net 144)
	)
	(segment
		(start 154.708229 76.360704)
		(end 154.818229 76.360704)
		(width 0.125)
		(layer "In2.Cu")
		(net 144)
	)
	(segment
		(start 156.575729 77.906796)
		(end 156.575729 77.62)
		(width 0.125)
		(layer "In2.Cu")
		(net 144)
	)
	(segment
		(start 162.408229 76.360704)
		(end 162.518229 76.360704)
		(width 0.125)
		(layer "In2.Cu")
		(net 144)
	)
	(segment
		(start 160.650729 77.2875)
		(end 160.650729 77.5125)
		(width 0.125)
		(layer "In2.Cu")
		(net 144)
	)
	(segment
		(start 161.750729 77.2875)
		(end 161.750729 77.5125)
		(width 0.125)
		(layer "In2.Cu")
		(net 144)
	)
	(segment
		(start 162.075729 77.906796)
		(end 162.075729 77.5125)
		(width 0.125)
		(layer "In2.Cu")
		(net 144)
	)
	(segment
		(start 161.858229 78.014296)
		(end 161.968229 78.014296)
		(width 0.125)
		(layer "In2.Cu")
		(net 144)
	)
	(segment
		(start 162.850729 77.62)
		(end 162.850729 77.906771)
		(width 0.125)
		(layer "In2.Cu")
		(net 144)
	)
	(segment
		(start 156.250729 77.62)
		(end 156.250729 77.906796)
		(width 0.125)
		(layer "In2.Cu")
		(net 144)
	)
	(segment
		(start 161.299812 76.864333)
		(end 161.426646 76.864333)
		(width 0.125)
		(layer "In2.Cu")
		(net 144)
	)
	(segment
		(start 160.650729 77.188416)
		(end 160.650729 77.2875)
		(width 0.125)
		(layer "In2.Cu")
		(net 144)
	)
	(segment
		(start 154.375729 77.2875)
		(end 154.375729 76.693204)
		(width 0.125)
		(layer "In2.Cu")
		(net 144)
	)
	(segment
		(start 159.875729 77.906771)
		(end 159.875729 77.5125)
		(width 0.125)
		(layer "In2.Cu")
		(net 144)
	)
	(segment
		(start 159.875729 77.5125)
		(end 159.875729 77.2875)
		(width 0.125)
		(layer "In2.Cu")
		(net 144)
	)
	(segment
		(start 158.775729 77.5125)
		(end 158.775729 77.2875)
		(width 0.125)
		(layer "In2.Cu")
		(net 144)
	)
	(arc
		(start 159.226646 76.864333)
		(mid 159.455807 76.959255)
		(end 159.550729 77.188416)
		(width 0.125)
		(layer "In2.Cu")
		(net 144)
	)
	(arc
		(start 157.675729 77.143206)
		(mid 157.773116 76.908093)
		(end 158.008229 76.810706)
		(width 0.125)
		(layer "In2.Cu")
		(net 144)
	)
	(arc
		(start 154.050729 77.906796)
		(mid 154.082215 77.98281)
		(end 154.158229 78.014296)
		(width 0.125)
		(layer "In2.Cu")
		(net 144)
	)
	(arc
		(start 157.350729 77.18)
		(mid 157.382215 77.256014)
		(end 157.458229 77.2875)
		(width 0.125)
		(layer "In2.Cu")
		(net 144)
	)
	(arc
		(start 154.375729 76.693204)
		(mid 154.473116 76.458091)
		(end 154.708229 76.360704)
		(width 0.125)
		(layer "In2.Cu")
		(net 144)
	)
	(arc
		(start 162.075729 76.693204)
		(mid 162.173116 76.458091)
		(end 162.408229 76.360704)
		(width 0.125)
		(layer "In2.Cu")
		(net 144)
	)
	(arc
		(start 158.118229 76.810706)
		(mid 158.353342 76.908093)
		(end 158.450729 77.143206)
		(width 0.125)
		(layer "In2.Cu")
		(net 144)
	)
	(arc
		(start 155.368229 78.014296)
		(mid 155.444243 77.98281)
		(end 155.475729 77.906796)
		(width 0.125)
		(layer "In2.Cu")
		(net 144)
	)
	(arc
		(start 163.175729 77.62)
		(mid 163.273116 77.384887)
		(end 163.508229 77.2875)
		(width 0.125)
		(layer "In2.Cu")
		(net 144)
	)
	(arc
		(start 161.750729 77.906796)
		(mid 161.782215 77.98281)
		(end 161.858229 78.014296)
		(width 0.125)
		(layer "In2.Cu")
		(net 144)
	)
	(arc
		(start 163.068229 78.014271)
		(mid 163.144243 77.982785)
		(end 163.175729 77.906771)
		(width 0.125)
		(layer "In2.Cu")
		(net 144)
	)
	(arc
		(start 153.275729 76.693204)
		(mid 153.373116 76.458091)
		(end 153.608229 76.360704)
		(width 0.125)
		(layer "In2.Cu")
		(net 144)
	)
	(arc
		(start 160.975729 77.188416)
		(mid 161.070651 76.959255)
		(end 161.299812 76.864333)
		(width 0.125)
		(layer "In2.Cu")
		(net 144)
	)
	(arc
		(start 155.918229 77.2875)
		(mid 156.153342 77.384887)
		(end 156.250729 77.62)
		(width 0.125)
		(layer "In2.Cu")
		(net 144)
	)
	(arc
		(start 159.768229 78.014271)
		(mid 159.844243 77.982785)
		(end 159.875729 77.906771)
		(width 0.125)
		(layer "In2.Cu")
		(net 144)
	)
	(arc
		(start 160.326646 76.864333)
		(mid 160.555807 76.959255)
		(end 160.650729 77.188416)
		(width 0.125)
		(layer "In2.Cu")
		(net 144)
	)
	(arc
		(start 153.718229 76.360704)
		(mid 153.953342 76.458091)
		(end 154.050729 76.693204)
		(width 0.125)
		(layer "In2.Cu")
		(net 144)
	)
	(arc
		(start 158.450729 77.906771)
		(mid 158.482215 77.982785)
		(end 158.558229 78.014271)
		(width 0.125)
		(layer "In2.Cu")
		(net 144)
	)
	(arc
		(start 161.426646 76.864333)
		(mid 161.655807 76.959255)
		(end 161.750729 77.188416)
		(width 0.125)
		(layer "In2.Cu")
		(net 144)
	)
	(arc
		(start 157.018229 76.810706)
		(mid 157.253342 76.908093)
		(end 157.350729 77.143206)
		(width 0.125)
		(layer "In2.Cu")
		(net 144)
	)
	(arc
		(start 154.818229 76.360704)
		(mid 155.053342 76.458091)
		(end 155.150729 76.693204)
		(width 0.125)
		(layer "In2.Cu")
		(net 144)
	)
	(arc
		(start 162.518229 76.360704)
		(mid 162.753342 76.458091)
		(end 162.850729 76.693204)
		(width 0.125)
		(layer "In2.Cu")
		(net 144)
	)
	(arc
		(start 154.268229 78.014296)
		(mid 154.344243 77.98281)
		(end 154.375729 77.906796)
		(width 0.125)
		(layer "In2.Cu")
		(net 144)
	)
	(arc
		(start 160.650729 77.906796)
		(mid 160.682215 77.98281)
		(end 160.758229 78.014296)
		(width 0.125)
		(layer "In2.Cu")
		(net 144)
	)
	(arc
		(start 156.468229 78.014296)
		(mid 156.544243 77.98281)
		(end 156.575729 77.906796)
		(width 0.125)
		(layer "In2.Cu")
		(net 144)
	)
	(arc
		(start 160.868229 78.014296)
		(mid 160.944243 77.98281)
		(end 160.975729 77.906796)
		(width 0.125)
		(layer "In2.Cu")
		(net 144)
	)
	(arc
		(start 161.968229 78.014296)
		(mid 162.044243 77.98281)
		(end 162.075729 77.906796)
		(width 0.125)
		(layer "In2.Cu")
		(net 144)
	)
	(arc
		(start 155.150729 77.906796)
		(mid 155.182215 77.98281)
		(end 155.258229 78.014296)
		(width 0.125)
		(layer "In2.Cu")
		(net 144)
	)
	(arc
		(start 159.875729 77.188416)
		(mid 159.970651 76.959255)
		(end 160.199812 76.864333)
		(width 0.125)
		(layer "In2.Cu")
		(net 144)
	)
	(arc
		(start 153.168229 77.2875)
		(mid 153.244243 77.256014)
		(end 153.275729 77.18)
		(width 0.125)
		(layer "In2.Cu")
		(net 144)
	)
	(arc
		(start 158.775729 77.188416)
		(mid 158.870651 76.959255)
		(end 159.099812 76.864333)
		(width 0.125)
		(layer "In2.Cu")
		(net 144)
	)
	(arc
		(start 155.475729 77.62)
		(mid 155.573116 77.384887)
		(end 155.808229 77.2875)
		(width 0.125)
		(layer "In2.Cu")
		(net 144)
	)
	(arc
		(start 156.250729 77.906796)
		(mid 156.282215 77.98281)
		(end 156.358229 78.014296)
		(width 0.125)
		(layer "In2.Cu")
		(net 144)
	)
	(arc
		(start 158.668229 78.014271)
		(mid 158.744243 77.982785)
		(end 158.775729 77.906771)
		(width 0.125)
		(layer "In2.Cu")
		(net 144)
	)
	(arc
		(start 156.575729 77.143206)
		(mid 156.673116 76.908093)
		(end 156.908229 76.810706)
		(width 0.125)
		(layer "In2.Cu")
		(net 144)
	)
	(arc
		(start 159.550729 77.906771)
		(mid 159.582215 77.982785)
		(end 159.658229 78.014271)
		(width 0.125)
		(layer "In2.Cu")
		(net 144)
	)
	(arc
		(start 157.568229 77.2875)
		(mid 157.644243 77.256014)
		(end 157.675729 77.18)
		(width 0.125)
		(layer "In2.Cu")
		(net 144)
	)
	(arc
		(start 162.850729 77.906771)
		(mid 162.882215 77.982785)
		(end 162.958229 78.014271)
		(width 0.125)
		(layer "In2.Cu")
		(net 144)
	)
	(segment
		(start 158 108.6)
		(end 160.1 110.7)
		(width 0.1)
		(layer "F.Cu")
		(net 145)
	)
	(segment
		(start 132.1 81.4)
		(end 131 82.5)
		(width 0.1)
		(layer "F.Cu")
		(net 145)
	)
	(segment
		(start 131 85.3)
		(end 131 86.2)
		(width 0.1)
		(layer "F.Cu")
		(net 145)
	)
	(segment
		(start 155.52 118.8)
		(end 156.12 119.4)
		(width 0.1)
		(layer "F.Cu")
		(net 145)
	)
	(segment
		(start 156.2 101.565686)
		(end 158 103.365686)
		(width 0.1)
		(layer "F.Cu")
		(net 145)
	)
	(segment
		(start 158 103.365686)
		(end 158 108.6)
		(width 0.1)
		(layer "F.Cu")
		(net 145)
	)
	(segment
		(start 132.5 80.5)
		(end 132.1 80.9)
		(width 0.1)
		(layer "F.Cu")
		(net 145)
	)
	(segment
		(start 131 86.2)
		(end 130.8 86.4)
		(width 0.1)
		(layer "F.Cu")
		(net 145)
	)
	(segment
		(start 160.1 115.5)
		(end 158.4 117.2)
		(width 0.1)
		(layer "F.Cu")
		(net 145)
	)
	(segment
		(start 153.729999 118.75)
		(end 154.35 118.75)
		(width 0.1)
		(layer "F.Cu")
		(net 145)
	)
	(segment
		(start 131.2 85.1)
		(end 131 85.3)
		(width 0.1)
		(layer "F.Cu")
		(net 145)
	)
	(segment
		(start 133.834314 88.1)
		(end 140.634314 94.9)
		(width 0.1)
		(layer "F.Cu")
		(net 145)
	)
	(segment
		(start 131 83.6)
		(end 131.2 83.8)
		(width 0.1)
		(layer "F.Cu")
		(net 145)
	)
	(segment
		(start 135.930532 79.65)
		(end 135.080532 80.5)
		(width 0.1)
		(layer "F.Cu")
		(net 145)
	)
	(segment
		(start 132.1 80.9)
		(end 132.1 81.4)
		(width 0.1)
		(layer "F.Cu")
		(net 145)
	)
	(segment
		(start 131 82.5)
		(end 131 83.6)
		(width 0.1)
		(layer "F.Cu")
		(net 145)
	)
	(segment
		(start 131.2 88.1)
		(end 133.834314 88.1)
		(width 0.1)
		(layer "F.Cu")
		(net 145)
	)
	(segment
		(start 158.4 117.2)
		(end 157.7 117.2)
		(width 0.1)
		(layer "F.Cu")
		(net 145)
	)
	(segment
		(start 130.8 87.7)
		(end 131.2 88.1)
		(width 0.1)
		(layer "F.Cu")
		(net 145)
	)
	(segment
		(start 140.634314 94.9)
		(end 153.9 94.9)
		(width 0.1)
		(layer "F.Cu")
		(net 145)
	)
	(segment
		(start 156.2 97.2)
		(end 156.2 101.565686)
		(width 0.1)
		(layer "F.Cu")
		(net 145)
	)
	(segment
		(start 130.8 86.4)
		(end 130.8 87.7)
		(width 0.1)
		(layer "F.Cu")
		(net 145)
	)
	(segment
		(start 160.1 110.7)
		(end 160.1 115.5)
		(width 0.1)
		(layer "F.Cu")
		(net 145)
	)
	(segment
		(start 154.35 118.75)
		(end 154.4 118.8)
		(width 0.1)
		(layer "F.Cu")
		(net 145)
	)
	(segment
		(start 153.9 94.9)
		(end 156.2 97.2)
		(width 0.1)
		(layer "F.Cu")
		(net 145)
	)
	(segment
		(start 131.2 83.8)
		(end 131.2 85.1)
		(width 0.1)
		(layer "F.Cu")
		(net 145)
	)
	(segment
		(start 135.080532 80.5)
		(end 132.5 80.5)
		(width 0.1)
		(layer "F.Cu")
		(net 145)
	)
	(segment
		(start 156.12 119.4)
		(end 156.12 119.320001)
		(width 0.1)
		(layer "F.Cu")
		(net 145)
	)
	(segment
		(start 154.4 118.8)
		(end 155.52 118.8)
		(width 0.1)
		(layer "F.Cu")
		(net 145)
	)
	(via
		(at 157.7 117.2)
		(size 0.45)
		(drill 0.1)
		(layers "F.Cu" "B.Cu")
		(net 145)
	)
	(via
		(at 154.4 118.8)
		(size 0.45)
		(drill 0.1)
		(layers "F.Cu" "B.Cu")
		(net 145)
	)
	(segment
		(start 155.1 117.2)
		(end 157.7 117.2)
		(width 0.1)
		(layer "B.Cu")
		(net 145)
	)
	(segment
		(start 154.4 117.9)
		(end 155.1 117.2)
		(width 0.1)
		(layer "B.Cu")
		(net 145)
	)
	(segment
		(start 154.4 118.8)
		(end 154.4 117.9)
		(width 0.1)
		(layer "B.Cu")
		(net 145)
	)
	(via
		(at 89.030532 79.65)
		(size 0.45)
		(drill 0.1)
		(layers "F.Cu" "B.Cu")
		(net 146)
	)
	(via
		(at 75.775532 86.565)
		(size 0.45)
		(drill 0.1)
		(layers "F.Cu" "B.Cu")
		(net 146)
	)
	(segment
		(start 75.775532 85.974468)
		(end 76.6 85.15)
		(width 0.1)
		(layer "In5.Cu")
		(net 146)
	)
	(segment
		(start 88.630532 79.25)
		(end 89.030532 79.65)
		(width 0.1)
		(layer "In5.Cu")
		(net 146)
	)
	(segment
		(start 87.85 79.25)
		(end 88.630532 79.25)
		(width 0.1)
		(layer "In5.Cu")
		(net 146)
	)
	(segment
		(start 76.6 85.15)
		(end 76.6 83.5)
		(width 0.1)
		(layer "In5.Cu")
		(net 146)
	)
	(segment
		(start 87.45 80.05)
		(end 87.65 79.85)
		(width 0.1)
		(layer "In5.Cu")
		(net 146)
	)
	(segment
		(start 87.65 79.85)
		(end 87.65 79.45)
		(width 0.1)
		(layer "In5.Cu")
		(net 146)
	)
	(segment
		(start 75.775532 86.565)
		(end 75.775532 85.974468)
		(width 0.1)
		(layer "In5.Cu")
		(net 146)
	)
	(segment
		(start 76.6 83.5)
		(end 76.9 83.2)
		(width 0.1)
		(layer "In5.Cu")
		(net 146)
	)
	(segment
		(start 83.6 83.2)
		(end 86.75 80.05)
		(width 0.1)
		(layer "In5.Cu")
		(net 146)
	)
	(segment
		(start 76.9 83.2)
		(end 83.6 83.2)
		(width 0.1)
		(layer "In5.Cu")
		(net 146)
	)
	(segment
		(start 86.75 80.05)
		(end 87.45 80.05)
		(width 0.1)
		(layer "In5.Cu")
		(net 146)
	)
	(segment
		(start 87.65 79.45)
		(end 87.85 79.25)
		(width 0.1)
		(layer "In5.Cu")
		(net 146)
	)
	(segment
		(start 192.306 142.59)
		(end 191.691 142.59)
		(width 0.19)
		(layer "F.Cu")
		(net 147)
	)
	(segment
		(start 192.646 142.275)
		(end 192.621 142.275)
		(width 0.19)
		(layer "F.Cu")
		(net 147)
	)
	(segment
		(start 191.691 142.59)
		(end 191.576 142.475)
		(width 0.19)
		(layer "F.Cu")
		(net 147)
	)
	(segment
		(start 113.330532 81.15)
		(end 113.065532 81.415)
		(width 0.19)
		(layer "F.Cu")
		(net 147)
	)
	(segment
		(start 113.065532 81.885)
		(end 113.180532 82)
		(width 0.19)
		(layer "F.Cu")
		(net 147)
	)
	(segment
		(start 192.621 142.275)
		(end 192.306 142.59)
		(width 0.19)
		(layer "F.Cu")
		(net 147)
	)
	(segment
		(start 113.065532 81.415)
		(end 113.065532 81.885)
		(width 0.19)
		(layer "F.Cu")
		(net 147)
	)
	(via
		(at 191.576 142.475)
		(size 0.45)
		(drill 0.1)
		(layers "F.Cu" "B.Cu")
		(net 147)
	)
	(via
		(at 113.180532 82)
		(size 0.45)
		(drill 0.1)
		(layers "F.Cu" "B.Cu")
		(net 147)
	)
	(segment
		(start 174.349002 142.59)
		(end 174.549002 142.59)
		(width 0.19)
		(layer "B.Cu")
		(net 147)
	)
	(segment
		(start 119.185 86.62337)
		(end 119.97663 87.415)
		(width 0.19)
		(layer "B.Cu")
		(net 147)
	)
	(segment
		(start 179.291502 142.59)
		(end 188.235 142.59)
		(width 0.19)
		(layer "B.Cu")
		(net 147)
	)
	(segment
		(start 172.134002 142.097043)
		(end 172.134002 142.375)
		(width 0.19)
		(layer "B.Cu")
		(net 147)
	)
	(segment
		(start 174.764002 142.375)
		(end 174.764002 142.097025)
		(width 0.19)
		(layer "B.Cu")
		(net 147)
	)
	(segment
		(start 168.134002 142.097043)
		(end 168.134002 143.074362)
		(width 0.19)
		(layer "B.Cu")
		(net 147)
	)
	(segment
		(start 166.764002 143.202965)
		(end 166.764002 142.097043)
		(width 0.19)
		(layer "B.Cu")
		(net 147)
	)
	(segment
		(start 119.185 85.62337)
		(end 119.185 86.62337)
		(width 0.19)
		(layer "B.Cu")
		(net 147)
	)
	(segment
		(start 177.139002 143.18)
		(end 177.596502 143.18)
		(width 0.19)
		(layer "B.Cu")
		(net 147)
	)
	(segment
		(start 118.22663 84.665)
		(end 119.185 85.62337)
		(width 0.19)
		(layer "B.Cu")
		(net 147)
	)
	(segment
		(start 172.764002 142.375)
		(end 172.764002 142.097043)
		(width 0.19)
		(layer "B.Cu")
		(net 147)
	)
	(segment
		(start 171.349002 141.512043)
		(end 171.549002 141.512043)
		(width 0.19)
		(layer "B.Cu")
		(net 147)
	)
	(segment
		(start 173.349002 141.512043)
		(end 173.549002 141.512043)
		(width 0.19)
		(layer "B.Cu")
		(net 147)
	)
	(segment
		(start 168.248364 143.188724)
		(end 168.64964 143.188724)
		(width 0.19)
		(layer "B.Cu")
		(net 147)
	)
	(segment
		(start 167.349002 141.512043)
		(end 167.549002 141.512043)
		(width 0.19)
		(layer "B.Cu")
		(net 147)
	)
	(segment
		(start 151.161523 132.961523)
		(end 160.79 142.59)
		(width 0.19)
		(layer "B.Cu")
		(net 147)
	)
	(segment
		(start 166.134002 143.175)
		(end 166.134002 143.202965)
		(width 0.19)
		(layer "B.Cu")
		(net 147)
	)
	(segment
		(start 122.67663 87.415)
		(end 151.161523 115.899893)
		(width 0.19)
		(layer "B.Cu")
		(net 147)
	)
	(segment
		(start 172.349002 142.59)
		(end 172.549002 142.59)
		(width 0.19)
		(layer "B.Cu")
		(net 147)
	)
	(segment
		(start 175.349002 141.512025)
		(end 175.549002 141.512025)
		(width 0.19)
		(layer "B.Cu")
		(net 147)
	)
	(segment
		(start 115.049974 83.115)
		(end 115.87663 83.115)
		(width 0.19)
		(layer "B.Cu")
		(net 147)
	)
	(segment
		(start 170.349002 142.59)
		(end 170.549002 142.59)
		(width 0.19)
		(layer "B.Cu")
		(net 147)
	)
	(segment
		(start 117.42663 84.665)
		(end 118.22663 84.665)
		(width 0.19)
		(layer "B.Cu")
		(net 147)
	)
	(segment
		(start 113.180532 82)
		(end 113.065532 82.115)
		(width 0.19)
		(layer "B.Cu")
		(net 147)
	)
	(segment
		(start 174.134002 142.097043)
		(end 174.134002 142.375)
		(width 0.19)
		(layer "B.Cu")
		(net 147)
	)
	(segment
		(start 119.97663 87.415)
		(end 122.67663 87.415)
		(width 0.19)
		(layer "B.Cu")
		(net 147)
	)
	(segment
		(start 160.79 142.59)
		(end 165.549002 142.59)
		(width 0.19)
		(layer "B.Cu")
		(net 147)
	)
	(segment
		(start 169.349002 141.512043)
		(end 169.549002 141.512043)
		(width 0.19)
		(layer "B.Cu")
		(net 147)
	)
	(segment
		(start 176.349002 142.59)
		(end 176.549002 142.59)
		(width 0.19)
		(layer "B.Cu")
		(net 147)
	)
	(segment
		(start 170.134002 142.097043)
		(end 170.134002 142.375)
		(width 0.19)
		(layer "B.Cu")
		(net 147)
	)
	(segment
		(start 188.235 142.59)
		(end 191.461 142.59)
		(width 0.19)
		(layer "B.Cu")
		(net 147)
	)
	(segment
		(start 177.706502 143.07)
		(end 177.706502 142.13965)
		(width 0.19)
		(layer "B.Cu")
		(net 147)
	)
	(segment
		(start 191.461 142.59)
		(end 191.576 142.475)
		(width 0.19)
		(layer "B.Cu")
		(net 147)
	)
	(segment
		(start 113.065532 82.803902)
		(end 113.37663 83.115)
		(width 0.19)
		(layer "B.Cu")
		(net 147)
	)
	(segment
		(start 170.764002 142.375)
		(end 170.764002 142.097043)
		(width 0.19)
		(layer "B.Cu")
		(net 147)
	)
	(segment
		(start 178.291502 141.55465)
		(end 178.491502 141.55465)
		(width 0.19)
		(layer "B.Cu")
		(net 147)
	)
	(segment
		(start 151.161523 115.899893)
		(end 151.161523 132.961523)
		(width 0.19)
		(layer "B.Cu")
		(net 147)
	)
	(segment
		(start 176.134002 142.097025)
		(end 176.134002 142.375)
		(width 0.19)
		(layer "B.Cu")
		(net 147)
	)
	(segment
		(start 114.279974 82.895)
		(end 114.279974 82.839664)
		(width 0.19)
		(layer "B.Cu")
		(net 147)
	)
	(segment
		(start 168.764002 143.074362)
		(end 168.764002 142.097043)
		(width 0.19)
		(layer "B.Cu")
		(net 147)
	)
	(segment
		(start 166.349002 143.417965)
		(end 166.549002 143.417965)
		(width 0.19)
		(layer "B.Cu")
		(net 147)
	)
	(segment
		(start 179.076502 142.13965)
		(end 179.076502 142.375)
		(width 0.19)
		(layer "B.Cu")
		(net 147)
	)
	(segment
		(start 113.37663 83.115)
		(end 114.059974 83.115)
		(width 0.19)
		(layer "B.Cu")
		(net 147)
	)
	(segment
		(start 114.829974 82.839664)
		(end 114.829974 82.895)
		(width 0.19)
		(layer "B.Cu")
		(net 147)
	)
	(segment
		(start 113.065532 82.115)
		(end 113.065532 82.803902)
		(width 0.19)
		(layer "B.Cu")
		(net 147)
	)
	(segment
		(start 114.499974 82.619664)
		(end 114.609974 82.619664)
		(width 0.19)
		(layer "B.Cu")
		(net 147)
	)
	(segment
		(start 115.87663 83.115)
		(end 117.42663 84.665)
		(width 0.19)
		(layer "B.Cu")
		(net 147)
	)
	(arc
		(start 177.706502 142.13965)
		(mid 177.877845 141.725993)
		(end 178.291502 141.55465)
		(width 0.19)
		(layer "B.Cu")
		(net 147)
	)
	(arc
		(start 172.764002 142.097043)
		(mid 172.935345 141.683386)
		(end 173.349002 141.512043)
		(width 0.19)
		(layer "B.Cu")
		(net 147)
	)
	(arc
		(start 177.029002 143.07)
		(mid 177.06122 143.147782)
		(end 177.139002 143.18)
		(width 0.19)
		(layer "B.Cu")
		(net 147)
	)
	(arc
		(start 176.549002 142.59)
		(mid 176.888413 142.730589)
		(end 177.029002 143.07)
		(width 0.19)
		(layer "B.Cu")
		(net 147)
	)
	(arc
		(start 178.491502 141.55465)
		(mid 178.905159 141.725993)
		(end 179.076502 142.13965)
		(width 0.19)
		(layer "B.Cu")
		(net 147)
	)
	(arc
		(start 168.134002 143.074362)
		(mid 168.167498 143.155228)
		(end 168.248364 143.188724)
		(width 0.19)
		(layer "B.Cu")
		(net 147)
	)
	(arc
		(start 114.829974 82.895)
		(mid 114.894411 83.050563)
		(end 115.049974 83.115)
		(width 0.19)
		(layer "B.Cu")
		(net 147)
	)
	(arc
		(start 168.64964 143.188724)
		(mid 168.730506 143.155228)
		(end 168.764002 143.074362)
		(width 0.19)
		(layer "B.Cu")
		(net 147)
	)
	(arc
		(start 170.764002 142.097043)
		(mid 170.935345 141.683386)
		(end 171.349002 141.512043)
		(width 0.19)
		(layer "B.Cu")
		(net 147)
	)
	(arc
		(start 174.134002 142.375)
		(mid 174.196974 142.527028)
		(end 174.349002 142.59)
		(width 0.19)
		(layer "B.Cu")
		(net 147)
	)
	(arc
		(start 179.076502 142.375)
		(mid 179.139474 142.527028)
		(end 179.291502 142.59)
		(width 0.19)
		(layer "B.Cu")
		(net 147)
	)
	(arc
		(start 172.549002 142.59)
		(mid 172.70103 142.527028)
		(end 172.764002 142.375)
		(width 0.19)
		(layer "B.Cu")
		(net 147)
	)
	(arc
		(start 167.549002 141.512043)
		(mid 167.962659 141.683386)
		(end 168.134002 142.097043)
		(width 0.19)
		(layer "B.Cu")
		(net 147)
	)
	(arc
		(start 175.549002 141.512025)
		(mid 175.962659 141.683368)
		(end 176.134002 142.097025)
		(width 0.19)
		(layer "B.Cu")
		(net 147)
	)
	(arc
		(start 170.134002 142.375)
		(mid 170.196974 142.527028)
		(end 170.349002 142.59)
		(width 0.19)
		(layer "B.Cu")
		(net 147)
	)
	(arc
		(start 174.549002 142.59)
		(mid 174.70103 142.527028)
		(end 174.764002 142.375)
		(width 0.19)
		(layer "B.Cu")
		(net 147)
	)
	(arc
		(start 165.549002 142.59)
		(mid 165.962659 142.761343)
		(end 166.134002 143.175)
		(width 0.19)
		(layer "B.Cu")
		(net 147)
	)
	(arc
		(start 114.059974 83.115)
		(mid 114.215537 83.050563)
		(end 114.279974 82.895)
		(width 0.19)
		(layer "B.Cu")
		(net 147)
	)
	(arc
		(start 176.134002 142.375)
		(mid 176.196974 142.527028)
		(end 176.349002 142.59)
		(width 0.19)
		(layer "B.Cu")
		(net 147)
	)
	(arc
		(start 166.549002 143.417965)
		(mid 166.70103 143.354993)
		(end 166.764002 143.202965)
		(width 0.19)
		(layer "B.Cu")
		(net 147)
	)
	(arc
		(start 170.549002 142.59)
		(mid 170.70103 142.527028)
		(end 170.764002 142.375)
		(width 0.19)
		(layer "B.Cu")
		(net 147)
	)
	(arc
		(start 171.549002 141.512043)
		(mid 171.962659 141.683386)
		(end 172.134002 142.097043)
		(width 0.19)
		(layer "B.Cu")
		(net 147)
	)
	(arc
		(start 168.764002 142.097043)
		(mid 168.935345 141.683386)
		(end 169.349002 141.512043)
		(width 0.19)
		(layer "B.Cu")
		(net 147)
	)
	(arc
		(start 166.134002 143.202965)
		(mid 166.196974 143.354993)
		(end 166.349002 143.417965)
		(width 0.19)
		(layer "B.Cu")
		(net 147)
	)
	(arc
		(start 174.764002 142.097025)
		(mid 174.935345 141.683368)
		(end 175.349002 141.512025)
		(width 0.19)
		(layer "B.Cu")
		(net 147)
	)
	(arc
		(start 166.764002 142.097043)
		(mid 166.935345 141.683386)
		(end 167.349002 141.512043)
		(width 0.19)
		(layer "B.Cu")
		(net 147)
	)
	(arc
		(start 173.549002 141.512043)
		(mid 173.962659 141.683386)
		(end 174.134002 142.097043)
		(width 0.19)
		(layer "B.Cu")
		(net 147)
	)
	(arc
		(start 114.609974 82.619664)
		(mid 114.765537 82.684101)
		(end 114.829974 82.839664)
		(width 0.19)
		(layer "B.Cu")
		(net 147)
	)
	(arc
		(start 169.549002 141.512043)
		(mid 169.962659 141.683386)
		(end 170.134002 142.097043)
		(width 0.19)
		(layer "B.Cu")
		(net 147)
	)
	(arc
		(start 172.134002 142.375)
		(mid 172.196974 142.527028)
		(end 172.349002 142.59)
		(width 0.19)
		(layer "B.Cu")
		(net 147)
	)
	(arc
		(start 114.279974 82.839664)
		(mid 114.344411 82.684101)
		(end 114.499974 82.619664)
		(width 0.19)
		(layer "B.Cu")
		(net 147)
	)
	(arc
		(start 177.596502 143.18)
		(mid 177.674284 143.147782)
		(end 177.706502 143.07)
		(width 0.19)
		(layer "B.Cu")
		(net 147)
	)
	(segment
		(start 95 120.9)
		(end 97.2 123.1)
		(width 0.5)
		(layer "F.Cu")
		(net 148)
	)
	(segment
		(start 86.403983 117.7)
		(end 88.403983 119.7)
		(width 0.5)
		(layer "F.Cu")
		(net 148)
	)
	(segment
		(start 79.585532 118.315)
		(end 80.200532 117.7)
		(width 0.5)
		(layer "F.Cu")
		(net 148)
	)
	(segment
		(start 91.1 119.7)
		(end 92.3 120.9)
		(width 0.5)
		(layer "F.Cu")
		(net 148)
	)
	(segment
		(start 129.08 132.8)
		(end 129 132.72)
		(width 0.3)
		(layer "F.Cu")
		(net 148)
	)
	(segment
		(start 92.3 120.9)
		(end 95 120.9)
		(width 0.5)
		(layer "F.Cu")
		(net 148)
	)
	(segment
		(start 99.6 123.14)
		(end 99.64 123.1)
		(width 0.3)
		(layer "F.Cu")
		(net 148)
	)
	(segment
		(start 80.200532 117.7)
		(end 86.403983 117.7)
		(width 0.5)
		(layer "F.Cu")
		(net 148)
	)
	(segment
		(start 97.2 123.1)
		(end 99.64 123.1)
		(width 0.5)
		(layer "F.Cu")
		(net 148)
	)
	(segment
		(start 129 132.72)
		(end 129 126.5)
		(width 0.3)
		(layer "F.Cu")
		(net 148)
	)
	(segment
		(start 129.095 132.815)
		(end 129.08 132.8)
		(width 0.3)
		(layer "F.Cu")
		(net 148)
	)
	(segment
		(start 129.095 135.29)
		(end 129.095 132.815)
		(width 0.3)
		(layer "F.Cu")
		(net 148)
	)
	(segment
		(start 88.403983 119.7)
		(end 91.1 119.7)
		(width 0.5)
		(layer "F.Cu")
		(net 148)
	)
	(segment
		(start 99.6 124.4)
		(end 99.6 123.14)
		(width 0.3)
		(layer "F.Cu")
		(net 148)
	)
	(via
		(at 129 126.5)
		(size 0.45)
		(drill 0.1)
		(layers "F.Cu" "B.Cu")
		(net 148)
	)
	(via
		(at 79.585532 118.315)
		(size 0.45)
		(drill 0.1)
		(layers "F.Cu" "B.Cu")
		(net 148)
	)
	(via
		(at 99.6 124.4)
		(size 0.45)
		(drill 0.1)
		(layers "F.Cu" "B.Cu")
		(net 148)
	)
	(via
		(at 108.4 125.1)
		(size 0.45)
		(drill 0.1)
		(layers "F.Cu" "B.Cu")
		(net 148)
	)
	(segment
		(start 108.4 125.1)
		(end 100.3 125.1)
		(width 0.3)
		(layer "B.Cu")
		(net 148)
	)
	(segment
		(start 100.3 125.1)
		(end 99.6 124.4)
		(width 0.3)
		(layer "B.Cu")
		(net 148)
	)
	(segment
		(start 129 126)
		(end 129 126.5)
		(width 0.3)
		(layer "In4.Cu")
		(net 148)
	)
	(segment
		(start 124.7 125.6)
		(end 108.9 125.6)
		(width 0.3)
		(layer "In4.Cu")
		(net 148)
	)
	(segment
		(start 124.7 125.6)
		(end 128.6 125.6)
		(width 0.3)
		(layer "In4.Cu")
		(net 148)
	)
	(segment
		(start 128.6 125.6)
		(end 129 126)
		(width 0.3)
		(layer "In4.Cu")
		(net 148)
	)
	(segment
		(start 108.9 125.6)
		(end 108.4 125.1)
		(width 0.3)
		(layer "In4.Cu")
		(net 148)
	)
	(segment
		(start 139.7 112.4)
		(end 139.7 112.2)
		(width 0.1)
		(layer "F.Cu")
		(net 149)
	)
	(segment
		(start 135.75 132.217157)
		(end 136.801 131.166158)
		(width 0.1)
		(layer "F.Cu")
		(net 149)
	)
	(segment
		(start 134.4 150.6)
		(end 139.2 145.8)
		(width 0.1)
		(layer "F.Cu")
		(net 149)
	)
	(segment
		(start 139.2 138.45)
		(end 135.75 135)
		(width 0.1)
		(layer "F.Cu")
		(net 149)
	)
	(segment
		(start 136.801 115.299)
		(end 139.7 112.4)
		(width 0.1)
		(layer "F.Cu")
		(net 149)
	)
	(segment
		(start 129.7 150.6)
		(end 134.4 150.6)
		(width 0.1)
		(layer "F.Cu")
		(net 149)
	)
	(segment
		(start 139.2 145.8)
		(end 139.2 138.45)
		(width 0.1)
		(layer "F.Cu")
		(net 149)
	)
	(segment
		(start 135.75 135)
		(end 135.75 132.217157)
		(width 0.1)
		(layer "F.Cu")
		(net 149)
	)
	(segment
		(start 129.1 150)
		(end 129.7 150.6)
		(width 0.1)
		(layer "F.Cu")
		(net 149)
	)
	(segment
		(start 136.801 131.166158)
		(end 136.801 115.299)
		(width 0.1)
		(layer "F.Cu")
		(net 149)
	)
	(via
		(at 129.1 150)
		(size 0.45)
		(drill 0.1)
		(layers "F.Cu" "B.Cu")
		(net 149)
	)
	(segment
		(start 129.3345 149.027)
		(end 129.3345 149.7655)
		(width 0.1)
		(layer "B.Cu")
		(net 149)
	)
	(segment
		(start 127.4 152.2)
		(end 128.3 151.3)
		(width 0.1)
		(layer "B.Cu")
		(net 149)
	)
	(segment
		(start 128.3 151)
		(end 128.58 150.72)
		(width 0.1)
		(layer "B.Cu")
		(net 149)
	)
	(segment
		(start 128.3 151.3)
		(end 128.3 151)
		(width 0.1)
		(layer "B.Cu")
		(net 149)
	)
	(segment
		(start 128.58 150.72)
		(end 129.1 150.72)
		(width 0.1)
		(layer "B.Cu")
		(net 149)
	)
	(segment
		(start 129.3345 149.7655)
		(end 129.1 150)
		(width 0.1)
		(layer "B.Cu")
		(net 149)
	)
	(segment
		(start 129.1 150.72)
		(end 129.1 150)
		(width 0.1)
		(layer "B.Cu")
		(net 149)
	)
	(segment
		(start 89.55 83.35)
		(end 89.6 83.4)
		(width 0.1)
		(layer "F.Cu")
		(net 150)
	)
	(segment
		(start 92.180532 81.8)
		(end 92.830532 81.15)
		(width 0.1)
		(layer "F.Cu")
		(net 150)
	)
	(segment
		(start 91.3 82.2)
		(end 91.7 81.8)
		(width 0.1)
		(layer "F.Cu")
		(net 150)
	)
	(segment
		(start 91.3 83.15)
		(end 91.3 82.2)
		(width 0.1)
		(layer "F.Cu")
		(net 150)
	)
	(segment
		(start 89.6 83.4)
		(end 91.05 83.4)
		(width 0.1)
		(layer "F.Cu")
		(net 150)
	)
	(segment
		(start 91.7 81.8)
		(end 92.180532 81.8)
		(width 0.1)
		(layer "F.Cu")
		(net 150)
	)
	(segment
		(start 91.05 83.4)
		(end 91.3 83.15)
		(width 0.1)
		(layer "F.Cu")
		(net 150)
	)
	(via
		(at 89.55 83.35)
		(size 0.45)
		(drill 0.1)
		(layers "F.Cu" "B.Cu")
		(net 150)
	)
	(segment
		(start 89.5 83.35)
		(end 89.7 83.35)
		(width 0.1)
		(layer "B.Cu")
		(net 150)
	)
	(segment
		(start 128.15 99)
		(end 130.05 99)
		(width 0.1)
		(layer "F.Cu")
		(net 151)
	)
	(segment
		(start 130.05 99)
		(end 130.45 99.4)
		(width 0.1)
		(layer "F.Cu")
		(net 151)
	)
	(segment
		(start 130.45 99.4)
		(end 131.8 99.4)
		(width 0.1)
		(layer "F.Cu")
		(net 151)
	)
	(segment
		(start 128.05 98.9)
		(end 128.15 99)
		(width 0.1)
		(layer "F.Cu")
		(net 151)
	)
	(via
		(at 140.630532 75.15)
		(size 0.45)
		(drill 0.1)
		(layers "F.Cu" "B.Cu")
		(net 151)
	)
	(via
		(at 128.05 98.9)
		(size 0.45)
		(drill 0.1)
		(layers "F.Cu" "B.Cu")
		(net 151)
	)
	(via
		(at 131.8 99.4)
		(size 0.45)
		(drill 0.1)
		(layers "F.Cu" "B.Cu")
		(net 151)
	)
	(via
		(at 79.585532 100.535)
		(size 0.45)
		(drill 0.1)
		(layers "F.Cu" "B.Cu")
		(net 151)
	)
	(segment
		(start 133.9 98.1)
		(end 133.9 94.071572)
		(width 0.1)
		(layer "In5.Cu")
		(net 151)
	)
	(segment
		(start 141 82.2)
		(end 140.2 81.4)
		(width 0.1)
		(layer "In5.Cu")
		(net 151)
	)
	(segment
		(start 140.2 80.1)
		(end 140 79.9)
		(width 0.1)
		(layer "In5.Cu")
		(net 151)
	)
	(segment
		(start 140.85 77)
		(end 140.85 75.369468)
		(width 0.1)
		(layer "In5.Cu")
		(net 151)
	)
	(segment
		(start 86.5 115.5)
		(end 86.4 115.4)
		(width 0.1)
		(layer "In5.Cu")
		(net 151)
	)
	(segment
		(start 132.6 99.4)
		(end 133.9 98.1)
		(width 0.1)
		(layer "In5.Cu")
		(net 151)
	)
	(segment
		(start 83.8 115.075)
		(end 83.8 101.6)
		(width 0.1)
		(layer "In5.Cu")
		(net 151)
	)
	(segment
		(start 133.9 94.071572)
		(end 140.4 87.571572)
		(width 0.1)
		(layer "In5.Cu")
		(net 151)
	)
	(segment
		(start 140 79.9)
		(end 140 78.6)
		(width 0.1)
		(layer "In5.Cu")
		(net 151)
	)
	(segment
		(start 140.85 75.369468)
		(end 140.630532 75.15)
		(width 0.1)
		(layer "In5.Cu")
		(net 151)
	)
	(segment
		(start 99.868634 102.2)
		(end 98.500003 103.568631)
		(width 0.1)
		(layer "In5.Cu")
		(net 151)
	)
	(segment
		(start 128.05 98.9)
		(end 123.434316 98.9)
		(width 0.1)
		(layer "In5.Cu")
		(net 151)
	)
	(segment
		(start 86.4 115.4)
		(end 84.125 115.4)
		(width 0.1)
		(layer "In5.Cu")
		(net 151)
	)
	(segment
		(start 140.2 78.4)
		(end 140.2 77.65)
		(width 0.1)
		(layer "In5.Cu")
		(net 151)
	)
	(segment
		(start 83.4 101.2)
		(end 80.250532 101.2)
		(width 0.1)
		(layer "In5.Cu")
		(net 151)
	)
	(segment
		(start 123.434316 98.9)
		(end 120.134316 102.2)
		(width 0.1)
		(layer "In5.Cu")
		(net 151)
	)
	(segment
		(start 93.737262 115.5)
		(end 86.5 115.5)
		(width 0.1)
		(layer "In5.Cu")
		(net 151)
	)
	(segment
		(start 140.2 81.4)
		(end 140.2 80.1)
		(width 0.1)
		(layer "In5.Cu")
		(net 151)
	)
	(segment
		(start 84.125 115.4)
		(end 83.8 115.075)
		(width 0.1)
		(layer "In5.Cu")
		(net 151)
	)
	(segment
		(start 120.134316 102.2)
		(end 99.868634 102.2)
		(width 0.1)
		(layer "In5.Cu")
		(net 151)
	)
	(segment
		(start 131.8 99.4)
		(end 132.6 99.4)
		(width 0.1)
		(layer "In5.Cu")
		(net 151)
	)
	(segment
		(start 141 82.75)
		(end 141 82.2)
		(width 0.1)
		(layer "In5.Cu")
		(net 151)
	)
	(segment
		(start 98.500003 110.737259)
		(end 93.737262 115.5)
		(width 0.1)
		(layer "In5.Cu")
		(net 151)
	)
	(segment
		(start 140.4 83.35)
		(end 141 82.75)
		(width 0.1)
		(layer "In5.Cu")
		(net 151)
	)
	(segment
		(start 140 78.6)
		(end 140.2 78.4)
		(width 0.1)
		(layer "In5.Cu")
		(net 151)
	)
	(segment
		(start 80.250532 101.2)
		(end 79.585532 100.535)
		(width 0.1)
		(layer "In5.Cu")
		(net 151)
	)
	(segment
		(start 140.2 77.65)
		(end 140.85 77)
		(width 0.1)
		(layer "In5.Cu")
		(net 151)
	)
	(segment
		(start 140.4 87.571572)
		(end 140.4 83.35)
		(width 0.1)
		(layer "In5.Cu")
		(net 151)
	)
	(segment
		(start 83.8 101.6)
		(end 83.4 101.2)
		(width 0.1)
		(layer "In5.Cu")
		(net 151)
	)
	(segment
		(start 98.500003 103.568631)
		(end 98.500003 110.737259)
		(width 0.1)
		(layer "In5.Cu")
		(net 151)
	)
	(via
		(at 206.1875 60.1)
		(size 0.45)
		(drill 0.1)
		(layers "F.Cu" "B.Cu")
		(net 152)
	)
	(via
		(at 128.030532 72.15)
		(size 0.45)
		(drill 0.1)
		(layers "F.Cu" "B.Cu")
		(net 152)
	)
	(segment
		(start 206.075 59.840938)
		(end 206.075 59.9875)
		(width 0.17)
		(layer "B.Cu")
		(net 152)
	)
	(segment
		(start 206.075 59.9875)
		(end 206.1875 60.1)
		(width 0.17)
		(layer "B.Cu")
		(net 152)
	)
	(segment
		(start 206.082 59.833938)
		(end 206.075 59.840938)
		(width 0.17)
		(layer "B.Cu")
		(net 152)
	)
	(segment
		(start 206.082 59.364001)
		(end 206.082 59.833938)
		(width 0.17)
		(layer "B.Cu")
		(net 152)
	)
	(segment
		(start 206.156 59.290001)
		(end 206.082 59.364001)
		(width 0.17)
		(layer "B.Cu")
		(net 152)
	)
	(segment
		(start 206.156 58.39)
		(end 206.156 59.290001)
		(width 0.17)
		(layer "B.Cu")
		(net 152)
	)
	(segment
		(start 155.264864 72.185893)
		(end 155.374864 72.185893)
		(width 0.125)
		(layer "In2.Cu")
		(net 152)
	)
	(segment
		(start 206.012501 59.925001)
		(end 206.1875 60.1)
		(width 0.125)
		(layer "In2.Cu")
		(net 152)
	)
	(segment
		(start 153.507364 72.518393)
		(end 153.507364 72.68)
		(width 0.125)
		(layer "In2.Cu")
		(net 152)
	)
	(segment
		(start 155.707364 72.518393)
		(end 155.707364 72.7875)
		(width 0.125)
		(layer "In2.Cu")
		(net 152)
	)
	(segment
		(start 152.407364 73.0125)
		(end 152.407364 73.581603)
		(width 0.125)
		(layer "In2.Cu")
		(net 152)
	)
	(segment
		(start 153.064864 72.185893)
		(end 153.174864 72.185893)
		(width 0.125)
		(layer "In2.Cu")
		(net 152)
	)
	(segment
		(start 152.732364 72.68)
		(end 152.732364 72.518393)
		(width 0.125)
		(layer "In2.Cu")
		(net 152)
	)
	(segment
		(start 167.84607 68.414412)
		(end 177.185481 59.075001)
		(width 0.125)
		(layer "In2.Cu")
		(net 152)
	)
	(segment
		(start 205.434101 59.075001)
		(end 206.012501 59.653401)
		(width 0.125)
		(layer "In2.Cu")
		(net 152)
	)
	(segment
		(start 154.714864 73.689124)
		(end 154.824864 73.689124)
		(width 0.125)
		(layer "In2.Cu")
		(net 152)
	)
	(segment
		(start 152.732364 73.0125)
		(end 152.732364 72.68)
		(width 0.125)
		(layer "In2.Cu")
		(net 152)
	)
	(segment
		(start 152.514864 73.689103)
		(end 152.624864 73.689103)
		(width 0.125)
		(layer "In2.Cu")
		(net 152)
	)
	(segment
		(start 152.732364 73.581603)
		(end 152.732364 73.0125)
		(width 0.125)
		(layer "In2.Cu")
		(net 152)
	)
	(segment
		(start 163.472982 72.7875)
		(end 167.84607 68.414412)
		(width 0.125)
		(layer "In2.Cu")
		(net 152)
	)
	(segment
		(start 177.185481 59.075001)
		(end 205.434101 59.075001)
		(width 0.125)
		(layer "In2.Cu")
		(net 152)
	)
	(segment
		(start 151.632364 73.581603)
		(end 151.632364 73.12)
		(width 0.125)
		(layer "In2.Cu")
		(net 152)
	)
	(segment
		(start 151.307364 73.12)
		(end 151.307364 73.581603)
		(width 0.125)
		(layer "In2.Cu")
		(net 152)
	)
	(segment
		(start 154.607364 73.0125)
		(end 154.607364 73.581624)
		(width 0.125)
		(layer "In2.Cu")
		(net 152)
	)
	(segment
		(start 156.364864 72.7875)
		(end 156.474864 72.7875)
		(width 0.125)
		(layer "In2.Cu")
		(net 152)
	)
	(segment
		(start 153.832364 72.68)
		(end 153.832364 72.518393)
		(width 0.125)
		(layer "In2.Cu")
		(net 152)
	)
	(segment
		(start 151.632364 73.12)
		(end 151.632364 72.7875)
		(width 0.125)
		(layer "In2.Cu")
		(net 152)
	)
	(segment
		(start 127.693033 72.487499)
		(end 127.693033 72.583933)
		(width 0.125)
		(layer "In2.Cu")
		(net 152)
	)
	(segment
		(start 155.814864 73.689103)
		(end 155.924864 73.689103)
		(width 0.125)
		(layer "In2.Cu")
		(net 152)
	)
	(segment
		(start 154.932364 73.0125)
		(end 154.932364 72.7875)
		(width 0.125)
		(layer "In2.Cu")
		(net 152)
	)
	(segment
		(start 154.932364 72.7875)
		(end 154.932364 72.518393)
		(width 0.125)
		(layer "In2.Cu")
		(net 152)
	)
	(segment
		(start 152.407364 72.518393)
		(end 152.407364 72.7875)
		(width 0.125)
		(layer "In2.Cu")
		(net 152)
	)
	(segment
		(start 156.032364 73.581603)
		(end 156.032364 73.12)
		(width 0.125)
		(layer "In2.Cu")
		(net 152)
	)
	(segment
		(start 154.607364 72.518393)
		(end 154.607364 72.68)
		(width 0.125)
		(layer "In2.Cu")
		(net 152)
	)
	(segment
		(start 154.607364 72.68)
		(end 154.607364 73.0125)
		(width 0.125)
		(layer "In2.Cu")
		(net 152)
	)
	(segment
		(start 152.407364 72.7875)
		(end 152.407364 73.0125)
		(width 0.125)
		(layer "In2.Cu")
		(net 152)
	)
	(segment
		(start 155.707364 72.7875)
		(end 155.707364 73.12)
		(width 0.125)
		(layer "In2.Cu")
		(net 152)
	)
	(segment
		(start 206.012501 59.653401)
		(end 206.012501 59.925001)
		(width 0.125)
		(layer "In2.Cu")
		(net 152)
	)
	(segment
		(start 151.414864 73.689103)
		(end 151.524864 73.689103)
		(width 0.125)
		(layer "In2.Cu")
		(net 152)
	)
	(segment
		(start 151.632364 72.7875)
		(end 151.632364 72.518393)
		(width 0.125)
		(layer "In2.Cu")
		(net 152)
	)
	(segment
		(start 151.964864 72.185893)
		(end 152.074864 72.185893)
		(width 0.125)
		(layer "In2.Cu")
		(net 152)
	)
	(segment
		(start 153.614864 72.7875)
		(end 153.724864 72.7875)
		(width 0.125)
		(layer "In2.Cu")
		(net 152)
	)
	(segment
		(start 156.474864 72.7875)
		(end 163.472982 72.7875)
		(width 0.125)
		(layer "In2.Cu")
		(net 152)
	)
	(segment
		(start 154.164864 72.185893)
		(end 154.274864 72.185893)
		(width 0.125)
		(layer "In2.Cu")
		(net 152)
	)
	(segment
		(start 155.707364 73.12)
		(end 155.707364 73.581603)
		(width 0.125)
		(layer "In2.Cu")
		(net 152)
	)
	(segment
		(start 128.030532 72.15)
		(end 127.693033 72.487499)
		(width 0.125)
		(layer "In2.Cu")
		(net 152)
	)
	(segment
		(start 127.693033 72.583933)
		(end 127.8966 72.7875)
		(width 0.125)
		(layer "In2.Cu")
		(net 152)
	)
	(segment
		(start 154.932364 73.581624)
		(end 154.932364 73.0125)
		(width 0.125)
		(layer "In2.Cu")
		(net 152)
	)
	(segment
		(start 127.8966 72.7875)
		(end 150.974864 72.7875)
		(width 0.125)
		(layer "In2.Cu")
		(net 152)
	)
	(arc
		(start 153.507364 72.68)
		(mid 153.53885 72.756014)
		(end 153.614864 72.7875)
		(width 0.125)
		(layer "In2.Cu")
		(net 152)
	)
	(arc
		(start 155.374864 72.185893)
		(mid 155.609977 72.28328)
		(end 155.707364 72.518393)
		(width 0.125)
		(layer "In2.Cu")
		(net 152)
	)
	(arc
		(start 152.407364 73.581603)
		(mid 152.43885 73.657617)
		(end 152.514864 73.689103)
		(width 0.125)
		(layer "In2.Cu")
		(net 152)
	)
	(arc
		(start 153.174864 72.185893)
		(mid 153.409977 72.28328)
		(end 153.507364 72.518393)
		(width 0.125)
		(layer "In2.Cu")
		(net 152)
	)
	(arc
		(start 152.624864 73.689103)
		(mid 152.700878 73.657617)
		(end 152.732364 73.581603)
		(width 0.125)
		(layer "In2.Cu")
		(net 152)
	)
	(arc
		(start 154.274864 72.185893)
		(mid 154.509977 72.28328)
		(end 154.607364 72.518393)
		(width 0.125)
		(layer "In2.Cu")
		(net 152)
	)
	(arc
		(start 155.707364 73.581603)
		(mid 155.73885 73.657617)
		(end 155.814864 73.689103)
		(width 0.125)
		(layer "In2.Cu")
		(net 152)
	)
	(arc
		(start 152.074864 72.185893)
		(mid 152.309977 72.28328)
		(end 152.407364 72.518393)
		(width 0.125)
		(layer "In2.Cu")
		(net 152)
	)
	(arc
		(start 152.732364 72.518393)
		(mid 152.829751 72.28328)
		(end 153.064864 72.185893)
		(width 0.125)
		(layer "In2.Cu")
		(net 152)
	)
	(arc
		(start 150.974864 72.7875)
		(mid 151.209977 72.884887)
		(end 151.307364 73.12)
		(width 0.125)
		(layer "In2.Cu")
		(net 152)
	)
	(arc
		(start 155.924864 73.689103)
		(mid 156.000878 73.657617)
		(end 156.032364 73.581603)
		(width 0.125)
		(layer "In2.Cu")
		(net 152)
	)
	(arc
		(start 151.632364 72.518393)
		(mid 151.729751 72.28328)
		(end 151.964864 72.185893)
		(width 0.125)
		(layer "In2.Cu")
		(net 152)
	)
	(arc
		(start 153.832364 72.518393)
		(mid 153.929751 72.28328)
		(end 154.164864 72.185893)
		(width 0.125)
		(layer "In2.Cu")
		(net 152)
	)
	(arc
		(start 154.607364 73.581624)
		(mid 154.63885 73.657638)
		(end 154.714864 73.689124)
		(width 0.125)
		(layer "In2.Cu")
		(net 152)
	)
	(arc
		(start 151.307364 73.581603)
		(mid 151.33885 73.657617)
		(end 151.414864 73.689103)
		(width 0.125)
		(layer "In2.Cu")
		(net 152)
	)
	(arc
		(start 154.824864 73.689124)
		(mid 154.900878 73.657638)
		(end 154.932364 73.581624)
		(width 0.125)
		(layer "In2.Cu")
		(net 152)
	)
	(arc
		(start 154.932364 72.518393)
		(mid 155.029751 72.28328)
		(end 155.264864 72.185893)
		(width 0.125)
		(layer "In2.Cu")
		(net 152)
	)
	(arc
		(start 153.724864 72.7875)
		(mid 153.800878 72.756014)
		(end 153.832364 72.68)
		(width 0.125)
		(layer "In2.Cu")
		(net 152)
	)
	(arc
		(start 156.032364 73.12)
		(mid 156.129751 72.884887)
		(end 156.364864 72.7875)
		(width 0.125)
		(layer "In2.Cu")
		(net 152)
	)
	(arc
		(start 151.524864 73.689103)
		(mid 151.600878 73.657617)
		(end 151.632364 73.581603)
		(width 0.125)
		(layer "In2.Cu")
		(net 152)
	)
	(segment
		(start 122.705532 80.275)
		(end 122.580532 80.4)
		(width 0.17)
		(layer "F.Cu")
		(net 153)
	)
	(segment
		(start 122.430532 79.65)
		(end 122.705532 79.925)
		(width 0.17)
		(layer "F.Cu")
		(net 153)
	)
	(segment
		(start 122.705532 79.925)
		(end 122.705532 80.275)
		(width 0.17)
		(layer "F.Cu")
		(net 153)
	)
	(via
		(at 66.203294 104.403294)
		(size 0.45)
		(drill 0.1)
		(layers "F.Cu" "B.Cu")
		(net 153)
	)
	(via
		(at 122.580532 80.4)
		(size 0.45)
		(drill 0.1)
		(layers "F.Cu" "B.Cu")
		(net 153)
	)
	(segment
		(start 65.115 104.885)
		(end 65.562488 104.885)
		(width 0.17)
		(layer "B.Cu")
		(net 153)
	)
	(segment
		(start 65.04 104.96)
		(end 65.115 104.885)
		(width 0.17)
		(layer "B.Cu")
		(net 153)
	)
	(segment
		(start 65.562488 104.885)
		(end 66.044194 104.403294)
		(width 0.17)
		(layer "B.Cu")
		(net 153)
	)
	(segment
		(start 64.59 104.96)
		(end 65.04 104.96)
		(width 0.17)
		(layer "B.Cu")
		(net 153)
	)
	(segment
		(start 66.044194 104.403294)
		(end 66.203294 104.403294)
		(width 0.17)
		(layer "B.Cu")
		(net 153)
	)
	(segment
		(start 106.62535 79.470439)
		(end 106.62535 80.579565)
		(width 0.125)
		(layer "In2.Cu")
		(net 153)
	)
	(segment
		(start 111.35785 80.4125)
		(end 111.9466 80.4125)
		(width 0.125)
		(layer "In2.Cu")
		(net 153)
	)
	(segment
		(start 104.6284 79.0375)
		(end 104.8375 79.2466)
		(width 0.125)
		(layer "In2.Cu")
		(net 153)
	)
	(segment
		(start 111.9466 80.4125)
		(end 113.2466 79.1125)
		(width 0.125)
		(layer "In2.Cu")
		(net 153)
	)
	(segment
		(start 84.15 83.725)
		(end 84.3125 83.725)
		(width 0.125)
		(layer "In2.Cu")
		(net 153)
	)
	(segment
		(start 107.72535 80.070439)
		(end 107.72535 80.629581)
		(width 0.125)
		(layer "In2.Cu")
		(net 153)
	)
	(segment
		(start 122.768031 80.212501)
		(end 122.580532 80.4)
		(width 0.125)
		(layer "In2.Cu")
		(net 153)
	)
	(segment
		(start 106.30035 80.475)
		(end 106.30035 79.470439)
		(width 0.125)
		(layer "In2.Cu")
		(net 153)
	)
	(segment
		(start 84.3125 83.725)
		(end 84.525 83.5125)
		(width 0.125)
		(layer "In2.Cu")
		(net 153)
	)
	(segment
		(start 109.70785 80.4125)
		(end 109.81785 80.4125)
		(width 0.125)
		(layer "In2.Cu")
		(net 153)
	)
	(segment
		(start 116.2791 80.479561)
		(end 116.2791 80.47)
		(width 0.125)
		(layer "In2.Cu")
		(net 153)
	)
	(segment
		(start 91.4125 79.605893)
		(end 91.4125 79.145)
		(width 0.125)
		(layer "In2.Cu")
		(net 153)
	)
	(segment
		(start 66.4125 103.9466)
		(end 66.4125 100.9534)
		(width 0.125)
		(layer "In2.Cu")
		(net 153)
	)
	(segment
		(start 95.37 79.938393)
		(end 95.48 79.938393)
		(width 0.125)
		(layer "In2.Cu")
		(net 153)
	)
	(segment
		(start 106.95785 80.912065)
		(end 107.06785 80.912065)
		(width 0.125)
		(layer "In2.Cu")
		(net 153)
	)
	(segment
		(start 95.0375 78.594097)
		(end 95.0375 79.605893)
		(width 0.125)
		(layer "In2.Cu")
		(net 153)
	)
	(segment
		(start 90.3125 79.605893)
		(end 90.3125 78.694092)
		(width 0.125)
		(layer "In2.Cu")
		(net 153)
	)
	(segment
		(start 93.6125 78.705)
		(end 93.6125 78.04409)
		(width 0.125)
		(layer "In2.Cu")
		(net 153)
	)
	(segment
		(start 89.5375 79.145)
		(end 89.5375 79.605893)
		(width 0.125)
		(layer "In2.Cu")
		(net 153)
	)
	(segment
		(start 92.8375 78.394108)
		(end 92.8375 78.705)
		(width 0.125)
		(layer "In2.Cu")
		(net 153)
	)
	(segment
		(start 122.768031 80.027131)
		(end 122.768031 80.212501)
		(width 0.125)
		(layer "In2.Cu")
		(net 153)
	)
	(segment
		(start 110.15035 80.08)
		(end 110.15035 79.42044)
		(width 0.125)
		(layer "In2.Cu")
		(net 153)
	)
	(segment
		(start 105.8066 80.7625)
		(end 106.01285 80.7625)
		(width 0.125)
		(layer "In2.Cu")
		(net 153)
	)
	(segment
		(start 110.47535 79.42044)
		(end 110.47535 80.679584)
		(width 0.125)
		(layer "In2.Cu")
		(net 153)
	)
	(segment
		(start 108.60785 80.4125)
		(end 108.71785 80.4125)
		(width 0.125)
		(layer "In2.Cu")
		(net 153)
	)
	(segment
		(start 95.875 78.6875)
		(end 96.075 78.6875)
		(width 0.125)
		(layer "In2.Cu")
		(net 153)
	)
	(segment
		(start 106.40785 79.362939)
		(end 106.51785 79.362939)
		(width 0.125)
		(layer "In2.Cu")
		(net 153)
	)
	(segment
		(start 105.3634 80.4125)
		(end 105.4566 80.4125)
		(width 0.125)
		(layer "In2.Cu")
		(net 153)
	)
	(segment
		(start 119.4659 80.3)
		(end 120.95 80.3)
		(width 0.125)
		(layer "In2.Cu")
		(net 153)
	)
	(segment
		(start 90.6375 78.694092)
		(end 90.6375 79.605893)
		(width 0.125)
		(layer "In2.Cu")
		(net 153)
	)
	(segment
		(start 93.9375 78.04409)
		(end 93.9375 79.605893)
		(width 0.125)
		(layer "In2.Cu")
		(net 153)
	)
	(segment
		(start 107.40035 80.579565)
		(end 107.40035 80.070439)
		(width 0.125)
		(layer "In2.Cu")
		(net 153)
	)
	(segment
		(start 117.7466 80.3625)
		(end 118.2216 79.8875)
		(width 0.125)
		(layer "In2.Cu")
		(net 153)
	)
	(segment
		(start 65.6125 87.1466)
		(end 69.2466 83.5125)
		(width 0.125)
		(layer "In2.Cu")
		(net 153)
	)
	(segment
		(start 121.3466 79.2125)
		(end 121.9534 79.2125)
		(width 0.125)
		(layer "In2.Cu")
		(net 153)
	)
	(segment
		(start 96.96875 78.6875)
		(end 97.16875 78.6875)
		(width 0.125)
		(layer "In2.Cu")
		(net 153)
	)
	(segment
		(start 96.425 79.0375)
		(end 96.61875 79.0375)
		(width 0.125)
		(layer "In2.Cu")
		(net 153)
	)
	(segment
		(start 109.60035 81.07956)
		(end 109.60035 80.52)
		(width 0.125)
		(layer "In2.Cu")
		(net 153)
	)
	(segment
		(start 92.5125 79.605893)
		(end 92.5125 78.394108)
		(width 0.125)
		(layer "In2.Cu")
		(net 153)
	)
	(segment
		(start 110.25785 79.31294)
		(end 110.36785 79.31294)
		(width 0.125)
		(layer "In2.Cu")
		(net 153)
	)
	(segment
		(start 107.50785 79.962939)
		(end 107.61785 79.962939)
		(width 0.125)
		(layer "In2.Cu")
		(net 153)
	)
	(segment
		(start 111.25035 80.679584)
		(end 111.25035 80.52)
		(width 0.125)
		(layer "In2.Cu")
		(net 153)
	)
	(segment
		(start 113.2466 79.1125)
		(end 113.6034 79.1125)
		(width 0.125)
		(layer "In2.Cu")
		(net 153)
	)
	(segment
		(start 94.7125 79.605893)
		(end 94.7125 78.594097)
		(width 0.125)
		(layer "In2.Cu")
		(net 153)
	)
	(segment
		(start 118.2216 79.8875)
		(end 119.0534 79.8875)
		(width 0.125)
		(layer "In2.Cu")
		(net 153)
	)
	(segment
		(start 110.80785 81.012084)
		(end 110.91785 81.012084)
		(width 0.125)
		(layer "In2.Cu")
		(net 153)
	)
	(segment
		(start 115.3034 80.3625)
		(end 115.3966 80.3625)
		(width 0.125)
		(layer "In2.Cu")
		(net 153)
	)
	(segment
		(start 92.62 78.286608)
		(end 92.73 78.286608)
		(width 0.125)
		(layer "In2.Cu")
		(net 153)
	)
	(segment
		(start 114.8534 79.9125)
		(end 115.3034 80.3625)
		(width 0.125)
		(layer "In2.Cu")
		(net 153)
	)
	(segment
		(start 116.3866 80.3625)
		(end 117.7466 80.3625)
		(width 0.125)
		(layer "In2.Cu")
		(net 153)
	)
	(segment
		(start 120.95 80.3)
		(end 121.0125 80.2375)
		(width 0.125)
		(layer "In2.Cu")
		(net 153)
	)
	(segment
		(start 95.8125 79.605893)
		(end 95.8125 78.75)
		(width 0.125)
		(layer "In2.Cu")
		(net 153)
	)
	(segment
		(start 115.8366 80.812061)
		(end 115.9466 80.812061)
		(width 0.125)
		(layer "In2.Cu")
		(net 153)
	)
	(segment
		(start 97.51875 79.0375)
		(end 104.6284 79.0375)
		(width 0.125)
		(layer "In2.Cu")
		(net 153)
	)
	(segment
		(start 89.87 79.938393)
		(end 89.98 79.938393)
		(width 0.125)
		(layer "In2.Cu")
		(net 153)
	)
	(segment
		(start 91.7375 79.145)
		(end 91.7375 79.605893)
		(width 0.125)
		(layer "In2.Cu")
		(net 153)
	)
	(segment
		(start 121.9534 79.2125)
		(end 122.768031 80.027131)
		(width 0.125)
		(layer "In2.Cu")
		(net 153)
	)
	(segment
		(start 113.6034 79.1125)
		(end 114.4034 79.9125)
		(width 0.125)
		(layer "In2.Cu")
		(net 153)
	)
	(segment
		(start 109.15785 81.41206)
		(end 109.26785 81.41206)
		(width 0.125)
		(layer "In2.Cu")
		(net 153)
	)
	(segment
		(start 66.203294 104.155806)
		(end 66.4125 103.9466)
		(width 0.125)
		(layer "In2.Cu")
		(net 153)
	)
	(segment
		(start 92.07 79.938393)
		(end 92.18 79.938393)
		(width 0.125)
		(layer "In2.Cu")
		(net 153)
	)
	(segment
		(start 69.2466 83.5125)
		(end 83.9375 83.5125)
		(width 0.125)
		(layer "In2.Cu")
		(net 153)
	)
	(segment
		(start 104.8375 79.2466)
		(end 104.8375 79.8866)
		(width 0.125)
		(layer "In2.Cu")
		(net 153)
	)
	(segment
		(start 121.0125 80.2375)
		(end 121.0125 79.5466)
		(width 0.125)
		(layer "In2.Cu")
		(net 153)
	)
	(segment
		(start 83.9375 83.5125)
		(end 84.15 83.725)
		(width 0.125)
		(layer "In2.Cu")
		(net 153)
	)
	(segment
		(start 90.42 78.586592)
		(end 90.53 78.586592)
		(width 0.125)
		(layer "In2.Cu")
		(net 153)
	)
	(segment
		(start 94.82 78.486597)
		(end 94.93 78.486597)
		(width 0.125)
		(layer "In2.Cu")
		(net 153)
	)
	(segment
		(start 94.27 79.938393)
		(end 94.38 79.938393)
		(width 0.125)
		(layer "In2.Cu")
		(net 153)
	)
	(segment
		(start 86.5875 83.1716)
		(end 86.5875 79.4216)
		(width 0.125)
		(layer "In2.Cu")
		(net 153)
	)
	(segment
		(start 86.9716 79.0375)
		(end 89.43 79.0375)
		(width 0.125)
		(layer "In2.Cu")
		(net 153)
	)
	(segment
		(start 93.72 77.93659)
		(end 93.83 77.93659)
		(width 0.125)
		(layer "In2.Cu")
		(net 153)
	)
	(segment
		(start 66.4125 100.9534)
		(end 65.6125 100.1534)
		(width 0.125)
		(layer "In2.Cu")
		(net 153)
	)
	(segment
		(start 91.52 79.0375)
		(end 91.63 79.0375)
		(width 0.125)
		(layer "In2.Cu")
		(net 153)
	)
	(segment
		(start 65.6125 100.1534)
		(end 65.6125 87.1466)
		(width 0.125)
		(layer "In2.Cu")
		(net 153)
	)
	(segment
		(start 114.4034 79.9125)
		(end 114.8534 79.9125)
		(width 0.125)
		(layer "In2.Cu")
		(net 153)
	)
	(segment
		(start 104.8375 79.8866)
		(end 105.3634 80.4125)
		(width 0.125)
		(layer "In2.Cu")
		(net 153)
	)
	(segment
		(start 121.0125 79.5466)
		(end 121.3466 79.2125)
		(width 0.125)
		(layer "In2.Cu")
		(net 153)
	)
	(segment
		(start 66.203294 104.403294)
		(end 66.203294 104.155806)
		(width 0.125)
		(layer "In2.Cu")
		(net 153)
	)
	(segment
		(start 108.05785 80.962081)
		(end 108.16785 80.962081)
		(width 0.125)
		(layer "In2.Cu")
		(net 153)
	)
	(segment
		(start 93.17 79.0375)
		(end 93.28 79.0375)
		(width 0.125)
		(layer "In2.Cu")
		(net 153)
	)
	(segment
		(start 90.97 79.938393)
		(end 91.08 79.938393)
		(width 0.125)
		(layer "In2.Cu")
		(net 153)
	)
	(segment
		(start 86.5875 79.4216)
		(end 86.9716 79.0375)
		(width 0.125)
		(layer "In2.Cu")
		(net 153)
	)
	(segment
		(start 86.2466 83.5125)
		(end 86.5875 83.1716)
		(width 0.125)
		(layer "In2.Cu")
		(net 153)
	)
	(segment
		(start 84.525 83.5125)
		(end 86.2466 83.5125)
		(width 0.125)
		(layer "In2.Cu")
		(net 153)
	)
	(segment
		(start 115.5041 80.47)
		(end 115.5041 80.479561)
		(width 0.125)
		(layer "In2.Cu")
		(net 153)
	)
	(segment
		(start 108.50035 80.629581)
		(end 108.50035 80.52)
		(width 0.125)
		(layer "In2.Cu")
		(net 153)
	)
	(segment
		(start 108.82535 80.52)
		(end 108.82535 81.07956)
		(width 0.125)
		(layer "In2.Cu")
		(net 153)
	)
	(segment
		(start 119.0534 79.8875)
		(end 119.4659 80.3)
		(width 0.125)
		(layer "In2.Cu")
		(net 153)
	)
	(arc
		(start 115.5041 80.479561)
		(mid 115.601487 80.714674)
		(end 115.8366 80.812061)
		(width 0.125)
		(layer "In2.Cu")
		(net 153)
	)
	(arc
		(start 91.7375 79.605893)
		(mid 91.834887 79.841006)
		(end 92.07 79.938393)
		(width 0.125)
		(layer "In2.Cu")
		(net 153)
	)
	(arc
		(start 107.06785 80.912065)
		(mid 107.302963 80.814678)
		(end 107.40035 80.579565)
		(width 0.125)
		(layer "In2.Cu")
		(net 153)
	)
	(arc
		(start 106.51785 79.362939)
		(mid 106.593864 79.394425)
		(end 106.62535 79.470439)
		(width 0.125)
		(layer "In2.Cu")
		(net 153)
	)
	(arc
		(start 115.9466 80.812061)
		(mid 116.181713 80.714674)
		(end 116.2791 80.479561)
		(width 0.125)
		(layer "In2.Cu")
		(net 153)
	)
	(arc
		(start 93.6125 78.04409)
		(mid 93.643986 77.968076)
		(end 93.72 77.93659)
		(width 0.125)
		(layer "In2.Cu")
		(net 153)
	)
	(arc
		(start 108.82535 81.07956)
		(mid 108.922737 81.314673)
		(end 109.15785 81.41206)
		(width 0.125)
		(layer "In2.Cu")
		(net 153)
	)
	(arc
		(start 108.71785 80.4125)
		(mid 108.793864 80.443986)
		(end 108.82535 80.52)
		(width 0.125)
		(layer "In2.Cu")
		(net 153)
	)
	(arc
		(start 109.81785 80.4125)
		(mid 110.052963 80.315113)
		(end 110.15035 80.08)
		(width 0.125)
		(layer "In2.Cu")
		(net 153)
	)
	(arc
		(start 110.15035 79.42044)
		(mid 110.181836 79.344426)
		(end 110.25785 79.31294)
		(width 0.125)
		(layer "In2.Cu")
		(net 153)
	)
	(arc
		(start 92.73 78.286608)
		(mid 92.806014 78.318094)
		(end 92.8375 78.394108)
		(width 0.125)
		(layer "In2.Cu")
		(net 153)
	)
	(arc
		(start 93.83 77.93659)
		(mid 93.906014 77.968076)
		(end 93.9375 78.04409)
		(width 0.125)
		(layer "In2.Cu")
		(net 153)
	)
	(arc
		(start 96.1375 78.75)
		(mid 96.221707 78.953293)
		(end 96.425 79.0375)
		(width 0.125)
		(layer "In2.Cu")
		(net 153)
	)
	(arc
		(start 93.9375 79.605893)
		(mid 94.034887 79.841006)
		(end 94.27 79.938393)
		(width 0.125)
		(layer "In2.Cu")
		(net 153)
	)
	(arc
		(start 95.0375 79.605893)
		(mid 95.134887 79.841006)
		(end 95.37 79.938393)
		(width 0.125)
		(layer "In2.Cu")
		(net 153)
	)
	(arc
		(start 107.72535 80.629581)
		(mid 107.822737 80.864694)
		(end 108.05785 80.962081)
		(width 0.125)
		(layer "In2.Cu")
		(net 153)
	)
	(arc
		(start 109.60035 80.52)
		(mid 109.631836 80.443986)
		(end 109.70785 80.4125)
		(width 0.125)
		(layer "In2.Cu")
		(net 153)
	)
	(arc
		(start 95.48 79.938393)
		(mid 95.715113 79.841006)
		(end 95.8125 79.605893)
		(width 0.125)
		(layer "In2.Cu")
		(net 153)
	)
	(arc
		(start 105.5191 80.475)
		(mid 105.603307 80.678293)
		(end 105.8066 80.7625)
		(width 0.125)
		(layer "In2.Cu")
		(net 153)
	)
	(arc
		(start 110.47535 80.679584)
		(mid 110.572737 80.914697)
		(end 110.80785 81.012084)
		(width 0.125)
		(layer "In2.Cu")
		(net 153)
	)
	(arc
		(start 91.08 79.938393)
		(mid 91.315113 79.841006)
		(end 91.4125 79.605893)
		(width 0.125)
		(layer "In2.Cu")
		(net 153)
	)
	(arc
		(start 90.3125 78.694092)
		(mid 90.343986 78.618078)
		(end 90.42 78.586592)
		(width 0.125)
		(layer "In2.Cu")
		(net 153)
	)
	(arc
		(start 110.36785 79.31294)
		(mid 110.443864 79.344426)
		(end 110.47535 79.42044)
		(width 0.125)
		(layer "In2.Cu")
		(net 153)
	)
	(arc
		(start 91.63 79.0375)
		(mid 91.706014 79.068986)
		(end 91.7375 79.145)
		(width 0.125)
		(layer "In2.Cu")
		(net 153)
	)
	(arc
		(start 90.6375 79.605893)
		(mid 90.734887 79.841006)
		(end 90.97 79.938393)
		(width 0.125)
		(layer "In2.Cu")
		(net 153)
	)
	(arc
		(start 108.16785 80.962081)
		(mid 108.402963 80.864694)
		(end 108.50035 80.629581)
		(width 0.125)
		(layer "In2.Cu")
		(net 153)
	)
	(arc
		(start 111.25035 80.52)
		(mid 111.281836 80.443986)
		(end 111.35785 80.4125)
		(width 0.125)
		(layer "In2.Cu")
		(net 153)
	)
	(arc
		(start 94.7125 78.594097)
		(mid 94.743986 78.518083)
		(end 94.82 78.486597)
		(width 0.125)
		(layer "In2.Cu")
		(net 153)
	)
	(arc
		(start 96.61875 79.0375)
		(mid 96.822043 78.953293)
		(end 96.90625 78.75)
		(width 0.125)
		(layer "In2.Cu")
		(net 153)
	)
	(arc
		(start 106.62535 80.579565)
		(mid 106.722737 80.814678)
		(end 106.95785 80.912065)
		(width 0.125)
		(layer "In2.Cu")
		(net 153)
	)
	(arc
		(start 93.28 79.0375)
		(mid 93.515113 78.940113)
		(end 93.6125 78.705)
		(width 0.125)
		(layer "In2.Cu")
		(net 153)
	)
	(arc
		(start 107.61785 79.962939)
		(mid 107.693864 79.994425)
		(end 107.72535 80.070439)
		(width 0.125)
		(layer "In2.Cu")
		(net 153)
	)
	(arc
		(start 106.30035 79.470439)
		(mid 106.331836 79.394425)
		(end 106.40785 79.362939)
		(width 0.125)
		(layer "In2.Cu")
		(net 153)
	)
	(arc
		(start 94.93 78.486597)
		(mid 95.006014 78.518083)
		(end 95.0375 78.594097)
		(width 0.125)
		(layer "In2.Cu")
		(net 153)
	)
	(arc
		(start 107.40035 80.070439)
		(mid 107.431836 79.994425)
		(end 107.50785 79.962939)
		(width 0.125)
		(layer "In2.Cu")
		(net 153)
	)
	(arc
		(start 96.90625 78.75)
		(mid 96.924556 78.705806)
		(end 96.96875 78.6875)
		(width 0.125)
		(layer "In2.Cu")
		(net 153)
	)
	(arc
		(start 105.4566 80.4125)
		(mid 105.500794 80.430806)
		(end 105.5191 80.475)
		(width 0.125)
		(layer "In2.Cu")
		(net 153)
	)
	(arc
		(start 90.53 78.586592)
		(mid 90.606014 78.618078)
		(end 90.6375 78.694092)
		(width 0.125)
		(layer "In2.Cu")
		(net 153)
	)
	(arc
		(start 108.50035 80.52)
		(mid 108.531836 80.443986)
		(end 108.60785 80.4125)
		(width 0.125)
		(layer "In2.Cu")
		(net 153)
	)
	(arc
		(start 94.38 79.938393)
		(mid 94.615113 79.841006)
		(end 94.7125 79.605893)
		(width 0.125)
		(layer "In2.Cu")
		(net 153)
	)
	(arc
		(start 89.98 79.938393)
		(mid 90.215113 79.841006)
		(end 90.3125 79.605893)
		(width 0.125)
		(layer "In2.Cu")
		(net 153)
	)
	(arc
		(start 97.23125 78.75)
		(mid 97.315457 78.953293)
		(end 97.51875 79.0375)
		(width 0.125)
		(layer "In2.Cu")
		(net 153)
	)
	(arc
		(start 106.01285 80.7625)
		(mid 106.216143 80.678293)
		(end 106.30035 80.475)
		(width 0.125)
		(layer "In2.Cu")
		(net 153)
	)
	(arc
		(start 115.3966 80.3625)
		(mid 115.472614 80.393986)
		(end 115.5041 80.47)
		(width 0.125)
		(layer "In2.Cu")
		(net 153)
	)
	(arc
		(start 96.075 78.6875)
		(mid 96.119194 78.705806)
		(end 96.1375 78.75)
		(width 0.125)
		(layer "In2.Cu")
		(net 153)
	)
	(arc
		(start 89.5375 79.605893)
		(mid 89.634887 79.841006)
		(end 89.87 79.938393)
		(width 0.125)
		(layer "In2.Cu")
		(net 153)
	)
	(arc
		(start 92.18 79.938393)
		(mid 92.415113 79.841006)
		(end 92.5125 79.605893)
		(width 0.125)
		(layer "In2.Cu")
		(net 153)
	)
	(arc
		(start 91.4125 79.145)
		(mid 91.443986 79.068986)
		(end 91.52 79.0375)
		(width 0.125)
		(layer "In2.Cu")
		(net 153)
	)
	(arc
		(start 109.26785 81.41206)
		(mid 109.502963 81.314673)
		(end 109.60035 81.07956)
		(width 0.125)
		(layer "In2.Cu")
		(net 153)
	)
	(arc
		(start 95.8125 78.75)
		(mid 95.830806 78.705806)
		(end 95.875 78.6875)
		(width 0.125)
		(layer "In2.Cu")
		(net 153)
	)
	(arc
		(start 92.5125 78.394108)
		(mid 92.543986 78.318094)
		(end 92.62 78.286608)
		(width 0.125)
		(layer "In2.Cu")
		(net 153)
	)
	(arc
		(start 110.91785 81.012084)
		(mid 111.152963 80.914697)
		(end 111.25035 80.679584)
		(width 0.125)
		(layer "In2.Cu")
		(net 153)
	)
	(arc
		(start 89.43 79.0375)
		(mid 89.506014 79.068986)
		(end 89.5375 79.145)
		(width 0.125)
		(layer "In2.Cu")
		(net 153)
	)
	(arc
		(start 116.2791 80.47)
		(mid 116.310586 80.393986)
		(end 116.3866 80.3625)
		(width 0.125)
		(layer "In2.Cu")
		(net 153)
	)
	(arc
		(start 92.8375 78.705)
		(mid 92.934887 78.940113)
		(end 93.17 79.0375)
		(width 0.125)
		(layer "In2.Cu")
		(net 153)
	)
	(arc
		(start 97.16875 78.6875)
		(mid 97.212944 78.705806)
		(end 97.23125 78.75)
		(width 0.125)
		(layer "In2.Cu")
		(net 153)
	)
	(segment
		(start 128.730532 76.65)
		(end 128.455532 76.375)
		(width 0.17)
		(layer "F.Cu")
		(net 154)
	)
	(segment
		(start 128.455532 76.125)
		(end 128.580532 76)
		(width 0.17)
		(layer "F.Cu")
		(net 154)
	)
	(segment
		(start 128.455532 76.375)
		(end 128.455532 76.125)
		(width 0.17)
		(layer "F.Cu")
		(net 154)
	)
	(via
		(at 61.8 108)
		(size 0.45)
		(drill 0.1)
		(layers "F.Cu" "B.Cu")
		(net 154)
	)
	(via
		(at 128.580532 76)
		(size 0.45)
		(drill 0.1)
		(layers "F.Cu" "B.Cu")
		(net 154)
	)
	(segment
		(start 63.689999 115.96)
		(end 63.614999 115.885)
		(width 0.17)
		(layer "B.Cu")
		(net 154)
	)
	(segment
		(start 61.925 108.125)
		(end 61.8 108)
		(width 0.17)
		(layer "B.Cu")
		(net 154)
	)
	(segment
		(start 64.59 115.96)
		(end 63.689999 115.96)
		(width 0.17)
		(layer "B.Cu")
		(net 154)
	)
	(segment
		(start 61.925 114.772488)
		(end 61.925 108.125)
		(width 0.17)
		(layer "B.Cu")
		(net 154)
	)
	(segment
		(start 63.037512 115.885)
		(end 61.925 114.772488)
		(width 0.17)
		(layer "B.Cu")
		(net 154)
	)
	(segment
		(start 63.614999 115.885)
		(end 63.037512 115.885)
		(width 0.17)
		(layer "B.Cu")
		(net 154)
	)
	(segment
		(start 107.6466 82.5125)
		(end 108.2466 81.9125)
		(width 0.125)
		(layer "In2.Cu")
		(net 154)
	)
	(segment
		(start 113.0466 80.6125)
		(end 114.3534 80.6125)
		(width 0.125)
		(layer "In2.Cu")
		(net 154)
	)
	(segment
		(start 61.8 108)
		(end 61.987499 108.187499)
		(width 0.125)
		(layer "In2.Cu")
		(net 154)
	)
	(segment
		(start 115.2534 82.0125)
		(end 115.8466 82.0125)
		(width 0.125)
		(layer "In2.Cu")
		(net 154)
	)
	(segment
		(start 126.7125 80.7466)
		(end 126.7125 80.1534)
		(width 0.125)
		(layer "In2.Cu")
		(net 154)
	)
	(segment
		(start 97.7466 80.4125)
		(end 98.3466 79.8125)
		(width 0.125)
		(layer "In2.Cu")
		(net 154)
	)
	(segment
		(start 99.3534 79.8125)
		(end 100.3034 80.7625)
		(width 0.125)
		(layer "In2.Cu")
		(net 154)
	)
	(segment
		(start 114.7875 81.0466)
		(end 114.7875 81.5466)
		(width 0.125)
		(layer "In2.Cu")
		(net 154)
	)
	(segment
		(start 127.4125 78.1466)
		(end 128.393033 77.166067)
		(width 0.125)
		(layer "In2.Cu")
		(net 154)
	)
	(segment
		(start 106.2534 82.5125)
		(end 107.6466 82.5125)
		(width 0.125)
		(layer "In2.Cu")
		(net 154)
	)
	(segment
		(start 64.8466 108.9125)
		(end 67.4125 106.3466)
		(width 0.125)
		(layer "In2.Cu")
		(net 154)
	)
	(segment
		(start 69.3466 84.7125)
		(end 86.8466 84.7125)
		(width 0.125)
		(layer "In2.Cu")
		(net 154)
	)
	(segment
		(start 86.8466 84.7125)
		(end 87.6125 83.9466)
		(width 0.125)
		(layer "In2.Cu")
		(net 154)
	)
	(segment
		(start 61.987499 108.187499)
		(end 61.987499 108.596599)
		(width 0.125)
		(layer "In2.Cu")
		(net 154)
	)
	(segment
		(start 116.3466 81.5125)
		(end 117.4534 81.5125)
		(width 0.125)
		(layer "In2.Cu")
		(net 154)
	)
	(segment
		(start 104.5034 80.7625)
		(end 106.2534 82.5125)
		(width 0.125)
		(layer "In2.Cu")
		(net 154)
	)
	(segment
		(start 61.987499 108.596599)
		(end 62.3034 108.9125)
		(width 0.125)
		(layer "In2.Cu")
		(net 154)
	)
	(segment
		(start 115.8466 82.0125)
		(end 116.3466 81.5125)
		(width 0.125)
		(layer "In2.Cu")
		(net 154)
	)
	(segment
		(start 98.3466 79.8125)
		(end 99.3534 79.8125)
		(width 0.125)
		(layer "In2.Cu")
		(net 154)
	)
	(segment
		(start 117.9534 82.0125)
		(end 125.4466 82.0125)
		(width 0.125)
		(layer "In2.Cu")
		(net 154)
	)
	(segment
		(start 128.393033 77.166067)
		(end 128.393033 76.187499)
		(width 0.125)
		(layer "In2.Cu")
		(net 154)
	)
	(segment
		(start 89.0975 80.4125)
		(end 97.7466 80.4125)
		(width 0.125)
		(layer "In2.Cu")
		(net 154)
	)
	(segment
		(start 126.4125 79.8534)
		(end 126.4125 79.3466)
		(width 0.125)
		(layer "In2.Cu")
		(net 154)
	)
	(segment
		(start 67.4125 86.6466)
		(end 69.3466 84.7125)
		(width 0.125)
		(layer "In2.Cu")
		(net 154)
	)
	(segment
		(start 114.7875 81.5466)
		(end 115.2534 82.0125)
		(width 0.125)
		(layer "In2.Cu")
		(net 154)
	)
	(segment
		(start 111.7466 81.9125)
		(end 113.0466 80.6125)
		(width 0.125)
		(layer "In2.Cu")
		(net 154)
	)
	(segment
		(start 126.7125 80.1534)
		(end 126.4125 79.8534)
		(width 0.125)
		(layer "In2.Cu")
		(net 154)
	)
	(segment
		(start 126.4125 79.3466)
		(end 127.4125 78.3466)
		(width 0.125)
		(layer "In2.Cu")
		(net 154)
	)
	(segment
		(start 108.2466 81.9125)
		(end 111.7466 81.9125)
		(width 0.125)
		(layer "In2.Cu")
		(net 154)
	)
	(segment
		(start 62.3034 108.9125)
		(end 64.8466 108.9125)
		(width 0.125)
		(layer "In2.Cu")
		(net 154)
	)
	(segment
		(start 127.4125 78.3466)
		(end 127.4125 78.1466)
		(width 0.125)
		(layer "In2.Cu")
		(net 154)
	)
	(segment
		(start 128.393033 76.187499)
		(end 128.580532 76)
		(width 0.125)
		(layer "In2.Cu")
		(net 154)
	)
	(segment
		(start 87.6125 81.8975)
		(end 89.0975 80.4125)
		(width 0.125)
		(layer "In2.Cu")
		(net 154)
	)
	(segment
		(start 67.4125 106.3466)
		(end 67.4125 86.6466)
		(width 0.125)
		(layer "In2.Cu")
		(net 154)
	)
	(segment
		(start 87.6125 83.9466)
		(end 87.6125 81.8975)
		(width 0.125)
		(layer "In2.Cu")
		(net 154)
	)
	(segment
		(start 117.4534 81.5125)
		(end 117.9534 82.0125)
		(width 0.125)
		(layer "In2.Cu")
		(net 154)
	)
	(segment
		(start 125.4466 82.0125)
		(end 126.7125 80.7466)
		(width 0.125)
		(layer "In2.Cu")
		(net 154)
	)
	(segment
		(start 100.3034 80.7625)
		(end 104.5034 80.7625)
		(width 0.125)
		(layer "In2.Cu")
		(net 154)
	)
	(segment
		(start 114.3534 80.6125)
		(end 114.7875 81.0466)
		(width 0.125)
		(layer "In2.Cu")
		(net 154)
	)
	(segment
		(start 136.1 86.4)
		(end 135.5 87)
		(width 0.1)
		(layer "F.Cu")
		(net 155)
	)
	(segment
		(start 136.7 86.4)
		(end 136.1 86.4)
		(width 0.1)
		(layer "F.Cu")
		(net 155)
	)
	(segment
		(start 136.3 88.6)
		(end 145 88.6)
		(width 0.1)
		(layer "F.Cu")
		(net 155)
	)
	(segment
		(start 143.5 68.5)
		(end 151.725 68.5)
		(width 0.1)
		(layer "F.Cu")
		(net 155)
	)
	(segment
		(start 64.5 95.5)
		(end 65.6 94.4)
		(width 0.1)
		(layer "F.Cu")
		(net 155)
	)
	(segment
		(start 64.5 96.2)
		(end 64.5 95.5)
		(width 0.1)
		(layer "F.Cu")
		(net 155)
	)
	(segment
		(start 141.4 66.1)
		(end 141.4 66.4)
		(width 0.1)
		(layer "F.Cu")
		(net 155)
	)
	(segment
		(start 64.75 96.45)
		(end 64.5 96.2)
		(width 0.1)
		(layer "F.Cu")
		(net 155)
	)
	(segment
		(start 151.925 68.7)
		(end 151.925 69.45)
		(width 0.1)
		(layer "F.Cu")
		(net 155)
	)
	(segment
		(start 151.925 69.45)
		(end 150.9 70.475)
		(width 0.1)
		(layer "F.Cu")
		(net 155)
	)
	(segment
		(start 137.030532 84.15)
		(end 137.030532 84.530532)
		(width 0.1)
		(layer "F.Cu")
		(net 155)
	)
	(segment
		(start 150.9 70.475)
		(end 150.9 84)
		(width 0.1)
		(layer "F.Cu")
		(net 155)
	)
	(segment
		(start 135.5 87.8)
		(end 136.3 88.6)
		(width 0.1)
		(layer "F.Cu")
		(net 155)
	)
	(segment
		(start 135.5 87)
		(end 135.5 87.8)
		(width 0.1)
		(layer "F.Cu")
		(net 155)
	)
	(segment
		(start 137.3 84.8)
		(end 137.3 85.8)
		(width 0.1)
		(layer "F.Cu")
		(net 155)
	)
	(segment
		(start 141.4 66.4)
		(end 143.5 68.5)
		(width 0.1)
		(layer "F.Cu")
		(net 155)
	)
	(segment
		(start 65.6 94.4)
		(end 66.6 94.4)
		(width 0.1)
		(layer "F.Cu")
		(net 155)
	)
	(segment
		(start 137.030532 84.530532)
		(end 137.3 84.8)
		(width 0.1)
		(layer "F.Cu")
		(net 155)
	)
	(segment
		(start 137.3 85.8)
		(end 136.7 86.4)
		(width 0.1)
		(layer "F.Cu")
		(net 155)
	)
	(segment
		(start 151.725 68.5)
		(end 151.925 68.7)
		(width 0.1)
		(layer "F.Cu")
		(net 155)
	)
	(segment
		(start 65.15 96.45)
		(end 64.75 96.45)
		(width 0.1)
		(layer "F.Cu")
		(net 155)
	)
	(via
		(at 141.4 66.1)
		(size 0.45)
		(drill 0.1)
		(layers "F.Cu" "B.Cu")
		(net 155)
	)
	(via
		(at 145 88.6)
		(size 0.45)
		(drill 0.1)
		(layers "F.Cu" "B.Cu")
		(net 155)
	)
	(via
		(at 150.9 84)
		(size 0.45)
		(drill 0.1)
		(layers "F.Cu" "B.Cu")
		(net 155)
	)
	(via
		(at 66.6 94.4)
		(size 0.45)
		(drill 0.1)
		(layers "F.Cu" "B.Cu")
		(net 155)
	)
	(segment
		(start 145 88.6)
		(end 147.1 88.6)
		(width 0.1)
		(layer "B.Cu")
		(net 155)
	)
	(segment
		(start 147.1 88.6)
		(end 150.9 84.8)
		(width 0.1)
		(layer "B.Cu")
		(net 155)
	)
	(segment
		(start 150.9 84.8)
		(end 150.9 84)
		(width 0.1)
		(layer "B.Cu")
		(net 155)
	)
	(segment
		(start 112.3 67.4)
		(end 111.4 68.3)
		(width 0.1)
		(layer "In5.Cu")
		(net 155)
	)
	(segment
		(start 141 66.1)
		(end 141.4 66.1)
		(width 0.1)
		(layer "In5.Cu")
		(net 155)
	)
	(segment
		(start 66.4 86.565686)
		(end 66.4 77.4)
		(width 0.1)
		(layer "In5.Cu")
		(net 155)
	)
	(segment
		(start 98.6 68.3)
		(end 111.4 68.3)
		(width 0.1)
		(layer "In5.Cu")
		(net 155)
	)
	(segment
		(start 125 67.4)
		(end 127.1 65.3)
		(width 0.1)
		(layer "In5.Cu")
		(net 155)
	)
	(segment
		(start 127.1 65.3)
		(end 140.2 65.3)
		(width 0.1)
		(layer "In5.Cu")
		(net 155)
	)
	(segment
		(start 98.2 68.7)
		(end 98.6 68.3)
		(width 0.1)
		(layer "In5.Cu")
		(net 155)
	)
	(segment
		(start 65.6 93.4)
		(end 65.6 87.365686)
		(width 0.1)
		(layer "In5.Cu")
		(net 155)
	)
	(segment
		(start 72.9 68.7)
		(end 98.2 68.7)
		(width 0.1)
		(layer "In5.Cu")
		(net 155)
	)
	(segment
		(start 71.6 72.2)
		(end 71.6 70)
		(width 0.1)
		(layer "In5.Cu")
		(net 155)
	)
	(segment
		(start 140.2 65.3)
		(end 141 66.1)
		(width 0.1)
		(layer "In5.Cu")
		(net 155)
	)
	(segment
		(start 65.6 87.365686)
		(end 66.4 86.565686)
		(width 0.1)
		(layer "In5.Cu")
		(net 155)
	)
	(segment
		(start 66.4 77.4)
		(end 71.6 72.2)
		(width 0.1)
		(layer "In5.Cu")
		(net 155)
	)
	(segment
		(start 71.6 70)
		(end 72.9 68.7)
		(width 0.1)
		(layer "In5.Cu")
		(net 155)
	)
	(segment
		(start 66.6 94.4)
		(end 65.6 93.4)
		(width 0.1)
		(layer "In5.Cu")
		(net 155)
	)
	(segment
		(start 125 67.4)
		(end 112.3 67.4)
		(width 0.1)
		(layer "In5.Cu")
		(net 155)
	)
	(segment
		(start 125.755532 79.925)
		(end 125.755532 80.275)
		(width 0.17)
		(layer "F.Cu")
		(net 157)
	)
	(segment
		(start 126.030532 79.65)
		(end 125.755532 79.925)
		(width 0.17)
		(layer "F.Cu")
		(net 157)
	)
	(segment
		(start 125.755532 80.275)
		(end 125.880532 80.4)
		(width 0.17)
		(layer "F.Cu")
		(net 157)
	)
	(via
		(at 125.880532 80.4)
		(size 0.45)
		(drill 0.1)
		(layers "F.Cu" "B.Cu")
		(net 157)
	)
	(via
		(at 63.1 103.411)
		(size 0.45)
		(drill 0.1)
		(layers "F.Cu" "B.Cu")
		(net 157)
	)
	(segment
		(start 63.225 103.536)
		(end 63.1 103.411)
		(width 0.17)
		(layer "B.Cu")
		(net 157)
	)
	(segment
		(start 63.615999 103.536)
		(end 63.225 103.536)
		(width 0.17)
		(layer "B.Cu")
		(net 157)
	)
	(segment
		(start 63.689999 103.462)
		(end 63.615999 103.536)
		(width 0.17)
		(layer "B.Cu")
		(net 157)
	)
	(segment
		(start 64.59 103.462)
		(end 63.689999 103.462)
		(width 0.17)
		(layer "B.Cu")
		(net 157)
	)
	(segment
		(start 63.287499 103.598499)
		(end 63.842401 103.598499)
		(width 0.125)
		(layer "In2.Cu")
		(net 157)
	)
	(segment
		(start 124.4534 80.0875)
		(end 124.8534 79.6875)
		(width 0.125)
		(layer "In2.Cu")
		(net 157)
	)
	(segment
		(start 99.5866 76.825)
		(end 99.6966 76.825)
		(width 0.125)
		(layer "In2.Cu")
		(net 157)
	)
	(segment
		(start 104.7541 78.2425)
		(end 104.7541 77.97)
		(width 0.125)
		(layer "In2.Cu")
		(net 157)
	)
	(segment
		(start 125.693033 80.212501)
		(end 125.880532 80.4)
		(width 0.125)
		(layer "In2.Cu")
		(net 157)
	)
	(segment
		(start 108.797871 77.89787)
		(end 108.797871 77.897871)
		(width 0.125)
		(layer "In2.Cu")
		(net 157)
	)
	(segment
		(start 93.3216 77.1875)
		(end 95.6466 77.1875)
		(width 0.125)
		(layer "In2.Cu")
		(net 157)
	)
	(segment
		(start 97.9534 77.2875)
		(end 98.0466 77.2875)
		(width 0.125)
		(layer "In2.Cu")
		(net 157)
	)
	(segment
		(start 85.1534 77.1875)
		(end 85.2466 77.1875)
		(width 0.125)
		(layer "In2.Cu")
		(net 157)
	)
	(segment
		(start 100.3541 77.7425)
		(end 100.3541 77.21875)
		(width 0.125)
		(layer "In2.Cu")
		(net 157)
	)
	(segment
		(start 96.4466 77.9875)
		(end 97.2534 77.9875)
		(width 0.125)
		(layer "In2.Cu")
		(net 157)
	)
	(segment
		(start 68.8034 81.9875)
		(end 83.4534 81.9875)
		(width 0.125)
		(layer "In2.Cu")
		(net 157)
	)
	(segment
		(start 123.9466 80.0875)
		(end 124.4534 80.0875)
		(width 0.125)
		(layer "In2.Cu")
		(net 157)
	)
	(segment
		(start 105.6034 77.6375)
		(end 105.9534 77.2875)
		(width 0.125)
		(layer "In2.Cu")
		(net 157)
	)
	(segment
		(start 83.4534 81.9875)
		(end 83.9875 81.4534)
		(width 0.125)
		(layer "In2.Cu")
		(net 157)
	)
	(segment
		(start 64.0875 87.0334)
		(end 66.3375 84.7834)
		(width 0.125)
		(layer "In2.Cu")
		(net 157)
	)
	(segment
		(start 91.9116 76.7875)
		(end 92.9216 76.7875)
		(width 0.125)
		(layer "In2.Cu")
		(net 157)
	)
	(segment
		(start 86.09035 77.11875)
		(end 86.09035 77.48125)
		(width 0.125)
		(layer "In2.Cu")
		(net 157)
	)
	(segment
		(start 63.842401 103.598499)
		(end 64.3875 103.0534)
		(width 0.125)
		(layer "In2.Cu")
		(net 157)
	)
	(segment
		(start 83.9875 81.4534)
		(end 83.9875 78.3534)
		(width 0.125)
		(layer "In2.Cu")
		(net 157)
	)
	(segment
		(start 109.976971 77.814785)
		(end 109.501442 78.290315)
		(width 0.125)
		(layer "In2.Cu")
		(net 157)
	)
	(segment
		(start 99.0366 77.2875)
		(end 99.1466 77.2875)
		(width 0.125)
		(layer "In2.Cu")
		(net 157)
	)
	(segment
		(start 121.0534 77.1875)
		(end 122.3466 77.1875)
		(width 0.125)
		(layer "In2.Cu")
		(net 157)
	)
	(segment
		(start 108.184457 78.203695)
		(end 108.262238 78.281476)
		(width 0.125)
		(layer "In2.Cu")
		(net 157)
	)
	(segment
		(start 66.3375 84.4534)
		(end 68.8034 81.9875)
		(width 0.125)
		(layer "In2.Cu")
		(net 157)
	)
	(segment
		(start 91.3616 76.275)
		(end 91.4716 76.275)
		(width 0.125)
		(layer "In2.Cu")
		(net 157)
	)
	(segment
		(start 101.7866 77.2875)
		(end 103.7466 77.2875)
		(width 0.125)
		(layer "In2.Cu")
		(net 157)
	)
	(segment
		(start 66.3375 84.7834)
		(end 66.3375 84.4534)
		(width 0.125)
		(layer "In2.Cu")
		(net 157)
	)
	(segment
		(start 108.953433 77.742306)
		(end 109.428964 77.266778)
		(width 0.125)
		(layer "In2.Cu")
		(net 157)
	)
	(segment
		(start 113.2534 77.3875)
		(end 116.4466 77.3875)
		(width 0.125)
		(layer "In2.Cu")
		(net 157)
	)
	(segment
		(start 117.7466 78.6875)
		(end 119.5534 78.6875)
		(width 0.125)
		(layer "In2.Cu")
		(net 157)
	)
	(segment
		(start 64.3875 101.0466)
		(end 64.0875 100.7466)
		(width 0.125)
		(layer "In2.Cu")
		(net 157)
	)
	(segment
		(start 86.7091 77.1875)
		(end 90.4284 77.1875)
		(width 0.125)
		(layer "In2.Cu")
		(net 157)
	)
	(segment
		(start 92.9216 76.7875)
		(end 93.3216 77.1875)
		(width 0.125)
		(layer "In2.Cu")
		(net 157)
	)
	(segment
		(start 104.4291 77.97)
		(end 104.4291 78.2425)
		(width 0.125)
		(layer "In2.Cu")
		(net 157)
	)
	(segment
		(start 100.1366 77.85)
		(end 100.2466 77.85)
		(width 0.125)
		(layer "In2.Cu")
		(net 157)
	)
	(segment
		(start 125.693033 80.033933)
		(end 125.693033 80.212501)
		(width 0.125)
		(layer "In2.Cu")
		(net 157)
	)
	(segment
		(start 108.797871 77.897871)
		(end 108.873885 77.821857)
		(width 0.125)
		(layer "In2.Cu")
		(net 157)
	)
	(segment
		(start 122.9125 79.0534)
		(end 123.9466 80.0875)
		(width 0.125)
		(layer "In2.Cu")
		(net 157)
	)
	(segment
		(start 91.0291 76.68)
		(end 91.0291 76.6075)
		(width 0.125)
		(layer "In2.Cu")
		(net 157)
	)
	(segment
		(start 108.414266 78.281476)
		(end 108.797871 77.89787)
		(width 0.125)
		(layer "In2.Cu")
		(net 157)
	)
	(segment
		(start 85.228964 78.533219)
		(end 84.753434 78.057689)
		(width 0.125)
		(layer "In2.Cu")
		(net 157)
	)
	(segment
		(start 103.7466 77.2875)
		(end 104.0966 77.6375)
		(width 0.125)
		(layer "In2.Cu")
		(net 157)
	)
	(segment
		(start 64.0875 100.7466)
		(end 64.0875 87.0334)
		(width 0.125)
		(layer "In2.Cu")
		(net 157)
	)
	(segment
		(start 100.0291 77.1575)
		(end 100.0291 77.7425)
		(width 0.125)
		(layer "In2.Cu")
		(net 157)
	)
	(segment
		(start 90.4284 77.1875)
		(end 90.8284 76.7875)
		(width 0.125)
		(layer "In2.Cu")
		(net 157)
	)
	(segment
		(start 98.9291 77.0575)
		(end 98.9291 77.18)
		(width 0.125)
		(layer "In2.Cu")
		(net 157)
	)
	(segment
		(start 97.2534 77.9875)
		(end 97.9534 77.2875)
		(width 0.125)
		(layer "In2.Cu")
		(net 157)
	)
	(segment
		(start 116.4466 77.3875)
		(end 117.7466 78.6875)
		(width 0.125)
		(layer "In2.Cu")
		(net 157)
	)
	(segment
		(start 101.1291 77.21875)
		(end 101.1291 78.2425)
		(width 0.125)
		(layer "In2.Cu")
		(net 157)
	)
	(segment
		(start 84.523626 78.2875)
		(end 84.999155 78.763029)
		(width 0.125)
		(layer "In2.Cu")
		(net 157)
	)
	(segment
		(start 109.6466 78.5875)
		(end 112.0534 78.5875)
		(width 0.125)
		(layer "In2.Cu")
		(net 157)
	)
	(segment
		(start 83.9875 78.3534)
		(end 84.0534 78.2875)
		(width 0.125)
		(layer "In2.Cu")
		(net 157)
	)
	(segment
		(start 105.0866 77.6375)
		(end 105.6034 77.6375)
		(width 0.125)
		(layer "In2.Cu")
		(net 157)
	)
	(segment
		(start 101.4541 78.2425)
		(end 101.4541 77.62)
		(width 0.125)
		(layer "In2.Cu")
		(net 157)
	)
	(segment
		(start 122.9125 77.7534)
		(end 122.9125 79.0534)
		(width 0.125)
		(layer "In2.Cu")
		(net 157)
	)
	(segment
		(start 95.6466 77.1875)
		(end 96.4466 77.9875)
		(width 0.125)
		(layer "In2.Cu")
		(net 157)
	)
	(segment
		(start 84.831217 77.509683)
		(end 85.1534 77.1875)
		(width 0.125)
		(layer "In2.Cu")
		(net 157)
	)
	(segment
		(start 112.0534 78.5875)
		(end 113.2534 77.3875)
		(width 0.125)
		(layer "In2.Cu")
		(net 157)
	)
	(segment
		(start 109.501442 78.442343)
		(end 109.6466 78.5875)
		(width 0.125)
		(layer "In2.Cu")
		(net 157)
	)
	(segment
		(start 84.753434 77.587463)
		(end 84.831217 77.509683)
		(width 0.125)
		(layer "In2.Cu")
		(net 157)
	)
	(segment
		(start 101.2366 78.35)
		(end 101.3466 78.35)
		(width 0.125)
		(layer "In2.Cu")
		(net 157)
	)
	(segment
		(start 125.3466 79.6875)
		(end 125.693033 80.033933)
		(width 0.125)
		(layer "In2.Cu")
		(net 157)
	)
	(segment
		(start 122.3466 77.1875)
		(end 122.9125 77.7534)
		(width 0.125)
		(layer "In2.Cu")
		(net 157)
	)
	(segment
		(start 108.3466 77.2875)
		(end 108.412499 77.3534)
		(width 0.125)
		(layer "In2.Cu")
		(net 157)
	)
	(segment
		(start 105.9534 77.2875)
		(end 108.3466 77.2875)
		(width 0.125)
		(layer "In2.Cu")
		(net 157)
	)
	(segment
		(start 108.412499 77.823626)
		(end 108.184457 78.051667)
		(width 0.125)
		(layer "In2.Cu")
		(net 157)
	)
	(segment
		(start 85.151183 78.763029)
		(end 85.228964 78.685247)
		(width 0.125)
		(layer "In2.Cu")
		(net 157)
	)
	(segment
		(start 104.5366 78.35)
		(end 104.6466 78.35)
		(width 0.125)
		(layer "In2.Cu")
		(net 157)
	)
	(segment
		(start 63.1 103.411)
		(end 63.287499 103.598499)
		(width 0.125)
		(layer "In2.Cu")
		(net 157)
	)
	(segment
		(start 100.64785 76.925)
		(end 100.83535 76.925)
		(width 0.125)
		(layer "In2.Cu")
		(net 157)
	)
	(segment
		(start 98.1541 77.18)
		(end 98.1541 77.0575)
		(width 0.125)
		(layer "In2.Cu")
		(net 157)
	)
	(segment
		(start 108.873885 77.821857)
		(end 108.953433 77.742306)
		(width 0.125)
		(layer "In2.Cu")
		(net 157)
	)
	(segment
		(start 119.5534 78.6875)
		(end 121.0534 77.1875)
		(width 0.125)
		(layer "In2.Cu")
		(net 157)
	)
	(segment
		(start 64.3875 103.0534)
		(end 64.3875 101.0466)
		(width 0.125)
		(layer "In2.Cu")
		(net 157)
	)
	(segment
		(start 99.2541 77.18)
		(end 99.2541 77.1575)
		(width 0.125)
		(layer "In2.Cu")
		(net 157)
	)
	(segment
		(start 109.89919 77.266778)
		(end 109.976971 77.344559)
		(width 0.125)
		(layer "In2.Cu")
		(net 157)
	)
	(segment
		(start 85.6091 76.825)
		(end 85.7966 76.825)
		(width 0.125)
		(layer "In2.Cu")
		(net 157)
	)
	(segment
		(start 86.1591 77.55)
		(end 86.3466 77.55)
		(width 0.125)
		(layer "In2.Cu")
		(net 157)
	)
	(segment
		(start 98.4866 76.725)
		(end 98.5966 76.725)
		(width 0.125)
		(layer "In2.Cu")
		(net 157)
	)
	(segment
		(start 91.8041 76.6075)
		(end 91.8041 76.68)
		(width 0.125)
		(layer "In2.Cu")
		(net 157)
	)
	(segment
		(start 90.8284 76.7875)
		(end 90.9216 76.7875)
		(width 0.125)
		(layer "In2.Cu")
		(net 157)
	)
	(segment
		(start 124.8534 79.6875)
		(end 125.3466 79.6875)
		(width 0.125)
		(layer "In2.Cu")
		(net 157)
	)
	(arc
		(start 91.8041 76.68)
		(mid 91.835586 76.756014)
		(end 91.9116 76.7875)
		(width 0.125)
		(layer "In2.Cu")
		(net 157)
	)
	(arc
		(start 104.7541 77.97)
		(mid 104.851487 77.734887)
		(end 105.0866 77.6375)
		(width 0.125)
		(layer "In2.Cu")
		(net 157)
	)
	(arc
		(start 98.5966 76.725)
		(mid 98.831713 76.822387)
		(end 98.9291 77.0575)
		(width 0.125)
		(layer "In2.Cu")
		(net 157)
	)
	(arc
		(start 104.0966 77.6375)
		(mid 104.331713 77.734887)
		(end 104.4291 77.97)
		(width 0.125)
		(layer "In2.Cu")
		(net 157)
	)
	(arc
		(start 86.41535 77.48125)
		(mid 86.501387 77.273537)
		(end 86.7091 77.1875)
		(width 0.125)
		(layer "In2.Cu")
		(net 157)
	)
	(arc
		(start 100.83535 76.925)
		(mid 101.043063 77.011037)
		(end 101.1291 77.21875)
		(width 0.125)
		(layer "In2.Cu")
		(net 157)
	)
	(arc
		(start 84.999155 78.763029)
		(mid 85.075169 78.794515)
		(end 85.151183 78.763029)
		(width 0.125)
		(layer "In2.Cu")
		(net 157)
	)
	(arc
		(start 109.501442 78.290315)
		(mid 109.469956 78.366329)
		(end 109.501442 78.442343)
		(width 0.125)
		(layer "In2.Cu")
		(net 157)
	)
	(arc
		(start 104.6466 78.35)
		(mid 104.722614 78.318514)
		(end 104.7541 78.2425)
		(width 0.125)
		(layer "In2.Cu")
		(net 157)
	)
	(arc
		(start 85.31535 77.11875)
		(mid 85.401387 76.911037)
		(end 85.6091 76.825)
		(width 0.125)
		(layer "In2.Cu")
		(net 157)
	)
	(arc
		(start 99.1466 77.2875)
		(mid 99.222614 77.256014)
		(end 99.2541 77.18)
		(width 0.125)
		(layer "In2.Cu")
		(net 157)
	)
	(arc
		(start 86.09035 77.48125)
		(mid 86.110486 77.529864)
		(end 86.1591 77.55)
		(width 0.125)
		(layer "In2.Cu")
		(net 157)
	)
	(arc
		(start 109.428964 77.266778)
		(mid 109.664077 77.169391)
		(end 109.89919 77.266778)
		(width 0.125)
		(layer "In2.Cu")
		(net 157)
	)
	(arc
		(start 91.4716 76.275)
		(mid 91.706713 76.372387)
		(end 91.8041 76.6075)
		(width 0.125)
		(layer "In2.Cu")
		(net 157)
	)
	(arc
		(start 98.0466 77.2875)
		(mid 98.122614 77.256014)
		(end 98.1541 77.18)
		(width 0.125)
		(layer "In2.Cu")
		(net 157)
	)
	(arc
		(start 85.7966 76.825)
		(mid 86.004313 76.911037)
		(end 86.09035 77.11875)
		(width 0.125)
		(layer "In2.Cu")
		(net 157)
	)
	(arc
		(start 85.228964 78.685247)
		(mid 85.26045 78.609233)
		(end 85.228964 78.533219)
		(width 0.125)
		(layer "In2.Cu")
		(net 157)
	)
	(arc
		(start 100.3541 77.21875)
		(mid 100.440137 77.011037)
		(end 100.64785 76.925)
		(width 0.125)
		(layer "In2.Cu")
		(net 157)
	)
	(arc
		(start 108.262238 78.281476)
		(mid 108.338252 78.312962)
		(end 108.414266 78.281476)
		(width 0.125)
		(layer "In2.Cu")
		(net 157)
	)
	(arc
		(start 84.753434 78.057689)
		(mid 84.656047 77.822576)
		(end 84.753434 77.587463)
		(width 0.125)
		(layer "In2.Cu")
		(net 157)
	)
	(arc
		(start 100.2466 77.85)
		(mid 100.322614 77.818514)
		(end 100.3541 77.7425)
		(width 0.125)
		(layer "In2.Cu")
		(net 157)
	)
	(arc
		(start 99.2541 77.1575)
		(mid 99.351487 76.922387)
		(end 99.5866 76.825)
		(width 0.125)
		(layer "In2.Cu")
		(net 157)
	)
	(arc
		(start 104.4291 78.2425)
		(mid 104.460586 78.318514)
		(end 104.5366 78.35)
		(width 0.125)
		(layer "In2.Cu")
		(net 157)
	)
	(arc
		(start 99.6966 76.825)
		(mid 99.931713 76.922387)
		(end 100.0291 77.1575)
		(width 0.125)
		(layer "In2.Cu")
		(net 157)
	)
	(arc
		(start 108.184457 78.051667)
		(mid 108.152971 78.127681)
		(end 108.184457 78.203695)
		(width 0.125)
		(layer "In2.Cu")
		(net 157)
	)
	(arc
		(start 85.2466 77.1875)
		(mid 85.295214 77.167364)
		(end 85.31535 77.11875)
		(width 0.125)
		(layer "In2.Cu")
		(net 157)
	)
	(arc
		(start 84.0534 78.2875)
		(mid 84.288513 78.190113)
		(end 84.523626 78.2875)
		(width 0.125)
		(layer "In2.Cu")
		(net 157)
	)
	(arc
		(start 101.1291 78.2425)
		(mid 101.160586 78.318514)
		(end 101.2366 78.35)
		(width 0.125)
		(layer "In2.Cu")
		(net 157)
	)
	(arc
		(start 109.976971 77.344559)
		(mid 110.074358 77.579672)
		(end 109.976971 77.814785)
		(width 0.125)
		(layer "In2.Cu")
		(net 157)
	)
	(arc
		(start 100.0291 77.7425)
		(mid 100.060586 77.818514)
		(end 100.1366 77.85)
		(width 0.125)
		(layer "In2.Cu")
		(net 157)
	)
	(arc
		(start 98.1541 77.0575)
		(mid 98.251487 76.822387)
		(end 98.4866 76.725)
		(width 0.125)
		(layer "In2.Cu")
		(net 157)
	)
	(arc
		(start 101.3466 78.35)
		(mid 101.422614 78.318514)
		(end 101.4541 78.2425)
		(width 0.125)
		(layer "In2.Cu")
		(net 157)
	)
	(arc
		(start 108.412499 77.3534)
		(mid 108.509886 77.588513)
		(end 108.412499 77.823626)
		(width 0.125)
		(layer "In2.Cu")
		(net 157)
	)
	(arc
		(start 91.0291 76.6075)
		(mid 91.126487 76.372387)
		(end 91.3616 76.275)
		(width 0.125)
		(layer "In2.Cu")
		(net 157)
	)
	(arc
		(start 98.9291 77.18)
		(mid 98.960586 77.256014)
		(end 99.0366 77.2875)
		(width 0.125)
		(layer "In2.Cu")
		(net 157)
	)
	(arc
		(start 101.4541 77.62)
		(mid 101.551487 77.384887)
		(end 101.7866 77.2875)
		(width 0.125)
		(layer "In2.Cu")
		(net 157)
	)
	(arc
		(start 90.9216 76.7875)
		(mid 90.997614 76.756014)
		(end 91.0291 76.68)
		(width 0.125)
		(layer "In2.Cu")
		(net 157)
	)
	(arc
		(start 86.3466 77.55)
		(mid 86.395214 77.529864)
		(end 86.41535 77.48125)
		(width 0.125)
		(layer "In2.Cu")
		(net 157)
	)
	(segment
		(start 139.530532 85.65)
		(end 139.530532 86.969468)
		(width 0.1)
		(layer "F.Cu")
		(net 158)
	)
	(segment
		(start 132.05 98.6)
		(end 130.83 98.6)
		(width 0.1)
		(layer "F.Cu")
		(net 158)
	)
	(segment
		(start 139.530532 86.969468)
		(end 139.5 87)
		(width 0.1)
		(layer "F.Cu")
		(net 158)
	)
	(segment
		(start 130.43 98.2)
		(end 128.6 98.2)
		(width 0.1)
		(layer "F.Cu")
		(net 158)
	)
	(segment
		(start 128.6 98.2)
		(end 128.4 98)
		(width 0.1)
		(layer "F.Cu")
		(net 158)
	)
	(segment
		(start 130.83 98.6)
		(end 130.43 98.2)
		(width 0.1)
		(layer "F.Cu")
		(net 158)
	)
	(segment
		(start 132.35 98.3)
		(end 132.05 98.6)
		(width 0.1)
		(layer "F.Cu")
		(net 158)
	)
	(segment
		(start 128.4 98)
		(end 128.4 97.5)
		(width 0.1)
		(layer "F.Cu")
		(net 158)
	)
	(via
		(at 128.4 97.5)
		(size 0.45)
		(drill 0.1)
		(layers "F.Cu" "B.Cu")
		(net 158)
	)
	(via
		(at 79.585532 89.105)
		(size 0.45)
		(drill 0.1)
		(layers "F.Cu" "B.Cu")
		(net 158)
	)
	(via
		(at 139.5 87)
		(size 0.45)
		(drill 0.1)
		(layers "F.Cu" "B.Cu")
		(net 158)
	)
	(via
		(at 132.35 98.3)
		(size 0.45)
		(drill 0.1)
		(layers "F.Cu" "B.Cu")
		(net 158)
	)
	(segment
		(start 80.25 94.1)
		(end 81.4 92.95)
		(width 0.1)
		(layer "In5.Cu")
		(net 158)
	)
	(segment
		(start 80.675 98.425)
		(end 80.25 98)
		(width 0.1)
		(layer "In5.Cu")
		(net 158)
	)
	(segment
		(start 122.95147 98.25147)
		(end 120.20294 101)
		(width 0.1)
		(layer "In5.Cu")
		(net 158)
	)
	(segment
		(start 85.4 100.6)
		(end 83.225 98.425)
		(width 0.1)
		(layer "In5.Cu")
		(net 158)
	)
	(segment
		(start 97.7 110.65)
		(end 93.35 115)
		(width 0.1)
		(layer "In5.Cu")
		(net 158)
	)
	(segment
		(start 84.225 114.625)
		(end 84.225 107.925)
		(width 0.1)
		(layer "In5.Cu")
		(net 158)
	)
	(segment
		(start 133.1 94.05)
		(end 139.5 87.65)
		(width 0.1)
		(layer "In5.Cu")
		(net 158)
	)
	(segment
		(start 80.25 98)
		(end 80.25 94.1)
		(width 0.1)
		(layer "In5.Cu")
		(net 158)
	)
	(segment
		(start 86.225 115)
		(end 86.15 114.925)
		(width 0.1)
		(layer "In5.Cu")
		(net 158)
	)
	(segment
		(start 86.15 114.925)
		(end 84.525 114.925)
		(width 0.1)
		(layer "In5.Cu")
		(net 158)
	)
	(segment
		(start 120.20294 101)
		(end 99.937258 101)
		(width 0.1)
		(layer "In5.Cu")
		(net 158)
	)
	(segment
		(start 80.280532 89.8)
		(end 79.585532 89.105)
		(width 0.1)
		(layer "In5.Cu")
		(net 158)
	)
	(segment
		(start 132.35 98.3)
		(end 133.1 97.55)
		(width 0.1)
		(layer "In5.Cu")
		(net 158)
	)
	(segment
		(start 139.5 87.65)
		(end 139.5 87)
		(width 0.1)
		(layer "In5.Cu")
		(net 158)
	)
	(segment
		(start 84.525 114.925)
		(end 84.225 114.625)
		(width 0.1)
		(layer "In5.Cu")
		(net 158)
	)
	(segment
		(start 81.4 92.95)
		(end 81.4 90)
		(width 0.1)
		(layer "In5.Cu")
		(net 158)
	)
	(segment
		(start 128.4 97.5)
		(end 127.575 97.5)
		(width 0.1)
		(layer "In5.Cu")
		(net 158)
	)
	(segment
		(start 83.225 98.425)
		(end 80.675 98.425)
		(width 0.1)
		(layer "In5.Cu")
		(net 158)
	)
	(segment
		(start 81.4 90)
		(end 81.2 89.8)
		(width 0.1)
		(layer "In5.Cu")
		(net 158)
	)
	(segment
		(start 127.575 97.5)
		(end 126.82353 98.25147)
		(width 0.1)
		(layer "In5.Cu")
		(net 158)
	)
	(segment
		(start 85.4 106.75)
		(end 85.4 100.6)
		(width 0.1)
		(layer "In5.Cu")
		(net 158)
	)
	(segment
		(start 97.7 103.237258)
		(end 97.7 110.65)
		(width 0.1)
		(layer "In5.Cu")
		(net 158)
	)
	(segment
		(start 133.1 97.55)
		(end 133.1 94.05)
		(width 0.1)
		(layer "In5.Cu")
		(net 158)
	)
	(segment
		(start 126.82353 98.25147)
		(end 122.95147 98.25147)
		(width 0.1)
		(layer "In5.Cu")
		(net 158)
	)
	(segment
		(start 93.35 115)
		(end 86.225 115)
		(width 0.1)
		(layer "In5.Cu")
		(net 158)
	)
	(segment
		(start 84.225 107.925)
		(end 85.4 106.75)
		(width 0.1)
		(layer "In5.Cu")
		(net 158)
	)
	(segment
		(start 81.2 89.8)
		(end 80.280532 89.8)
		(width 0.1)
		(layer "In5.Cu")
		(net 158)
	)
	(segment
		(start 99.937258 101)
		(end 97.7 103.237258)
		(width 0.1)
		(layer "In5.Cu")
		(net 158)
	)
	(via
		(at 192.4 65.574999)
		(size 0.45)
		(drill 0.1)
		(layers "F.Cu" "B.Cu")
		(net 160)
	)
	(via
		(at 131.630532 78.15)
		(size 0.45)
		(drill 0.1)
		(layers "F.Cu" "B.Cu")
		(net 160)
	)
	(segment
		(start 198.658 59.290001)
		(end 198.583 59.365001)
		(width 0.17)
		(layer "B.Cu")
		(net 160)
	)
	(segment
		(start 198.658 58.39)
		(end 198.658 59.290001)
		(width 0.17)
		(layer "B.Cu")
		(net 160)
	)
	(segment
		(start 198.583 59.365001)
		(end 198.583 61.664488)
		(width 0.17)
		(layer "B.Cu")
		(net 160)
	)
	(segment
		(start 198.583 61.664488)
		(end 194.784989 65.462499)
		(width 0.17)
		(layer "B.Cu")
		(net 160)
	)
	(segment
		(start 194.784989 65.462499)
		(end 192.5125 65.462499)
		(width 0.17)
		(layer "B.Cu")
		(net 160)
	)
	(segment
		(start 192.5125 65.462499)
		(end 192.4 65.574999)
		(width 0.17)
		(layer "B.Cu")
		(net 160)
	)
	(segment
		(start 167.481071 77.565209)
		(end 167.941828 78.025966)
		(width 0.125)
		(layer "In2.Cu")
		(net 160)
	)
	(segment
		(start 166.805633 77.985787)
		(end 166.933067 78.113221)
		(width 0.125)
		(layer "In2.Cu")
		(net 160)
	)
	(segment
		(start 170.822155 74.224128)
		(end 171.282911 74.684884)
		(width 0.125)
		(layer "In2.Cu")
		(net 160)
	)
	(segment
		(start 164.6675 79.22)
		(end 164.6675 79.651608)
		(width 0.125)
		(layer "In2.Cu")
		(net 160)
	)
	(segment
		(start 170.464914 74.326505)
		(end 170.592347 74.453938)
		(width 0.125)
		(layer "In2.Cu")
		(net 160)
	)
	(segment
		(start 171.242732 73.548687)
		(end 171.370165 73.67612)
		(width 0.125)
		(layer "In2.Cu")
		(net 160)
	)
	(segment
		(start 167.710883 77.3354)
		(end 168.171615 77.796132)
		(width 0.125)
		(layer "In2.Cu")
		(net 160)
	)
	(segment
		(start 169.036707 76.009573)
		(end 169.036711 76.009574)
		(width 0.125)
		(layer "In2.Cu")
		(net 160)
	)
	(segment
		(start 170.044337 75.001946)
		(end 170.505099 75.462708)
		(width 0.125)
		(layer "In2.Cu")
		(net 160)
	)
	(segment
		(start 167.583451 77.207969)
		(end 167.710885 77.335403)
		(width 0.125)
		(layer "In2.Cu")
		(net 160)
	)
	(segment
		(start 169.814525 75.231755)
		(end 170.275288 75.692518)
		(width 0.125)
		(layer "In2.Cu")
		(net 160)
	)
	(segment
		(start 167.353642 77.437777)
		(end 167.481075 77.56521)
		(width 0.125)
		(layer "In2.Cu")
		(net 160)
	)
	(segment
		(start 166.703253 78.343026)
		(end 166.703257 78.343028)
		(width 0.125)
		(layer "In2.Cu")
		(net 160)
	)
	(segment
		(start 172.530931 73.907042)
		(end 172.608712 73.82926)
		(width 0.125)
		(layer "In2.Cu")
		(net 160)
	)
	(segment
		(start 168.909273 75.786365)
		(end 169.043311 75.652328)
		(width 0.125)
		(layer "In2.Cu")
		(net 160)
	)
	(segment
		(start 169.916905 74.874515)
		(end 170.044339 75.001949)
		(width 0.125)
		(layer "In2.Cu")
		(net 160)
	)
	(segment
		(start 170.822157 74.224131)
		(end 170.822155 74.224128)
		(width 0.125)
		(layer "In2.Cu")
		(net 160)
	)
	(segment
		(start 168.361279 76.430161)
		(end 168.488702 76.557584)
		(width 0.125)
		(layer "In2.Cu")
		(net 160)
	)
	(segment
		(start 168.909274 75.882137)
		(end 169.036711 76.009574)
		(width 0.125)
		(layer "In2.Cu")
		(net 160)
	)
	(segment
		(start 166.933065 78.113218)
		(end 167.393821 78.573974)
		(width 0.125)
		(layer "In2.Cu")
		(net 160)
	)
	(segment
		(start 169.687096 75.104323)
		(end 169.814529 75.231756)
		(width 0.125)
		(layer "In2.Cu")
		(net 160)
	)
	(segment
		(start 169.139083 75.652329)
		(end 169.26652 75.779766)
		(width 0.125)
		(layer "In2.Cu")
		(net 160)
	)
	(segment
		(start 172.381326 72.824056)
		(end 179.805383 65.399999)
		(width 0.125)
		(layer "In2.Cu")
		(net 160)
	)
	(segment
		(start 171.472541 73.318879)
		(end 171.599975 73.446313)
		(width 0.125)
		(layer "In2.Cu")
		(net 160)
	)
	(segment
		(start 170.592343 74.453937)
		(end 170.592347 74.453938)
		(width 0.125)
		(layer "In2.Cu")
		(net 160)
	)
	(segment
		(start 170.464914 74.230737)
		(end 170.598955 74.096697)
		(width 0.125)
		(layer "In2.Cu")
		(net 160)
	)
	(segment
		(start 169.26652 75.779766)
		(end 169.266519 75.779764)
		(width 0.125)
		(layer "In2.Cu")
		(net 160)
	)
	(segment
		(start 170.044339 75.001949)
		(end 170.044337 75.001946)
		(width 0.125)
		(layer "In2.Cu")
		(net 160)
	)
	(segment
		(start 165.4425 79.651608)
		(end 165.4425 79.22)
		(width 0.125)
		(layer "In2.Cu")
		(net 160)
	)
	(segment
		(start 171.753137 74.684884)
		(end 171.830918 74.607102)
		(width 0.125)
		(layer "In2.Cu")
		(net 160)
	)
	(segment
		(start 168.488701 76.557582)
		(end 168.949439 77.01832)
		(width 0.125)
		(layer "In2.Cu")
		(net 160)
	)
	(segment
		(start 169.419665 77.01832)
		(end 169.497446 76.940538)
		(width 0.125)
		(layer "In2.Cu")
		(net 160)
	)
	(segment
		(start 131.630532 78.15)
		(end 131.968031 78.487499)
		(width 0.125)
		(layer "In2.Cu")
		(net 160)
	)
	(segment
		(start 168.258889 76.787391)
		(end 168.719622 77.248124)
		(width 0.125)
		(layer "In2.Cu")
		(net 160)
	)
	(segment
		(start 166.575824 78.215595)
		(end 166.703257 78.343028)
		(width 0.125)
		(layer "In2.Cu")
		(net 160)
	)
	(segment
		(start 170.694723 74.096697)
		(end 170.822157 74.224131)
		(width 0.125)
		(layer "In2.Cu")
		(net 160)
	)
	(segment
		(start 192.225001 65.4)
		(end 192.4 65.574999)
		(width 0.125)
		(layer "In2.Cu")
		(net 160)
	)
	(segment
		(start 131.968031 78.727131)
		(end 132.3534 79.1125)
		(width 0.125)
		(layer "In2.Cu")
		(net 160)
	)
	(segment
		(start 165.55 79.1125)
		(end 166.092882 79.1125)
		(width 0.125)
		(layer "In2.Cu")
		(net 160)
	)
	(segment
		(start 168.13147 76.659969)
		(end 168.258893 76.787392)
		(width 0.125)
		(layer "In2.Cu")
		(net 160)
	)
	(segment
		(start 131.968031 78.487499)
		(end 131.968031 78.727131)
		(width 0.125)
		(layer "In2.Cu")
		(net 160)
	)
	(segment
		(start 169.266519 75.779764)
		(end 169.727281 76.240526)
		(width 0.125)
		(layer "In2.Cu")
		(net 160)
	)
	(segment
		(start 170.592343 74.453937)
		(end 171.053106 74.9147)
		(width 0.125)
		(layer "In2.Cu")
		(net 160)
	)
	(segment
		(start 166.575824 78.119827)
		(end 166.709865 77.985787)
		(width 0.125)
		(layer "In2.Cu")
		(net 160)
	)
	(segment
		(start 166.703253 78.343026)
		(end 167.16401 78.803783)
		(width 0.125)
		(layer "In2.Cu")
		(net 160)
	)
	(segment
		(start 171.599973 73.44631)
		(end 172.060705 73.907042)
		(width 0.125)
		(layer "In2.Cu")
		(net 160)
	)
	(segment
		(start 172.303543 72.901837)
		(end 172.381326 72.824056)
		(width 0.125)
		(layer "In2.Cu")
		(net 160)
	)
	(segment
		(start 170.197507 76.240526)
		(end 170.275288 76.162744)
		(width 0.125)
		(layer "In2.Cu")
		(net 160)
	)
	(segment
		(start 171.370161 73.676119)
		(end 171.830918 74.136876)
		(width 0.125)
		(layer "In2.Cu")
		(net 160)
	)
	(segment
		(start 179.805383 65.399999)
		(end 192.225001 65.4)
		(width 0.125)
		(layer "In2.Cu")
		(net 160)
	)
	(segment
		(start 170.975325 75.462708)
		(end 171.053106 75.384926)
		(width 0.125)
		(layer "In2.Cu")
		(net 160)
	)
	(segment
		(start 132.3534 79.1125)
		(end 164.56 79.1125)
		(width 0.125)
		(layer "In2.Cu")
		(net 160)
	)
	(segment
		(start 167.481071 77.565209)
		(end 167.481075 77.56521)
		(width 0.125)
		(layer "In2.Cu")
		(net 160)
	)
	(segment
		(start 167.086229 79.351791)
		(end 167.16401 79.274009)
		(width 0.125)
		(layer "In2.Cu")
		(net 160)
	)
	(segment
		(start 171.242732 73.452919)
		(end 171.376773 73.318879)
		(width 0.125)
		(layer "In2.Cu")
		(net 160)
	)
	(segment
		(start 171.370161 73.676119)
		(end 171.370165 73.67612)
		(width 0.125)
		(layer "In2.Cu")
		(net 160)
	)
	(segment
		(start 166.933067 78.113221)
		(end 166.933065 78.113218)
		(width 0.125)
		(layer "In2.Cu")
		(net 160)
	)
	(segment
		(start 168.641841 77.796132)
		(end 168.719622 77.71835)
		(width 0.125)
		(layer "In2.Cu")
		(net 160)
	)
	(segment
		(start 168.258889 76.787391)
		(end 168.258893 76.787392)
		(width 0.125)
		(layer "In2.Cu")
		(net 160)
	)
	(segment
		(start 166.310811 79.046599)
		(end 166.616003 79.351791)
		(width 0.125)
		(layer "In2.Cu")
		(net 160)
	)
	(segment
		(start 172.608712 73.359034)
		(end 172.303543 73.053865)
		(width 0.125)
		(layer "In2.Cu")
		(net 160)
	)
	(segment
		(start 171.599975 73.446313)
		(end 171.599973 73.44631)
		(width 0.125)
		(layer "In2.Cu")
		(net 160)
	)
	(segment
		(start 167.710885 77.335403)
		(end 167.710883 77.3354)
		(width 0.125)
		(layer "In2.Cu")
		(net 160)
	)
	(segment
		(start 168.488702 76.557584)
		(end 168.488701 76.557582)
		(width 0.125)
		(layer "In2.Cu")
		(net 160)
	)
	(segment
		(start 169.036707 76.009573)
		(end 169.497446 76.470312)
		(width 0.125)
		(layer "In2.Cu")
		(net 160)
	)
	(segment
		(start 169.687096 75.008555)
		(end 169.821137 74.874515)
		(width 0.125)
		(layer "In2.Cu")
		(net 160)
	)
	(segment
		(start 168.131469 76.564225)
		(end 168.265535 76.43016)
		(width 0.125)
		(layer "In2.Cu")
		(net 160)
	)
	(segment
		(start 167.353642 77.342009)
		(end 167.487683 77.207969)
		(width 0.125)
		(layer "In2.Cu")
		(net 160)
	)
	(segment
		(start 169.814525 75.231755)
		(end 169.814529 75.231756)
		(width 0.125)
		(layer "In2.Cu")
		(net 160)
	)
	(segment
		(start 167.864047 78.573974)
		(end 167.941828 78.496192)
		(width 0.125)
		(layer "In2.Cu")
		(net 160)
	)
	(segment
		(start 165 79.984108)
		(end 165.11 79.984108)
		(width 0.125)
		(layer "In2.Cu")
		(net 160)
	)
	(segment
		(start 166.092882 79.1125)
		(end 166.158783 79.046599)
		(width 0.125)
		(layer "In2.Cu")
		(net 160)
	)
	(arc
		(start 172.303543 73.053865)
		(mid 172.272057 72.977851)
		(end 172.303543 72.901837)
		(width 0.125)
		(layer "In2.Cu")
		(net 160)
	)
	(arc
		(start 170.598955 74.096697)
		(mid 170.646839 74.076863)
		(end 170.694723 74.096697)
		(width 0.125)
		(layer "In2.Cu")
		(net 160)
	)
	(arc
		(start 169.687096 75.104323)
		(mid 169.667262 75.056439)
		(end 169.687096 75.008555)
		(width 0.125)
		(layer "In2.Cu")
		(net 160)
	)
	(arc
		(start 164.6675 79.651608)
		(mid 164.764887 79.886721)
		(end 165 79.984108)
		(width 0.125)
		(layer "In2.Cu")
		(net 160)
	)
	(arc
		(start 170.275288 76.162744)
		(mid 170.372675 75.927631)
		(end 170.275288 75.692518)
		(width 0.125)
		(layer "In2.Cu")
		(net 160)
	)
	(arc
		(start 167.353642 77.437777)
		(mid 167.333808 77.389893)
		(end 167.353642 77.342009)
		(width 0.125)
		(layer "In2.Cu")
		(net 160)
	)
	(arc
		(start 170.464914 74.326505)
		(mid 170.44508 74.278621)
		(end 170.464914 74.230737)
		(width 0.125)
		(layer "In2.Cu")
		(net 160)
	)
	(arc
		(start 168.719622 77.71835)
		(mid 168.817009 77.483237)
		(end 168.719622 77.248124)
		(width 0.125)
		(layer "In2.Cu")
		(net 160)
	)
	(arc
		(start 167.393821 78.573974)
		(mid 167.628934 78.671361)
		(end 167.864047 78.573974)
		(width 0.125)
		(layer "In2.Cu")
		(net 160)
	)
	(arc
		(start 167.487683 77.207969)
		(mid 167.535567 77.188135)
		(end 167.583451 77.207969)
		(width 0.125)
		(layer "In2.Cu")
		(net 160)
	)
	(arc
		(start 171.376773 73.318879)
		(mid 171.424657 73.299045)
		(end 171.472541 73.318879)
		(width 0.125)
		(layer "In2.Cu")
		(net 160)
	)
	(arc
		(start 171.830918 74.607102)
		(mid 171.928305 74.371989)
		(end 171.830918 74.136876)
		(width 0.125)
		(layer "In2.Cu")
		(net 160)
	)
	(arc
		(start 172.060705 73.907042)
		(mid 172.295818 74.004429)
		(end 172.530931 73.907042)
		(width 0.125)
		(layer "In2.Cu")
		(net 160)
	)
	(arc
		(start 168.949439 77.01832)
		(mid 169.184552 77.115707)
		(end 169.419665 77.01832)
		(width 0.125)
		(layer "In2.Cu")
		(net 160)
	)
	(arc
		(start 171.282911 74.684884)
		(mid 171.518024 74.782271)
		(end 171.753137 74.684884)
		(width 0.125)
		(layer "In2.Cu")
		(net 160)
	)
	(arc
		(start 169.727281 76.240526)
		(mid 169.962394 76.337913)
		(end 170.197507 76.240526)
		(width 0.125)
		(layer "In2.Cu")
		(net 160)
	)
	(arc
		(start 165.4425 79.22)
		(mid 165.473986 79.143986)
		(end 165.55 79.1125)
		(width 0.125)
		(layer "In2.Cu")
		(net 160)
	)
	(arc
		(start 170.505099 75.462708)
		(mid 170.740212 75.560095)
		(end 170.975325 75.462708)
		(width 0.125)
		(layer "In2.Cu")
		(net 160)
	)
	(arc
		(start 171.053106 75.384926)
		(mid 171.150493 75.149813)
		(end 171.053106 74.9147)
		(width 0.125)
		(layer "In2.Cu")
		(net 160)
	)
	(arc
		(start 166.616003 79.351791)
		(mid 166.851116 79.449178)
		(end 167.086229 79.351791)
		(width 0.125)
		(layer "In2.Cu")
		(net 160)
	)
	(arc
		(start 169.821137 74.874515)
		(mid 169.869021 74.854681)
		(end 169.916905 74.874515)
		(width 0.125)
		(layer "In2.Cu")
		(net 160)
	)
	(arc
		(start 164.56 79.1125)
		(mid 164.636014 79.143986)
		(end 164.6675 79.22)
		(width 0.125)
		(layer "In2.Cu")
		(net 160)
	)
	(arc
		(start 169.043311 75.652328)
		(mid 169.091198 75.632493)
		(end 169.139083 75.652329)
		(width 0.125)
		(layer "In2.Cu")
		(net 160)
	)
	(arc
		(start 166.158783 79.046599)
		(mid 166.234797 79.015113)
		(end 166.310811 79.046599)
		(width 0.125)
		(layer "In2.Cu")
		(net 160)
	)
	(arc
		(start 172.608712 73.82926)
		(mid 172.706099 73.594147)
		(end 172.608712 73.359034)
		(width 0.125)
		(layer "In2.Cu")
		(net 160)
	)
	(arc
		(start 167.16401 79.274009)
		(mid 167.261397 79.038896)
		(end 167.16401 78.803783)
		(width 0.125)
		(layer "In2.Cu")
		(net 160)
	)
	(arc
		(start 168.265535 76.43016)
		(mid 168.313407 76.410331)
		(end 168.361279 76.430161)
		(width 0.125)
		(layer "In2.Cu")
		(net 160)
	)
	(arc
		(start 168.909274 75.882137)
		(mid 168.889439 75.83425)
		(end 168.909273 75.786365)
		(width 0.125)
		(layer "In2.Cu")
		(net 160)
	)
	(arc
		(start 168.171615 77.796132)
		(mid 168.406728 77.893519)
		(end 168.641841 77.796132)
		(width 0.125)
		(layer "In2.Cu")
		(net 160)
	)
	(arc
		(start 169.497446 76.940538)
		(mid 169.594833 76.705425)
		(end 169.497446 76.470312)
		(width 0.125)
		(layer "In2.Cu")
		(net 160)
	)
	(arc
		(start 166.575824 78.215595)
		(mid 166.55599 78.167711)
		(end 166.575824 78.119827)
		(width 0.125)
		(layer "In2.Cu")
		(net 160)
	)
	(arc
		(start 165.11 79.984108)
		(mid 165.345113 79.886721)
		(end 165.4425 79.651608)
		(width 0.125)
		(layer "In2.Cu")
		(net 160)
	)
	(arc
		(start 167.941828 78.496192)
		(mid 168.039215 78.261079)
		(end 167.941828 78.025966)
		(width 0.125)
		(layer "In2.Cu")
		(net 160)
	)
	(arc
		(start 166.709865 77.985787)
		(mid 166.757749 77.965953)
		(end 166.805633 77.985787)
		(width 0.125)
		(layer "In2.Cu")
		(net 160)
	)
	(arc
		(start 168.13147 76.659969)
		(mid 168.111641 76.612096)
		(end 168.131469 76.564225)
		(width 0.125)
		(layer "In2.Cu")
		(net 160)
	)
	(arc
		(start 171.242732 73.548687)
		(mid 171.222898 73.500803)
		(end 171.242732 73.452919)
		(width 0.125)
		(layer "In2.Cu")
		(net 160)
	)
	(segment
		(start 127.830532 76.65)
		(end 128.105532 76.375)
		(width 0.17)
		(layer "F.Cu")
		(net 161)
	)
	(segment
		(start 128.105532 76.125)
		(end 127.980532 76)
		(width 0.17)
		(layer "F.Cu")
		(net 161)
	)
	(segment
		(start 128.105532 76.375)
		(end 128.105532 76.125)
		(width 0.17)
		(layer "F.Cu")
		(net 161)
	)
	(via
		(at 127.980532 76)
		(size 0.45)
		(drill 0.1)
		(layers "F.Cu" "B.Cu")
		(net 161)
	)
	(via
		(at 62.4 108)
		(size 0.45)
		(drill 0.1)
		(layers "F.Cu" "B.Cu")
		(net 161)
	)
	(segment
		(start 62.275 113.450028)
		(end 62.275 108.125)
		(width 0.17)
		(layer "B.Cu")
		(net 161)
	)
	(segment
		(start 64.59 115.46)
		(end 63.689999 115.46)
		(width 0.17)
		(layer "B.Cu")
		(net 161)
	)
	(segment
		(start 62.435 114.010028)
		(end 62.542251 114.010028)
		(width 0.17)
		(layer "B.Cu")
		(net 161)
	)
	(segment
		(start 63.689999 115.46)
		(end 63.614999 115.535)
		(width 0.17)
		(layer "B.Cu")
		(net 161)
	)
	(segment
		(start 62.275 108.125)
		(end 62.4 108)
		(width 0.17)
		(layer "B.Cu")
		(net 161)
	)
	(segment
		(start 63.182488 115.535)
		(end 62.275 114.627512)
		(width 0.17)
		(layer "B.Cu")
		(net 161)
	)
	(segment
		(start 63.614999 115.535)
		(end 63.182488 115.535)
		(width 0.17)
		(layer "B.Cu")
		(net 161)
	)
	(segment
		(start 62.275 114.627512)
		(end 62.275 114.170028)
		(width 0.17)
		(layer "B.Cu")
		(net 161)
	)
	(segment
		(start 62.702251 113.850028)
		(end 62.702251 113.770028)
		(width 0.17)
		(layer "B.Cu")
		(net 161)
	)
	(segment
		(start 62.542251 113.610028)
		(end 62.435 113.610028)
		(width 0.17)
		(layer "B.Cu")
		(net 161)
	)
	(arc
		(start 62.435 113.610028)
		(mid 62.321863 113.563165)
		(end 62.275 113.450028)
		(width 0.17)
		(layer "B.Cu")
		(net 161)
	)
	(arc
		(start 62.542251 114.010028)
		(mid 62.655388 113.963165)
		(end 62.702251 113.850028)
		(width 0.17)
		(layer "B.Cu")
		(net 161)
	)
	(arc
		(start 62.702251 113.770028)
		(mid 62.655388 113.656891)
		(end 62.542251 113.610028)
		(width 0.17)
		(layer "B.Cu")
		(net 161)
	)
	(arc
		(start 62.275 114.170028)
		(mid 62.321863 114.056891)
		(end 62.435 114.010028)
		(width 0.17)
		(layer "B.Cu")
		(net 161)
	)
	(segment
		(start 126.4875 80.2466)
		(end 126.1875 79.9466)
		(width 0.125)
		(layer "In2.Cu")
		(net 161)
	)
	(segment
		(start 69.2534 84.4875)
		(end 86.7534 84.4875)
		(width 0.125)
		(layer "In2.Cu")
		(net 161)
	)
	(segment
		(start 67.1875 106.2534)
		(end 67.1875 86.5534)
		(width 0.125)
		(layer "In2.Cu")
		(net 161)
	)
	(segment
		(start 62.3966 108.6875)
		(end 64.7534 108.6875)
		(width 0.125)
		(layer "In2.Cu")
		(net 161)
	)
	(segment
		(start 107.5534 82.2875)
		(end 108.1534 81.6875)
		(width 0.125)
		(layer "In2.Cu")
		(net 161)
	)
	(segment
		(start 100.3966 80.5375)
		(end 104.5966 80.5375)
		(width 0.125)
		(layer "In2.Cu")
		(net 161)
	)
	(segment
		(start 128.168031 76.187499)
		(end 127.980532 76)
		(width 0.125)
		(layer "In2.Cu")
		(net 161)
	)
	(segment
		(start 87.3875 83.8534)
		(end 87.3875 81.8043)
		(width 0.125)
		(layer "In2.Cu")
		(net 161)
	)
	(segment
		(start 127.1875 78.0534)
		(end 128.168031 77.072869)
		(width 0.125)
		(layer "In2.Cu")
		(net 161)
	)
	(segment
		(start 115.0125 80.9534)
		(end 115.0125 81.4534)
		(width 0.125)
		(layer "In2.Cu")
		(net 161)
	)
	(segment
		(start 62.212501 108.187499)
		(end 62.212501 108.503401)
		(width 0.125)
		(layer "In2.Cu")
		(net 161)
	)
	(segment
		(start 108.1534 81.6875)
		(end 111.6534 81.6875)
		(width 0.125)
		(layer "In2.Cu")
		(net 161)
	)
	(segment
		(start 97.6534 80.1875)
		(end 98.2534 79.5875)
		(width 0.125)
		(layer "In2.Cu")
		(net 161)
	)
	(segment
		(start 64.7534 108.6875)
		(end 67.1875 106.2534)
		(width 0.125)
		(layer "In2.Cu")
		(net 161)
	)
	(segment
		(start 89.0043 80.1875)
		(end 97.6534 80.1875)
		(width 0.125)
		(layer "In2.Cu")
		(net 161)
	)
	(segment
		(start 118.0466 81.7875)
		(end 119.76826 81.7875)
		(width 0.125)
		(layer "In2.Cu")
		(net 161)
	)
	(segment
		(start 86.7534 84.4875)
		(end 87.3875 83.8534)
		(width 0.125)
		(layer "In2.Cu")
		(net 161)
	)
	(segment
		(start 120.39826 81.7875)
		(end 125.3534 81.7875)
		(width 0.125)
		(layer "In2.Cu")
		(net 161)
	)
	(segment
		(start 120.25826 81.434606)
		(end 120.25826 81.6475)
		(width 0.125)
		(layer "In2.Cu")
		(net 161)
	)
	(segment
		(start 98.2534 79.5875)
		(end 99.4466 79.5875)
		(width 0.125)
		(layer "In2.Cu")
		(net 161)
	)
	(segment
		(start 115.3466 81.7875)
		(end 115.7534 81.7875)
		(width 0.125)
		(layer "In2.Cu")
		(net 161)
	)
	(segment
		(start 62.212501 108.503401)
		(end 62.3966 108.6875)
		(width 0.125)
		(layer "In2.Cu")
		(net 161)
	)
	(segment
		(start 125.3534 81.7875)
		(end 126.4875 80.6534)
		(width 0.125)
		(layer "In2.Cu")
		(net 161)
	)
	(segment
		(start 115.7534 81.7875)
		(end 116.2534 81.2875)
		(width 0.125)
		(layer "In2.Cu")
		(net 161)
	)
	(segment
		(start 128.168031 77.072869)
		(end 128.168031 76.187499)
		(width 0.125)
		(layer "In2.Cu")
		(net 161)
	)
	(segment
		(start 104.5966 80.5375)
		(end 106.3466 82.2875)
		(width 0.125)
		(layer "In2.Cu")
		(net 161)
	)
	(segment
		(start 112.9534 80.3875)
		(end 114.4466 80.3875)
		(width 0.125)
		(layer "In2.Cu")
		(net 161)
	)
	(segment
		(start 115.0125 81.4534)
		(end 115.3466 81.7875)
		(width 0.125)
		(layer "In2.Cu")
		(net 161)
	)
	(segment
		(start 111.6534 81.6875)
		(end 112.9534 80.3875)
		(width 0.125)
		(layer "In2.Cu")
		(net 161)
	)
	(segment
		(start 119.90826 81.6475)
		(end 119.90826 81.434606)
		(width 0.125)
		(layer "In2.Cu")
		(net 161)
	)
	(segment
		(start 114.4466 80.3875)
		(end 115.0125 80.9534)
		(width 0.125)
		(layer "In2.Cu")
		(net 161)
	)
	(segment
		(start 120.04826 81.294606)
		(end 120.11826 81.294606)
		(width 0.125)
		(layer "In2.Cu")
		(net 161)
	)
	(segment
		(start 99.4466 79.5875)
		(end 100.3966 80.5375)
		(width 0.125)
		(layer "In2.Cu")
		(net 161)
	)
	(segment
		(start 62.4 108)
		(end 62.212501 108.187499)
		(width 0.125)
		(layer "In2.Cu")
		(net 161)
	)
	(segment
		(start 116.2534 81.2875)
		(end 117.5466 81.2875)
		(width 0.125)
		(layer "In2.Cu")
		(net 161)
	)
	(segment
		(start 126.4875 80.6534)
		(end 126.4875 80.2466)
		(width 0.125)
		(layer "In2.Cu")
		(net 161)
	)
	(segment
		(start 106.3466 82.2875)
		(end 107.5534 82.2875)
		(width 0.125)
		(layer "In2.Cu")
		(net 161)
	)
	(segment
		(start 126.1875 79.2534)
		(end 127.1875 78.2534)
		(width 0.125)
		(layer "In2.Cu")
		(net 161)
	)
	(segment
		(start 127.1875 78.2534)
		(end 127.1875 78.0534)
		(width 0.125)
		(layer "In2.Cu")
		(net 161)
	)
	(segment
		(start 126.1875 79.9466)
		(end 126.1875 79.2534)
		(width 0.125)
		(layer "In2.Cu")
		(net 161)
	)
	(segment
		(start 87.3875 81.8043)
		(end 89.0043 80.1875)
		(width 0.125)
		(layer "In2.Cu")
		(net 161)
	)
	(segment
		(start 117.5466 81.2875)
		(end 118.0466 81.7875)
		(width 0.125)
		(layer "In2.Cu")
		(net 161)
	)
	(segment
		(start 67.1875 86.5534)
		(end 69.2534 84.4875)
		(width 0.125)
		(layer "In2.Cu")
		(net 161)
	)
	(arc
		(start 119.90826 81.434606)
		(mid 119.949265 81.335611)
		(end 120.04826 81.294606)
		(width 0.125)
		(layer "In2.Cu")
		(net 161)
	)
	(arc
		(start 119.76826 81.7875)
		(mid 119.867255 81.746495)
		(end 119.90826 81.6475)
		(width 0.125)
		(layer "In2.Cu")
		(net 161)
	)
	(arc
		(start 120.11826 81.294606)
		(mid 120.217255 81.335611)
		(end 120.25826 81.434606)
		(width 0.125)
		(layer "In2.Cu")
		(net 161)
	)
	(arc
		(start 120.25826 81.6475)
		(mid 120.299265 81.746495)
		(end 120.39826 81.7875)
		(width 0.125)
		(layer "In2.Cu")
		(net 161)
	)
	(via
		(at 131.430532 79.65)
		(size 0.45)
		(drill 0.1)
		(layers "F.Cu" "B.Cu")
		(net 162)
	)
	(via
		(at 190.746706 65.796706)
		(size 0.45)
		(drill 0.1)
		(layers "F.Cu" "B.Cu")
		(net 162)
	)
	(segment
		(start 190.625 64.322488)
		(end 190.625 62.527512)
		(width 0.17)
		(layer "B.Cu")
		(net 162)
	)
	(segment
		(start 195.733 59.365001)
		(end 195.658 59.290001)
		(width 0.17)
		(layer "B.Cu")
		(net 162)
	)
	(segment
		(start 190.625 62.527512)
		(end 191.127512 62.025)
		(width 0.17)
		(layer "B.Cu")
		(net 162)
	)
	(segment
		(start 191.127512 62.025)
		(end 193.927512 62.025)
		(width 0.17)
		(layer "B.Cu")
		(net 162)
	)
	(segment
		(start 195.658 59.290001)
		(end 195.658 58.39)
		(width 0.17)
		(layer "B.Cu")
		(net 162)
	)
	(segment
		(start 190.746706 65.796706)
		(end 190.905806 65.796706)
		(width 0.17)
		(layer "B.Cu")
		(net 162)
	)
	(segment
		(start 191.125 65.577512)
		(end 191.125 64.822488)
		(width 0.17)
		(layer "B.Cu")
		(net 162)
	)
	(segment
		(start 190.905806 65.796706)
		(end 191.125 65.577512)
		(width 0.17)
		(layer "B.Cu")
		(net 162)
	)
	(segment
		(start 191.125 64.822488)
		(end 190.625 64.322488)
		(width 0.17)
		(layer "B.Cu")
		(net 162)
	)
	(segment
		(start 195.733 60.219512)
		(end 195.733 59.365001)
		(width 0.17)
		(layer "B.Cu")
		(net 162)
	)
	(segment
		(start 193.927512 62.025)
		(end 195.733 60.219512)
		(width 0.17)
		(layer "B.Cu")
		(net 162)
	)
	(segment
		(start 166.579584 80.2875)
		(end 180.292084 66.575)
		(width 0.125)
		(layer "In2.Cu")
		(net 162)
	)
	(segment
		(start 158.907091 79.862465)
		(end 159.032057 79.862465)
		(width 0.125)
		(layer "In2.Cu")
		(net 162)
	)
	(segment
		(start 131.430532 79.65)
		(end 131.093033 79.987499)
		(width 0.125)
		(layer "In2.Cu")
		(net 162)
	)
	(segment
		(start 156.382074 81.108251)
		(end 156.382074 80.5125)
		(width 0.125)
		(layer "In2.Cu")
		(net 162)
	)
	(segment
		(start 158.364574 81.215751)
		(end 158.474574 81.215751)
		(width 0.125)
		(layer "In2.Cu")
		(net 162)
	)
	(segment
		(start 159.464574 81.215751)
		(end 159.574574 81.215751)
		(width 0.125)
		(layer "In2.Cu")
		(net 162)
	)
	(segment
		(start 190.746706 66.044194)
		(end 190.746706 65.796706)
		(width 0.125)
		(layer "In2.Cu")
		(net 162)
	)
	(segment
		(start 155.064574 81.21575)
		(end 155.174574 81.21575)
		(width 0.125)
		(layer "In2.Cu")
		(net 162)
	)
	(segment
		(start 155.282074 81.10825)
		(end 155.282074 80.62)
		(width 0.125)
		(layer "In2.Cu")
		(net 162)
	)
	(segment
		(start 157.157074 79.741751)
		(end 157.157074 80.2875)
		(width 0.125)
		(layer "In2.Cu")
		(net 162)
	)
	(segment
		(start 161.114574 80.2875)
		(end 161.224574 80.2875)
		(width 0.125)
		(layer "In2.Cu")
		(net 162)
	)
	(segment
		(start 156.057074 80.5125)
		(end 156.057074 81.108251)
		(width 0.125)
		(layer "In2.Cu")
		(net 162)
	)
	(segment
		(start 156.382074 80.2875)
		(end 156.382074 79.741751)
		(width 0.125)
		(layer "In2.Cu")
		(net 162)
	)
	(segment
		(start 156.057074 79.741749)
		(end 156.057074 80.2875)
		(width 0.125)
		(layer "In2.Cu")
		(net 162)
	)
	(segment
		(start 156.714574 79.409251)
		(end 156.824574 79.409251)
		(width 0.125)
		(layer "In2.Cu")
		(net 162)
	)
	(segment
		(start 158.257074 80.2875)
		(end 158.257074 80.5125)
		(width 0.125)
		(layer "In2.Cu")
		(net 162)
	)
	(segment
		(start 190.2159 66.575)
		(end 190.746706 66.044194)
		(width 0.125)
		(layer "In2.Cu")
		(net 162)
	)
	(segment
		(start 158.257074 79.741751)
		(end 158.257074 80.2875)
		(width 0.125)
		(layer "In2.Cu")
		(net 162)
	)
	(segment
		(start 133.0355 79.742751)
		(end 133.1055 79.742751)
		(width 0.125)
		(layer "In2.Cu")
		(net 162)
	)
	(segment
		(start 158.582074 80.5125)
		(end 158.582074 80.2875)
		(width 0.125)
		(layer "In2.Cu")
		(net 162)
	)
	(segment
		(start 156.057074 80.2875)
		(end 156.057074 80.5125)
		(width 0.125)
		(layer "In2.Cu")
		(net 162)
	)
	(segment
		(start 180.292084 66.575)
		(end 190.2159 66.575)
		(width 0.125)
		(layer "In2.Cu")
		(net 162)
	)
	(segment
		(start 160.564574 81.215754)
		(end 160.674574 81.215754)
		(width 0.125)
		(layer "In2.Cu")
		(net 162)
	)
	(segment
		(start 160.782074 81.108254)
		(end 160.782074 80.62)
		(width 0.125)
		(layer "In2.Cu")
		(net 162)
	)
	(segment
		(start 156.164574 81.215751)
		(end 156.274574 81.215751)
		(width 0.125)
		(layer "In2.Cu")
		(net 162)
	)
	(segment
		(start 158.582074 81.108251)
		(end 158.582074 80.5125)
		(width 0.125)
		(layer "In2.Cu")
		(net 162)
	)
	(segment
		(start 159.357074 80.187482)
		(end 159.357074 80.2875)
		(width 0.125)
		(layer "In2.Cu")
		(net 162)
	)
	(segment
		(start 156.382074 80.5125)
		(end 156.382074 80.2875)
		(width 0.125)
		(layer "In2.Cu")
		(net 162)
	)
	(segment
		(start 159.682074 80.5125)
		(end 159.682074 80.2875)
		(width 0.125)
		(layer "In2.Cu")
		(net 162)
	)
	(segment
		(start 132.8955 80.1475)
		(end 132.8955 79.882751)
		(width 0.125)
		(layer "In2.Cu")
		(net 162)
	)
	(segment
		(start 157.482074 80.5125)
		(end 157.482074 80.2875)
		(width 0.125)
		(layer "In2.Cu")
		(net 162)
	)
	(segment
		(start 160.457074 80.62)
		(end 160.457074 81.108254)
		(width 0.125)
		(layer "In2.Cu")
		(net 162)
	)
	(segment
		(start 157.482074 80.2875)
		(end 157.482074 79.741751)
		(width 0.125)
		(layer "In2.Cu")
		(net 162)
	)
	(segment
		(start 159.357074 80.2875)
		(end 159.357074 80.5125)
		(width 0.125)
		(layer "In2.Cu")
		(net 162)
	)
	(segment
		(start 133.2455 79.882751)
		(end 133.2455 80.1475)
		(width 0.125)
		(layer "In2.Cu")
		(net 162)
	)
	(segment
		(start 133.3855 80.2875)
		(end 154.624574 80.2875)
		(width 0.125)
		(layer "In2.Cu")
		(net 162)
	)
	(segment
		(start 158.582074 80.2875)
		(end 158.582074 80.187482)
		(width 0.125)
		(layer "In2.Cu")
		(net 162)
	)
	(segment
		(start 154.957074 80.62)
		(end 154.957074 81.10825)
		(width 0.125)
		(layer "In2.Cu")
		(net 162)
	)
	(segment
		(start 159.682074 81.108251)
		(end 159.682074 80.5125)
		(width 0.125)
		(layer "In2.Cu")
		(net 162)
	)
	(segment
		(start 131.2466 80.2875)
		(end 132.7555 80.2875)
		(width 0.125)
		(layer "In2.Cu")
		(net 162)
	)
	(segment
		(start 160.457074 80.2875)
		(end 160.457074 80.62)
		(width 0.125)
		(layer "In2.Cu")
		(net 162)
	)
	(segment
		(start 155.614574 79.409249)
		(end 155.724574 79.409249)
		(width 0.125)
		(layer "In2.Cu")
		(net 162)
	)
	(segment
		(start 131.093033 80.133933)
		(end 131.2466 80.2875)
		(width 0.125)
		(layer "In2.Cu")
		(net 162)
	)
	(segment
		(start 161.224574 80.2875)
		(end 165.19 80.2875)
		(width 0.125)
		(layer "In2.Cu")
		(net 162)
	)
	(segment
		(start 159.682074 80.2875)
		(end 159.682074 79.741751)
		(width 0.125)
		(layer "In2.Cu")
		(net 162)
	)
	(segment
		(start 157.157074 80.5125)
		(end 157.157074 81.108251)
		(width 0.125)
		(layer "In2.Cu")
		(net 162)
	)
	(segment
		(start 157.482074 81.108251)
		(end 157.482074 80.5125)
		(width 0.125)
		(layer "In2.Cu")
		(net 162)
	)
	(segment
		(start 158.257074 80.5125)
		(end 158.257074 81.108251)
		(width 0.125)
		(layer "In2.Cu")
		(net 162)
	)
	(segment
		(start 155.282074 80.2875)
		(end 155.282074 79.741749)
		(width 0.125)
		(layer "In2.Cu")
		(net 162)
	)
	(segment
		(start 160.457074 79.741751)
		(end 160.457074 80.2875)
		(width 0.125)
		(layer "In2.Cu")
		(net 162)
	)
	(segment
		(start 160.014574 79.409251)
		(end 160.124574 79.409251)
		(width 0.125)
		(layer "In2.Cu")
		(net 162)
	)
	(segment
		(start 155.282074 80.62)
		(end 155.282074 80.2875)
		(width 0.125)
		(layer "In2.Cu")
		(net 162)
	)
	(segment
		(start 157.264574 81.215751)
		(end 157.374574 81.215751)
		(width 0.125)
		(layer "In2.Cu")
		(net 162)
	)
	(segment
		(start 159.357074 80.5125)
		(end 159.357074 81.108251)
		(width 0.125)
		(layer "In2.Cu")
		(net 162)
	)
	(segment
		(start 131.093033 79.987499)
		(end 131.093033 80.133933)
		(width 0.125)
		(layer "In2.Cu")
		(net 162)
	)
	(segment
		(start 165.19 80.2875)
		(end 166.579584 80.2875)
		(width 0.125)
		(layer "In2.Cu")
		(net 162)
	)
	(segment
		(start 157.814574 79.409251)
		(end 157.924574 79.409251)
		(width 0.125)
		(layer "In2.Cu")
		(net 162)
	)
	(segment
		(start 157.157074 80.2875)
		(end 157.157074 80.5125)
		(width 0.125)
		(layer "In2.Cu")
		(net 162)
	)
	(arc
		(start 158.474574 81.215751)
		(mid 158.550588 81.184265)
		(end 158.582074 81.108251)
		(width 0.125)
		(layer "In2.Cu")
		(net 162)
	)
	(arc
		(start 159.574574 81.215751)
		(mid 159.650588 81.184265)
		(end 159.682074 81.108251)
		(width 0.125)
		(layer "In2.Cu")
		(net 162)
	)
	(arc
		(start 158.582074 80.187482)
		(mid 158.677269 79.95766)
		(end 158.907091 79.862465)
		(width 0.125)
		(layer "In2.Cu")
		(net 162)
	)
	(arc
		(start 133.1055 79.742751)
		(mid 133.204495 79.783756)
		(end 133.2455 79.882751)
		(width 0.125)
		(layer "In2.Cu")
		(net 162)
	)
	(arc
		(start 156.057074 81.108251)
		(mid 156.08856 81.184265)
		(end 156.164574 81.215751)
		(width 0.125)
		(layer "In2.Cu")
		(net 162)
	)
	(arc
		(start 154.624574 80.2875)
		(mid 154.859687 80.384887)
		(end 154.957074 80.62)
		(width 0.125)
		(layer "In2.Cu")
		(net 162)
	)
	(arc
		(start 155.724574 79.409249)
		(mid 155.959687 79.506636)
		(end 156.057074 79.741749)
		(width 0.125)
		(layer "In2.Cu")
		(net 162)
	)
	(arc
		(start 157.374574 81.215751)
		(mid 157.450588 81.184265)
		(end 157.482074 81.108251)
		(width 0.125)
		(layer "In2.Cu")
		(net 162)
	)
	(arc
		(start 156.824574 79.409251)
		(mid 157.059687 79.506638)
		(end 157.157074 79.741751)
		(width 0.125)
		(layer "In2.Cu")
		(net 162)
	)
	(arc
		(start 159.357074 81.108251)
		(mid 159.38856 81.184265)
		(end 159.464574 81.215751)
		(width 0.125)
		(layer "In2.Cu")
		(net 162)
	)
	(arc
		(start 155.174574 81.21575)
		(mid 155.250588 81.184264)
		(end 155.282074 81.10825)
		(width 0.125)
		(layer "In2.Cu")
		(net 162)
	)
	(arc
		(start 160.124574 79.409251)
		(mid 160.359687 79.506638)
		(end 160.457074 79.741751)
		(width 0.125)
		(layer "In2.Cu")
		(net 162)
	)
	(arc
		(start 156.274574 81.215751)
		(mid 156.350588 81.184265)
		(end 156.382074 81.108251)
		(width 0.125)
		(layer "In2.Cu")
		(net 162)
	)
	(arc
		(start 154.957074 81.10825)
		(mid 154.98856 81.184264)
		(end 155.064574 81.21575)
		(width 0.125)
		(layer "In2.Cu")
		(net 162)
	)
	(arc
		(start 157.924574 79.409251)
		(mid 158.159687 79.506638)
		(end 158.257074 79.741751)
		(width 0.125)
		(layer "In2.Cu")
		(net 162)
	)
	(arc
		(start 158.257074 81.108251)
		(mid 158.28856 81.184265)
		(end 158.364574 81.215751)
		(width 0.125)
		(layer "In2.Cu")
		(net 162)
	)
	(arc
		(start 133.2455 80.1475)
		(mid 133.286505 80.246495)
		(end 133.3855 80.2875)
		(width 0.125)
		(layer "In2.Cu")
		(net 162)
	)
	(arc
		(start 160.457074 81.108254)
		(mid 160.48856 81.184268)
		(end 160.564574 81.215754)
		(width 0.125)
		(layer "In2.Cu")
		(net 162)
	)
	(arc
		(start 159.682074 79.741751)
		(mid 159.779461 79.506638)
		(end 160.014574 79.409251)
		(width 0.125)
		(layer "In2.Cu")
		(net 162)
	)
	(arc
		(start 132.7555 80.2875)
		(mid 132.854495 80.246495)
		(end 132.8955 80.1475)
		(width 0.125)
		(layer "In2.Cu")
		(net 162)
	)
	(arc
		(start 155.282074 79.741749)
		(mid 155.379461 79.506636)
		(end 155.614574 79.409249)
		(width 0.125)
		(layer "In2.Cu")
		(net 162)
	)
	(arc
		(start 160.782074 80.62)
		(mid 160.879461 80.384887)
		(end 161.114574 80.2875)
		(width 0.125)
		(layer "In2.Cu")
		(net 162)
	)
	(arc
		(start 159.032057 79.862465)
		(mid 159.261879 79.95766)
		(end 159.357074 80.187482)
		(width 0.125)
		(layer "In2.Cu")
		(net 162)
	)
	(arc
		(start 157.157074 81.108251)
		(mid 157.18856 81.184265)
		(end 157.264574 81.215751)
		(width 0.125)
		(layer "In2.Cu")
		(net 162)
	)
	(arc
		(start 160.674574 81.215754)
		(mid 160.750588 81.184268)
		(end 160.782074 81.108254)
		(width 0.125)
		(layer "In2.Cu")
		(net 162)
	)
	(arc
		(start 132.8955 79.882751)
		(mid 132.936505 79.783756)
		(end 133.0355 79.742751)
		(width 0.125)
		(layer "In2.Cu")
		(net 162)
	)
	(arc
		(start 157.482074 79.741751)
		(mid 157.579461 79.506638)
		(end 157.814574 79.409251)
		(width 0.125)
		(layer "In2.Cu")
		(net 162)
	)
	(arc
		(start 156.382074 79.741751)
		(mid 156.479461 79.506638)
		(end 156.714574 79.409251)
		(width 0.125)
		(layer "In2.Cu")
		(net 162)
	)
	(segment
		(start 129.555532 80.525)
		(end 129.680532 80.4)
		(width 0.17)
		(layer "F.Cu")
		(net 163)
	)
	(segment
		(start 129.555532 80.875)
		(end 129.555532 80.525)
		(width 0.17)
		(layer "F.Cu")
		(net 163)
	)
	(segment
		(start 129.830532 81.15)
		(end 129.555532 80.875)
		(width 0.17)
		(layer "F.Cu")
		(net 163)
	)
	(via
		(at 193.3 67.8125)
		(size 0.45)
		(drill 0.1)
		(layers "F.Cu" "B.Cu")
		(net 163)
	)
	(via
		(at 129.680532 80.4)
		(size 0.45)
		(drill 0.1)
		(layers "F.Cu" "B.Cu")
		(net 163)
	)
	(segment
		(start 194.083 58.915)
		(end 194.083 59.264488)
		(width 0.17)
		(layer "B.Cu")
		(net 163)
	)
	(segment
		(start 194.083 59.264488)
		(end 193.272488 60.075)
		(width 0.17)
		(layer "B.Cu")
		(net 163)
	)
	(segment
		(start 194.158 58.39)
		(end 194.158 58.84)
		(width 0.17)
		(layer "B.Cu")
		(net 163)
	)
	(segment
		(start 192.677512 67.925)
		(end 193.1875 67.925)
		(width 0.17)
		(layer "B.Cu")
		(net 163)
	)
	(segment
		(start 188.575 61.572488)
		(end 190.072488 60.075)
		(width 0.17)
		(layer "B.Cu")
		(net 163)
	)
	(segment
		(start 190.072488 60.075)
		(end 191.596052 60.075)
		(width 0.17)
		(layer "B.Cu")
		(net 163)
	)
	(segment
		(start 193.272488 60.075)
		(end 192.628022 60.075)
		(width 0.17)
		(layer "B.Cu")
		(net 163)
	)
	(segment
		(start 192.196052 60.50697)
		(end 192.028022 60.50697)
		(width 0.17)
		(layer "B.Cu")
		(net 163)
	)
	(segment
		(start 194.158 58.84)
		(end 194.083 58.915)
		(width 0.17)
		(layer "B.Cu")
		(net 163)
	)
	(segment
		(start 193.1875 67.925)
		(end 193.3 67.8125)
		(width 0.17)
		(layer "B.Cu")
		(net 163)
	)
	(segment
		(start 188.575 67.227512)
		(end 190.072488 68.725)
		(width 0.17)
		(layer "B.Cu")
		(net 163)
	)
	(segment
		(start 191.877512 68.725)
		(end 192.677512 67.925)
		(width 0.17)
		(layer "B.Cu")
		(net 163)
	)
	(segment
		(start 188.575 61.572488)
		(end 188.575 67.227512)
		(width 0.17)
		(layer "B.Cu")
		(net 163)
	)
	(segment
		(start 190.072488 68.725)
		(end 191.877512 68.725)
		(width 0.17)
		(layer "B.Cu")
		(net 163)
	)
	(arc
		(start 191.812037 60.290985)
		(mid 191.748776 60.138261)
		(end 191.596052 60.075)
		(width 0.17)
		(layer "B.Cu")
		(net 163)
	)
	(arc
		(start 192.028022 60.50697)
		(mid 191.875298 60.443709)
		(end 191.812037 60.290985)
		(width 0.17)
		(layer "B.Cu")
		(net 163)
	)
	(arc
		(start 192.628022 60.075)
		(mid 192.475298 60.138261)
		(end 192.412037 60.290985)
		(width 0.17)
		(layer "B.Cu")
		(net 163)
	)
	(arc
		(start 192.412037 60.290985)
		(mid 192.348776 60.443709)
		(end 192.196052 60.50697)
		(width 0.17)
		(layer "B.Cu")
		(net 163)
	)
	(segment
		(start 129.972281 81.5975)
		(end 129.972281 81.527562)
		(width 0.125)
		(layer "In2.Cu")
		(net 163)
	)
	(segment
		(start 166.84 81.7375)
		(end 167.180192 81.7375)
		(width 0.125)
		(layer "In2.Cu")
		(net 163)
	)
	(segment
		(start 169.15718 79.760512)
		(end 180.930193 67.987499)
		(width 0.125)
		(layer "In2.Cu")
		(net 163)
	)
	(segment
		(start 129.493033 81.583933)
		(end 129.6466 81.7375)
		(width 0.125)
		(layer "In2.Cu")
		(net 163)
	)
	(segment
		(start 164.953686 81.175)
		(end 165.073686 81.175)
		(width 0.125)
		(layer "In2.Cu")
		(net 163)
	)
	(segment
		(start 164.601186 82.09)
		(end 164.601186 81.7375)
		(width 0.125)
		(layer "In2.Cu")
		(net 163)
	)
	(segment
		(start 164.353686 82.85)
		(end 164.473686 82.85)
		(width 0.125)
		(layer "In2.Cu")
		(net 163)
	)
	(segment
		(start 168.547401 81.397269)
		(end 168.653467 81.291202)
		(width 0.125)
		(layer "In2.Cu")
		(net 163)
	)
	(segment
		(start 166.153686 81.7375)
		(end 166.273686 81.7375)
		(width 0.125)
		(layer "In2.Cu")
		(net 163)
	)
	(segment
		(start 164.226186 82.09)
		(end 164.226186 82.7225)
		(width 0.125)
		(layer "In2.Cu")
		(net 163)
	)
	(segment
		(start 180.930193 67.987499)
		(end 193.125001 67.987499)
		(width 0.125)
		(layer "In2.Cu")
		(net 163)
	)
	(segment
		(start 168.653467 81.026037)
		(end 168.564241 80.936811)
		(width 0.125)
		(layer "In2.Cu")
		(net 163)
	)
	(segment
		(start 130.112281 81.387562)
		(end 130.182281 81.387562)
		(width 0.125)
		(layer "In2.Cu")
		(net 163)
	)
	(segment
		(start 132.2534 81.7375)
		(end 132.4534 81.5375)
		(width 0.125)
		(layer "In2.Cu")
		(net 163)
	)
	(segment
		(start 193.125001 67.987499)
		(end 193.3 67.8125)
		(width 0.125)
		(layer "In2.Cu")
		(net 163)
	)
	(segment
		(start 132.4534 81.5375)
		(end 133.2466 81.5375)
		(width 0.125)
		(layer "In2.Cu")
		(net 163)
	)
	(segment
		(start 165.801186 82.7225)
		(end 165.801186 82.09)
		(width 0.125)
		(layer "In2.Cu")
		(net 163)
	)
	(segment
		(start 130.462281 81.7375)
		(end 132.2534 81.7375)
		(width 0.125)
		(layer "In2.Cu")
		(net 163)
	)
	(segment
		(start 168.193011 81.308044)
		(end 168.282236 81.397269)
		(width 0.125)
		(layer "In2.Cu")
		(net 163)
	)
	(segment
		(start 167.180192 81.7375)
		(end 167.609648 81.308044)
		(width 0.125)
		(layer "In2.Cu")
		(net 163)
	)
	(segment
		(start 164.601186 81.7375)
		(end 164.601186 81.5275)
		(width 0.125)
		(layer "In2.Cu")
		(net 163)
	)
	(segment
		(start 166.273686 81.7375)
		(end 166.84 81.7375)
		(width 0.125)
		(layer "In2.Cu")
		(net 163)
	)
	(segment
		(start 165.426186 81.7375)
		(end 165.426186 82.09)
		(width 0.125)
		(layer "In2.Cu")
		(net 163)
	)
	(segment
		(start 168.564241 80.353448)
		(end 168.670308 80.247384)
		(width 0.125)
		(layer "In2.Cu")
		(net 163)
	)
	(segment
		(start 129.6466 81.7375)
		(end 129.832281 81.7375)
		(width 0.125)
		(layer "In2.Cu")
		(net 163)
	)
	(segment
		(start 129.680532 80.4)
		(end 129.493033 80.587499)
		(width 0.125)
		(layer "In2.Cu")
		(net 163)
	)
	(segment
		(start 129.493033 80.587499)
		(end 129.493033 81.583933)
		(width 0.125)
		(layer "In2.Cu")
		(net 163)
	)
	(segment
		(start 133.4466 81.7375)
		(end 163.873686 81.7375)
		(width 0.125)
		(layer "In2.Cu")
		(net 163)
	)
	(segment
		(start 165.426186 82.09)
		(end 165.426186 82.7225)
		(width 0.125)
		(layer "In2.Cu")
		(net 163)
	)
	(segment
		(start 164.601186 82.7225)
		(end 164.601186 82.09)
		(width 0.125)
		(layer "In2.Cu")
		(net 163)
	)
	(segment
		(start 130.322281 81.527562)
		(end 130.322281 81.5975)
		(width 0.125)
		(layer "In2.Cu")
		(net 163)
	)
	(segment
		(start 165.426186 81.5275)
		(end 165.426186 81.7375)
		(width 0.125)
		(layer "In2.Cu")
		(net 163)
	)
	(segment
		(start 133.2466 81.5375)
		(end 133.4466 81.7375)
		(width 0.125)
		(layer "In2.Cu")
		(net 163)
	)
	(segment
		(start 168.670308 80.247384)
		(end 169.15718 79.760512)
		(width 0.125)
		(layer "In2.Cu")
		(net 163)
	)
	(segment
		(start 165.553686 82.85)
		(end 165.673686 82.85)
		(width 0.125)
		(layer "In2.Cu")
		(net 163)
	)
	(arc
		(start 164.473686 82.85)
		(mid 164.563842 82.812656)
		(end 164.601186 82.7225)
		(width 0.125)
		(layer "In2.Cu")
		(net 163)
	)
	(arc
		(start 168.653467 81.291202)
		(mid 168.708385 81.158619)
		(end 168.653467 81.026037)
		(width 0.125)
		(layer "In2.Cu")
		(net 163)
	)
	(arc
		(start 165.801186 82.09)
		(mid 165.904431 81.840745)
		(end 166.153686 81.7375)
		(width 0.125)
		(layer "In2.Cu")
		(net 163)
	)
	(arc
		(start 163.873686 81.7375)
		(mid 164.122941 81.840745)
		(end 164.226186 82.09)
		(width 0.125)
		(layer "In2.Cu")
		(net 163)
	)
	(arc
		(start 129.832281 81.7375)
		(mid 129.931276 81.696495)
		(end 129.972281 81.5975)
		(width 0.125)
		(layer "In2.Cu")
		(net 163)
	)
	(arc
		(start 168.282236 81.397269)
		(mid 168.414819 81.452186)
		(end 168.547401 81.397269)
		(width 0.125)
		(layer "In2.Cu")
		(net 163)
	)
	(arc
		(start 164.226186 82.7225)
		(mid 164.26353 82.812656)
		(end 164.353686 82.85)
		(width 0.125)
		(layer "In2.Cu")
		(net 163)
	)
	(arc
		(start 165.673686 82.85)
		(mid 165.763842 82.812656)
		(end 165.801186 82.7225)
		(width 0.125)
		(layer "In2.Cu")
		(net 163)
	)
	(arc
		(start 164.601186 81.5275)
		(mid 164.704431 81.278245)
		(end 164.953686 81.175)
		(width 0.125)
		(layer "In2.Cu")
		(net 163)
	)
	(arc
		(start 168.564241 80.936811)
		(mid 168.443422 80.64513)
		(end 168.564241 80.353448)
		(width 0.125)
		(layer "In2.Cu")
		(net 163)
	)
	(arc
		(start 130.182281 81.387562)
		(mid 130.281276 81.428567)
		(end 130.322281 81.527562)
		(width 0.125)
		(layer "In2.Cu")
		(net 163)
	)
	(arc
		(start 130.322281 81.5975)
		(mid 130.363286 81.696495)
		(end 130.462281 81.7375)
		(width 0.125)
		(layer "In2.Cu")
		(net 163)
	)
	(arc
		(start 165.426186 82.7225)
		(mid 165.46353 82.812656)
		(end 165.553686 82.85)
		(width 0.125)
		(layer "In2.Cu")
		(net 163)
	)
	(arc
		(start 165.073686 81.175)
		(mid 165.322941 81.278245)
		(end 165.426186 81.5275)
		(width 0.125)
		(layer "In2.Cu")
		(net 163)
	)
	(arc
		(start 167.609648 81.308044)
		(mid 167.901329 81.187226)
		(end 168.193011 81.308044)
		(width 0.125)
		(layer "In2.Cu")
		(net 163)
	)
	(arc
		(start 129.972281 81.527562)
		(mid 130.013286 81.428567)
		(end 130.112281 81.387562)
		(width 0.125)
		(layer "In2.Cu")
		(net 163)
	)
	(segment
		(start 220.017499 118.125)
		(end 219.952499 118.19)
		(width 0.19)
		(layer "F.Cu")
		(net 164)
	)
	(segment
		(start 230.495532 112.735)
		(end 230.380532 112.62)
		(width 0.19)
		(layer "F.Cu")
		(net 164)
	)
	(segment
		(start 221.679501 118.19)
		(end 222.685 118.19)
		(width 0.19)
		(layer "F.Cu")
		(net 164)
	)
	(segment
		(start 219.952499 118.19)
		(end 219.758408 118.19)
		(width 0.19)
		(layer "F.Cu")
		(net 164)
	)
	(segment
		(start 219.5925 118.2125)
		(end 219.28 117.9)
		(width 0.19)
		(layer "F.Cu")
		(net 164)
	)
	(segment
		(start 230.430532 114.0725)
		(end 230.430532 113.385)
		(width 0.19)
		(layer "F.Cu")
		(net 164)
	)
	(segment
		(start 219.735908 118.2125)
		(end 219.5925 118.2125)
		(width 0.19)
		(layer "F.Cu")
		(net 164)
	)
	(segment
		(start 221.202 118.125)
		(end 221.614501 118.125)
		(width 0.19)
		(layer "F.Cu")
		(net 164)
	)
	(segment
		(start 220.43 118.125)
		(end 220.017499 118.125)
		(width 0.19)
		(layer "F.Cu")
		(net 164)
	)
	(segment
		(start 222.685 118.19)
		(end 222.8 118.075)
		(width 0.19)
		(layer "F.Cu")
		(net 164)
	)
	(segment
		(start 219.758408 118.19)
		(end 219.735908 118.2125)
		(width 0.19)
		(layer "F.Cu")
		(net 164)
	)
	(segment
		(start 230.495532 113.32)
		(end 230.495532 112.735)
		(width 0.19)
		(layer "F.Cu")
		(net 164)
	)
	(segment
		(start 230.430532 113.385)
		(end 230.495532 113.32)
		(width 0.19)
		(layer "F.Cu")
		(net 164)
	)
	(segment
		(start 221.614501 118.125)
		(end 221.679501 118.19)
		(width 0.19)
		(layer "F.Cu")
		(net 164)
	)
	(segment
		(start 220.43 118.125)
		(end 221.202 118.125)
		(width 0.19)
		(layer "F.Cu")
		(net 164)
	)
	(via
		(at 230.380532 112.62)
		(size 0.45)
		(drill 0.1)
		(layers "F.Cu" "B.Cu")
		(net 164)
	)
	(via
		(at 222.8 118.075)
		(size 0.45)
		(drill 0.1)
		(layers "F.Cu" "B.Cu")
		(net 164)
	)
	(segment
		(start 222.8 118.075)
		(end 222.6375 118.2375)
		(width 0.15)
		(layer "In7.Cu")
		(net 164)
	)
	(segment
		(start 225.29364 111.36732)
		(end 225.29364 111.1775)
		(width 0.15)
		(layer "In7.Cu")
		(net 164)
	)
	(segment
		(start 222.431956 118.2375)
		(end 221.7375 117.543044)
		(width 0.15)
		(layer "In7.Cu")
		(net 164)
	)
	(segment
		(start 225.43364 111.0375)
		(end 225.50364 111.0375)
		(width 0.15)
		(layer "In7.Cu")
		(net 164)
	)
	(segment
		(start 229.913044 111.0375)
		(end 230.543032 111.667488)
		(width 0.15)
		(layer "In7.Cu")
		(net 164)
	)
	(segment
		(start 223.456956 111.0375)
		(end 224.80364 111.0375)
		(width 0.15)
		(layer "In7.Cu")
		(net 164)
	)
	(segment
		(start 226.13364 111.0375)
		(end 226.20364 111.0375)
		(width 0.15)
		(layer "In7.Cu")
		(net 164)
	)
	(segment
		(start 225.99364 111.367336)
		(end 225.99364 111.1775)
		(width 0.15)
		(layer "In7.Cu")
		(net 164)
	)
	(segment
		(start 221.7375 117.543044)
		(end 221.7375 112.756956)
		(width 0.15)
		(layer "In7.Cu")
		(net 164)
	)
	(segment
		(start 222.6375 118.2375)
		(end 222.431956 118.2375)
		(width 0.15)
		(layer "In7.Cu")
		(net 164)
	)
	(segment
		(start 230.543032 111.667488)
		(end 230.543032 112.4575)
		(width 0.15)
		(layer "In7.Cu")
		(net 164)
	)
	(segment
		(start 230.543032 112.4575)
		(end 230.380532 112.62)
		(width 0.15)
		(layer "In7.Cu")
		(net 164)
	)
	(segment
		(start 226.20364 111.0375)
		(end 227.45 111.0375)
		(width 0.15)
		(layer "In7.Cu")
		(net 164)
	)
	(segment
		(start 224.94364 111.1775)
		(end 224.94364 111.36732)
		(width 0.15)
		(layer "In7.Cu")
		(net 164)
	)
	(segment
		(start 225.78364 111.507336)
		(end 225.85364 111.507336)
		(width 0.15)
		(layer "In7.Cu")
		(net 164)
	)
	(segment
		(start 227.45 111.0375)
		(end 229.913044 111.0375)
		(width 0.15)
		(layer "In7.Cu")
		(net 164)
	)
	(segment
		(start 225.64364 111.1775)
		(end 225.64364 111.367336)
		(width 0.15)
		(layer "In7.Cu")
		(net 164)
	)
	(segment
		(start 221.7375 112.756956)
		(end 223.456956 111.0375)
		(width 0.15)
		(layer "In7.Cu")
		(net 164)
	)
	(segment
		(start 225.08364 111.50732)
		(end 225.15364 111.50732)
		(width 0.15)
		(layer "In7.Cu")
		(net 164)
	)
	(arc
		(start 225.85364 111.507336)
		(mid 225.952635 111.466331)
		(end 225.99364 111.367336)
		(width 0.15)
		(layer "In7.Cu")
		(net 164)
	)
	(arc
		(start 225.64364 111.367336)
		(mid 225.684645 111.466331)
		(end 225.78364 111.507336)
		(width 0.15)
		(layer "In7.Cu")
		(net 164)
	)
	(arc
		(start 225.50364 111.0375)
		(mid 225.602635 111.078505)
		(end 225.64364 111.1775)
		(width 0.15)
		(layer "In7.Cu")
		(net 164)
	)
	(arc
		(start 225.99364 111.1775)
		(mid 226.034645 111.078505)
		(end 226.13364 111.0375)
		(width 0.15)
		(layer "In7.Cu")
		(net 164)
	)
	(arc
		(start 224.80364 111.0375)
		(mid 224.902635 111.078505)
		(end 224.94364 111.1775)
		(width 0.15)
		(layer "In7.Cu")
		(net 164)
	)
	(arc
		(start 225.15364 111.50732)
		(mid 225.252635 111.466315)
		(end 225.29364 111.36732)
		(width 0.15)
		(layer "In7.Cu")
		(net 164)
	)
	(arc
		(start 225.29364 111.1775)
		(mid 225.334645 111.078505)
		(end 225.43364 111.0375)
		(width 0.15)
		(layer "In7.Cu")
		(net 164)
	)
	(arc
		(start 224.94364 111.36732)
		(mid 224.984645 111.466315)
		(end 225.08364 111.50732)
		(width 0.15)
		(layer "In7.Cu")
		(net 164)
	)
	(segment
		(start 100.430532 75.15)
		(end 99.9 74.619468)
		(width 0.1)
		(layer "F.Cu")
		(net 165)
	)
	(segment
		(start 99.9 74.619468)
		(end 99.9 74.6)
		(width 0.1)
		(layer "F.Cu")
		(net 165)
	)
	(via
		(at 75.775532 92.915)
		(size 0.45)
		(drill 0.1)
		(layers "F.Cu" "B.Cu")
		(net 165)
	)
	(via
		(at 99.9 74.6)
		(size 0.45)
		(drill 0.1)
		(layers "F.Cu" "B.Cu")
		(net 165)
	)
	(segment
		(start 100 74.7)
		(end 100 75.7)
		(width 0.1)
		(layer "In5.Cu")
		(net 165)
	)
	(segment
		(start 95.6 76.35)
		(end 94.05 76.35)
		(width 0.1)
		(layer "In5.Cu")
		(net 165)
	)
	(segment
		(start 81.1 81.9)
		(end 82.05 80.95)
		(width 0.1)
		(layer "In5.Cu")
		(net 165)
	)
	(segment
		(start 95.75 76.2)
		(end 99.5 76.2)
		(width 0.1)
		(layer "In5.Cu")
		(net 165)
	)
	(segment
		(start 88.6 76.75)
		(end 88.6 76.4)
		(width 0.1)
		(layer "In5.Cu")
		(net 165)
	)
	(segment
		(start 75.35 92.489468)
		(end 75.35 82.6)
		(width 0.1)
		(layer "In5.Cu")
		(net 165)
	)
	(segment
		(start 76.35 82.25)
		(end 76.7 81.9)
		(width 0.1)
		(layer "In5.Cu")
		(net 165)
	)
	(segment
		(start 85.1 79.15)
		(end 85.1 78.4)
		(width 0.1)
		(layer "In5.Cu")
		(net 165)
	)
	(segment
		(start 75.7 82.25)
		(end 76.35 82.25)
		(width 0.1)
		(layer "In5.Cu")
		(net 165)
	)
	(segment
		(start 83.3 80.95)
		(end 85.1 79.15)
		(width 0.1)
		(layer "In5.Cu")
		(net 165)
	)
	(segment
		(start 93.9 76.2)
		(end 94.05 76.35)
		(width 0.1)
		(layer "In5.Cu")
		(net 165)
	)
	(segment
		(start 75.35 82.6)
		(end 75.7 82.25)
		(width 0.1)
		(layer "In5.Cu")
		(net 165)
	)
	(segment
		(start 88.15 77.2)
		(end 88.6 76.75)
		(width 0.1)
		(layer "In5.Cu")
		(net 165)
	)
	(segment
		(start 95.75 76.2)
		(end 95.6 76.35)
		(width 0.1)
		(layer "In5.Cu")
		(net 165)
	)
	(segment
		(start 99.9 74.6)
		(end 100 74.7)
		(width 0.1)
		(layer "In5.Cu")
		(net 165)
	)
	(segment
		(start 88.8 76.2)
		(end 93.9 76.2)
		(width 0.1)
		(layer "In5.Cu")
		(net 165)
	)
	(segment
		(start 76.7 81.9)
		(end 81.1 81.9)
		(width 0.1)
		(layer "In5.Cu")
		(net 165)
	)
	(segment
		(start 85.1 78.4)
		(end 86.3 77.2)
		(width 0.1)
		(layer "In5.Cu")
		(net 165)
	)
	(segment
		(start 75.775532 92.915)
		(end 75.35 92.489468)
		(width 0.1)
		(layer "In5.Cu")
		(net 165)
	)
	(segment
		(start 82.05 80.95)
		(end 83.3 80.95)
		(width 0.1)
		(layer "In5.Cu")
		(net 165)
	)
	(segment
		(start 100 75.7)
		(end 99.5 76.2)
		(width 0.1)
		(layer "In5.Cu")
		(net 165)
	)
	(segment
		(start 88.6 76.4)
		(end 88.8 76.2)
		(width 0.1)
		(layer "In5.Cu")
		(net 165)
	)
	(segment
		(start 86.3 77.2)
		(end 88.15 77.2)
		(width 0.1)
		(layer "In5.Cu")
		(net 165)
	)
	(segment
		(start 149.23 111.6)
		(end 148.63 111)
		(width 0.1)
		(layer "F.Cu")
		(net 167)
	)
	(segment
		(start 150.2 111.6)
		(end 149.23 111.6)
		(width 0.1)
		(layer "F.Cu")
		(net 167)
	)
	(segment
		(start 147.48 111)
		(end 148.63 111)
		(width 0.1)
		(layer "F.Cu")
		(net 167)
	)
	(segment
		(start 145.6 72.55)
		(end 145.75 72.4)
		(width 0.1)
		(layer "F.Cu")
		(net 167)
	)
	(segment
		(start 151.23 111.75)
		(end 150.7 111.75)
		(width 0.1)
		(layer "F.Cu")
		(net 167)
	)
	(segment
		(start 150.55 111.6)
		(end 150.7 111.75)
		(width 0.1)
		(layer "F.Cu")
		(net 167)
	)
	(segment
		(start 143.330532 72.15)
		(end 143.730532 72.55)
		(width 0.1)
		(layer "F.Cu")
		(net 167)
	)
	(segment
		(start 150.2 111.6)
		(end 150.55 111.6)
		(width 0.1)
		(layer "F.Cu")
		(net 167)
	)
	(segment
		(start 143.730532 72.55)
		(end 145.6 72.55)
		(width 0.1)
		(layer "F.Cu")
		(net 167)
	)
	(via
		(at 140.9 99.225)
		(size 0.45)
		(drill 0.1)
		(layers "F.Cu" "B.Cu")
		(net 167)
	)
	(via
		(at 145.75 72.4)
		(size 0.45)
		(drill 0.1)
		(layers "F.Cu" "B.Cu")
		(net 167)
	)
	(via
		(at 150.2 111.6)
		(size 0.45)
		(drill 0.1)
		(layers "F.Cu" "B.Cu")
		(net 167)
	)
	(segment
		(start 140.9 100.125)
		(end 146.725 105.95)
		(width 0.1)
		(layer "In4.Cu")
		(net 167)
	)
	(segment
		(start 150.2 108.625)
		(end 150.2 111.6)
		(width 0.1)
		(layer "In4.Cu")
		(net 167)
	)
	(segment
		(start 146.725 105.95)
		(end 146.725 106.3)
		(width 0.1)
		(layer "In4.Cu")
		(net 167)
	)
	(segment
		(start 146.725 106.3)
		(end 147.9 107.475)
		(width 0.1)
		(layer "In4.Cu")
		(net 167)
	)
	(segment
		(start 147.9 107.475)
		(end 149.05 107.475)
		(width 0.1)
		(layer "In4.Cu")
		(net 167)
	)
	(segment
		(start 140.9 99.225)
		(end 140.9 100.125)
		(width 0.1)
		(layer "In4.Cu")
		(net 167)
	)
	(segment
		(start 149.05 107.475)
		(end 150.2 108.625)
		(width 0.1)
		(layer "In4.Cu")
		(net 167)
	)
	(segment
		(start 147.6 80.05)
		(end 147.6 83.5)
		(width 0.1)
		(layer "In5.Cu")
		(net 167)
	)
	(segment
		(start 144.15 89.4)
		(end 140.5 93.05)
		(width 0.1)
		(layer "In5.Cu")
		(net 167)
	)
	(segment
		(start 145.328 87.294)
		(end 144.8 87.822)
		(width 0.1)
		(layer "In5.Cu")
		(net 167)
	)
	(segment
		(start 145.75 72.4)
		(end 145.75 73.3)
		(width 0.1)
		(layer "In5.Cu")
		(net 167)
	)
	(segment
		(start 140.5 93.05)
		(end 140.5 98.825)
		(width 0.1)
		(layer "In5.Cu")
		(net 167)
	)
	(segment
		(start 145.35 85.75)
		(end 145.35 85.843255)
		(width 0.1)
		(layer "In5.Cu")
		(net 167)
	)
	(segment
		(start 145.328 86.577742)
		(end 145.328 87.294)
		(width 0.1)
		(layer "In5.Cu")
		(net 167)
	)
	(segment
		(start 144.15 88.3)
		(end 144.15 89.4)
		(width 0.1)
		(layer "In5.Cu")
		(net 167)
	)
	(segment
		(start 146.05 73.6)
		(end 146.05 78.5)
		(width 0.1)
		(layer "In5.Cu")
		(net 167)
	)
	(segment
		(start 145.75 73.3)
		(end 146.05 73.6)
		(width 0.1)
		(layer "In5.Cu")
		(net 167)
	)
	(segment
		(start 145.175 86.424742)
		(end 145.328 86.577742)
		(width 0.1)
		(layer "In5.Cu")
		(net 167)
	)
	(segment
		(start 146.05 78.5)
		(end 147.6 80.05)
		(width 0.1)
		(layer "In5.Cu")
		(net 167)
	)
	(segment
		(start 144.8 87.822)
		(end 144.628 87.822)
		(width 0.1)
		(layer "In5.Cu")
		(net 167)
	)
	(segment
		(start 147.6 83.5)
		(end 145.35 85.75)
		(width 0.1)
		(layer "In5.Cu")
		(net 167)
	)
	(segment
		(start 140.5 98.825)
		(end 140.9 99.225)
		(width 0.1)
		(layer "In5.Cu")
		(net 167)
	)
	(segment
		(start 144.628 87.822)
		(end 144.15 88.3)
		(width 0.1)
		(layer "In5.Cu")
		(net 167)
	)
	(segment
		(start 145.35 85.843255)
		(end 145.175 86.018255)
		(width 0.1)
		(layer "In5.Cu")
		(net 167)
	)
	(segment
		(start 145.175 86.018255)
		(end 145.175 86.424742)
		(width 0.1)
		(layer "In5.Cu")
		(net 167)
	)
	(segment
		(start 91.030532 78.15)
		(end 91.05 78.15)
		(width 0.1)
		(layer "F.Cu")
		(net 168)
	)
	(via
		(at 91.05 78.15)
		(size 0.45)
		(drill 0.1)
		(layers "F.Cu" "B.Cu")
		(net 168)
	)
	(via
		(at 75.775532 90.375)
		(size 0.45)
		(drill 0.1)
		(layers "F.Cu" "B.Cu")
		(net 168)
	)
	(segment
		(start 91.05 79.3)
		(end 91.05 78.15)
		(width 0.1)
		(layer "In5.Cu")
		(net 168)
	)
	(segment
		(start 76.55 88.65)
		(end 76.55 86.35)
		(width 0.1)
		(layer "In5.Cu")
		(net 168)
	)
	(segment
		(start 77.5 85.95)
		(end 77.85 85.6)
		(width 0.1)
		(layer "In5.Cu")
		(net 168)
	)
	(segment
		(start 89.95 80.4)
		(end 91.05 79.3)
		(width 0.1)
		(layer "In5.Cu")
		(net 168)
	)
	(segment
		(start 75.775532 90.375)
		(end 76.35 89.800532)
		(width 0.1)
		(layer "In5.Cu")
		(net 168)
	)
	(segment
		(start 76.55 86.35)
		(end 76.95 85.95)
		(width 0.1)
		(layer "In5.Cu")
		(net 168)
	)
	(segment
		(start 86.35 84.45)
		(end 87.6 83.2)
		(width 0.1)
		(layer "In5.Cu")
		(net 168)
	)
	(segment
		(start 78.3 84.45)
		(end 86.35 84.45)
		(width 0.1)
		(layer "In5.Cu")
		(net 168)
	)
	(segment
		(start 87.6 83.2)
		(end 87.6 82.1)
		(width 0.1)
		(layer "In5.Cu")
		(net 168)
	)
	(segment
		(start 77.85 84.9)
		(end 78.3 84.45)
		(width 0.1)
		(layer "In5.Cu")
		(net 168)
	)
	(segment
		(start 77.85 85.6)
		(end 77.85 84.9)
		(width 0.1)
		(layer "In5.Cu")
		(net 168)
	)
	(segment
		(start 76.35 88.85)
		(end 76.55 88.65)
		(width 0.1)
		(layer "In5.Cu")
		(net 168)
	)
	(segment
		(start 76.35 89.800532)
		(end 76.35 88.85)
		(width 0.1)
		(layer "In5.Cu")
		(net 168)
	)
	(segment
		(start 76.95 85.95)
		(end 77.5 85.95)
		(width 0.1)
		(layer "In5.Cu")
		(net 168)
	)
	(segment
		(start 89.3 80.4)
		(end 89.95 80.4)
		(width 0.1)
		(layer "In5.Cu")
		(net 168)
	)
	(segment
		(start 87.6 82.1)
		(end 89.3 80.4)
		(width 0.1)
		(layer "In5.Cu")
		(net 168)
	)
	(segment
		(start 113.065532 78.415)
		(end 113.065532 78.615532)
		(width 0.19)
		(layer "F.Cu")
		(net 169)
	)
	(segment
		(start 113.165 78.715)
		(end 114.685 78.715)
		(width 0.19)
		(layer "F.Cu")
		(net 169)
	)
	(segment
		(start 113.065532 78.615532)
		(end 113.165 78.715)
		(width 0.19)
		(layer "F.Cu")
		(net 169)
	)
	(segment
		(start 114.685 78.715)
		(end 114.8 78.6)
		(width 0.19)
		(layer "F.Cu")
		(net 169)
	)
	(segment
		(start 113.330532 78.15)
		(end 113.065532 78.415)
		(width 0.19)
		(layer "F.Cu")
		(net 169)
	)
	(via
		(at 114.8 78.6)
		(size 0.45)
		(drill 0.1)
		(layers "F.Cu" "B.Cu")
		(net 169)
	)
	(via
		(at 105.158959 69.890544)
		(size 0.45)
		(drill 0.1)
		(layers "F.Cu" "B.Cu")
		(net 169)
	)
	(segment
		(start 104.87 66.490001)
		(end 104.59 66.770001)
		(width 0.19)
		(layer "B.Cu")
		(net 169)
	)
	(segment
		(start 104.87 66.01)
		(end 104.87 66.490001)
		(width 0.19)
		(layer "B.Cu")
		(net 169)
	)
	(segment
		(start 104.59 66.770001)
		(end 104.59 67.52837)
		(width 0.19)
		(layer "B.Cu")
		(net 169)
	)
	(segment
		(start 105.043959 69.775544)
		(end 105.158959 69.890544)
		(width 0.19)
		(layer "B.Cu")
		(net 169)
	)
	(segment
		(start 104.59 67.52837)
		(end 105.043959 67.982329)
		(width 0.19)
		(layer "B.Cu")
		(net 169)
	)
	(segment
		(start 104.9 64.98)
		(end 104.9 65.98)
		(width 0.19)
		(layer "B.Cu")
		(net 169)
	)
	(segment
		(start 105.043959 67.982329)
		(end 105.043959 69.775544)
		(width 0.19)
		(layer "B.Cu")
		(net 169)
	)
	(segment
		(start 109.7375 78.343044)
		(end 110.156956 78.7625)
		(width 0.15)
		(layer "In5.Cu")
		(net 169)
	)
	(segment
		(start 107.056956 74.1625)
		(end 108.456956 74.1625)
		(width 0.15)
		(layer "In5.Cu")
		(net 169)
	)
	(segment
		(start 110.4375 76.143044)
		(end 110.4375 76.956956)
		(width 0.15)
		(layer "In5.Cu")
		(net 169)
	)
	(segment
		(start 114.6375 78.7625)
		(end 114.8 78.6)
		(width 0.15)
		(layer "In5.Cu")
		(net 169)
	)
	(segment
		(start 105.9375 72.443044)
		(end 105.9375 73.043044)
		(width 0.15)
		(layer "In5.Cu")
		(net 169)
	)
	(segment
		(start 105.9375 73.043044)
		(end 107.056956 74.1625)
		(width 0.15)
		(layer "In5.Cu")
		(net 169)
	)
	(segment
		(start 113.023556 78.213761)
		(end 113.023556 78.6025)
		(width 0.15)
		(layer "In5.Cu")
		(net 169)
	)
	(segment
		(start 104.996459 70.053044)
		(end 104.996459 71.502003)
		(width 0.15)
		(layer "In5.Cu")
		(net 169)
	)
	(segment
		(start 105.158959 69.890544)
		(end 104.996459 70.053044)
		(width 0.15)
		(layer "In5.Cu")
		(net 169)
	)
	(segment
		(start 104.996459 71.502003)
		(end 105.9375 72.443044)
		(width 0.15)
		(layer "In5.Cu")
		(net 169)
	)
	(segment
		(start 108.456956 74.1625)
		(end 110.4375 76.143044)
		(width 0.15)
		(layer "In5.Cu")
		(net 169)
	)
	(segment
		(start 112.623556 78.6025)
		(end 112.623556 78.213761)
		(width 0.15)
		(layer "In5.Cu")
		(net 169)
	)
	(segment
		(start 113.183556 78.7625)
		(end 114.6375 78.7625)
		(width 0.15)
		(layer "In5.Cu")
		(net 169)
	)
	(segment
		(start 112.783556 78.053761)
		(end 112.863556 78.053761)
		(width 0.15)
		(layer "In5.Cu")
		(net 169)
	)
	(segment
		(start 109.7375 77.656956)
		(end 109.7375 78.343044)
		(width 0.15)
		(layer "In5.Cu")
		(net 169)
	)
	(segment
		(start 110.4375 76.956956)
		(end 109.7375 77.656956)
		(width 0.15)
		(layer "In5.Cu")
		(net 169)
	)
	(segment
		(start 110.156956 78.7625)
		(end 112.463556 78.7625)
		(width 0.15)
		(layer "In5.Cu")
		(net 169)
	)
	(arc
		(start 112.463556 78.7625)
		(mid 112.576693 78.715637)
		(end 112.623556 78.6025)
		(width 0.15)
		(layer "In5.Cu")
		(net 169)
	)
	(arc
		(start 112.863556 78.053761)
		(mid 112.976693 78.100624)
		(end 113.023556 78.213761)
		(width 0.15)
		(layer "In5.Cu")
		(net 169)
	)
	(arc
		(start 113.023556 78.6025)
		(mid 113.070419 78.715637)
		(end 113.183556 78.7625)
		(width 0.15)
		(layer "In5.Cu")
		(net 169)
	)
	(arc
		(start 112.623556 78.213761)
		(mid 112.670419 78.100624)
		(end 112.783556 78.053761)
		(width 0.15)
		(layer "In5.Cu")
		(net 169)
	)
	(segment
		(start 125.405532 82.925)
		(end 125.405532 83.075)
		(width 0.17)
		(layer "F.Cu")
		(net 170)
	)
	(segment
		(start 125.405532 83.075)
		(end 125.280532 83.2)
		(width 0.17)
		(layer "F.Cu")
		(net 170)
	)
	(segment
		(start 125.130532 82.65)
		(end 125.405532 82.925)
		(width 0.17)
		(layer "F.Cu")
		(net 170)
	)
	(via
		(at 125.280532 83.2)
		(size 0.45)
		(drill 0.1)
		(layers "F.Cu" "B.Cu")
		(net 170)
	)
	(via
		(at 63.3 113.9875)
		(size 0.45)
		(drill 0.1)
		(layers "F.Cu" "B.Cu")
		(net 170)
	)
	(segment
		(start 63.556062 113.875)
		(end 63.4125 113.875)
		(width 0.17)
		(layer "B.Cu")
		(net 170)
	)
	(segment
		(start 64.59 113.96)
		(end 64.14 113.96)
		(width 0.17)
		(layer "B.Cu")
		(net 170)
	)
	(segment
		(start 63.4125 113.875)
		(end 63.3 113.9875)
		(width 0.17)
		(layer "B.Cu")
		(net 170)
	)
	(segment
		(start 64.14 113.96)
		(end 64.065 113.885)
		(width 0.17)
		(layer "B.Cu")
		(net 170)
	)
	(segment
		(start 64.065 113.885)
		(end 63.566062 113.885)
		(width 0.17)
		(layer "B.Cu")
		(net 170)
	)
	(segment
		(start 63.566062 113.885)
		(end 63.556062 113.875)
		(width 0.17)
		(layer "B.Cu")
		(net 170)
	)
	(segment
		(start 98.505 83.2875)
		(end 98.74875 83.2875)
		(width 0.125)
		(layer "In2.Cu")
		(net 170)
	)
	(segment
		(start 97.905 82.9375)
		(end 98.155 82.9375)
		(width 0.125)
		(layer "In2.Cu")
		(net 170)
	)
	(segment
		(start 104.01535 84.975)
		(end 104.01535 84.164616)
		(width 0.125)
		(layer "In2.Cu")
		(net 170)
	)
	(segment
		(start 100.67625 84.2449)
		(end 100.67625 83.64)
		(width 0.125)
		(layer "In2.Cu")
		(net 170)
	)
	(segment
		(start 94.37 83.2875)
		(end 94.49 83.2875)
		(width 0.125)
		(layer "In2.Cu")
		(net 170)
	)
	(segment
		(start 125.4534 84.6875)
		(end 125.7875 84.3534)
		(width 0.125)
		(layer "In2.Cu")
		(net 170)
	)
	(segment
		(start 94.84 83.6375)
		(end 95.09 83.6375)
		(width 0.125)
		(layer "In2.Cu")
		(net 170)
	)
	(segment
		(start 96.4175 83.747633)
		(end 96.4175 83.18457)
		(width 0.125)
		(layer "In2.Cu")
		(net 170)
	)
	(segment
		(start 125.7875 83.8466)
		(end 125.468031 83.527131)
		(width 0.125)
		(layer "In2.Cu")
		(net 170)
	)
	(segment
		(start 125.468031 83.527131)
		(end 125.468031 83.387499)
		(width 0.125)
		(layer "In2.Cu")
		(net 170)
	)
	(segment
		(start 105.531757 84.6875)
		(end 107.7534 84.6875)
		(width 0.125)
		(layer "In2.Cu")
		(net 170)
	)
	(segment
		(start 100.42875 84.3724)
		(end 100.54875 84.3724)
		(width 0.125)
		(layer "In2.Cu")
		(net 170)
	)
	(segment
		(start 91.0534 83.2875)
		(end 93.29 83.2875)
		(width 0.125)
		(layer "In2.Cu")
		(net 170)
	)
	(segment
		(start 96.0425 83.64)
		(end 96.0425 83.747633)
		(width 0.125)
		(layer "In2.Cu")
		(net 170)
	)
	(segment
		(start 102.112776 83.2875)
		(end 102.5466 83.2875)
		(width 0.125)
		(layer "In2.Cu")
		(net 170)
	)
	(segment
		(start 104.36785 83.812116)
		(end 104.48785 83.812116)
		(width 0.125)
		(layer "In2.Cu")
		(net 170)
	)
	(segment
		(start 97.37 84.375146)
		(end 97.49 84.375146)
		(width 0.125)
		(layer "In2.Cu")
		(net 170)
	)
	(segment
		(start 99.82875 83.2875)
		(end 99.94875 83.2875)
		(width 0.125)
		(layer "In2.Cu")
		(net 170)
	)
	(segment
		(start 104.84035 84.164616)
		(end 104.84035 85.003907)
		(width 0.125)
		(layer "In2.Cu")
		(net 170)
	)
	(segment
		(start 110.0466 84.6875)
		(end 125.4534 84.6875)
		(width 0.125)
		(layer "In2.Cu")
		(net 170)
	)
	(segment
		(start 99.22875 82.602613)
		(end 99.34875 82.602613)
		(width 0.125)
		(layer "In2.Cu")
		(net 170)
	)
	(segment
		(start 103.6966 85.0375)
		(end 103.95285 85.0375)
		(width 0.125)
		(layer "In2.Cu")
		(net 170)
	)
	(segment
		(start 63.125001 113.812501)
		(end 62.853401 113.812501)
		(width 0.125)
		(layer "In2.Cu")
		(net 170)
	)
	(segment
		(start 95.44 83.2875)
		(end 95.69 83.2875)
		(width 0.125)
		(layer "In2.Cu")
		(net 170)
	)
	(segment
		(start 125.7875 84.3534)
		(end 125.7875 83.8466)
		(width 0.125)
		(layer "In2.Cu")
		(net 170)
	)
	(segment
		(start 70.5534 87.0875)
		(end 87.2534 87.0875)
		(width 0.125)
		(layer "In2.Cu")
		(net 170)
	)
	(segment
		(start 99.70125 82.955113)
		(end 99.70125 83.16)
		(width 0.125)
		(layer "In2.Cu")
		(net 170)
	)
	(segment
		(start 97.6175 84.247646)
		(end 97.6175 83.225)
		(width 0.125)
		(layer "In2.Cu")
		(net 170)
	)
	(segment
		(start 109.7466 84.3875)
		(end 110.0466 84.6875)
		(width 0.125)
		(layer "In2.Cu")
		(net 170)
	)
	(segment
		(start 101.512776 83.651526)
		(end 101.74875 83.651526)
		(width 0.125)
		(layer "In2.Cu")
		(net 170)
	)
	(segment
		(start 108.0534 84.3875)
		(end 109.7466 84.3875)
		(width 0.125)
		(layer "In2.Cu")
		(net 170)
	)
	(segment
		(start 63.3 113.9875)
		(end 63.125001 113.812501)
		(width 0.125)
		(layer "In2.Cu")
		(net 170)
	)
	(segment
		(start 98.87625 83.16)
		(end 98.87625 82.955113)
		(width 0.125)
		(layer "In2.Cu")
		(net 170)
	)
	(segment
		(start 62.853401 113.812501)
		(end 61.5875 112.5466)
		(width 0.125)
		(layer "In2.Cu")
		(net 170)
	)
	(segment
		(start 100.30125 83.64)
		(end 100.30125 84.2449)
		(width 0.125)
		(layer "In2.Cu")
		(net 170)
	)
	(segment
		(start 97.2425 83.18457)
		(end 97.2425 84.247646)
		(width 0.125)
		(layer "In2.Cu")
		(net 170)
	)
	(segment
		(start 69.8875 109.6534)
		(end 69.8875 87.7534)
		(width 0.125)
		(layer "In2.Cu")
		(net 170)
	)
	(segment
		(start 87.2534 87.0875)
		(end 91.0534 83.2875)
		(width 0.125)
		(layer "In2.Cu")
		(net 170)
	)
	(segment
		(start 93.6425 83.64)
		(end 93.6425 84.149248)
		(width 0.125)
		(layer "In2.Cu")
		(net 170)
	)
	(segment
		(start 102.5466 83.2875)
		(end 102.9125 83.6534)
		(width 0.125)
		(layer "In2.Cu")
		(net 170)
	)
	(segment
		(start 93.77 84.276748)
		(end 93.89 84.276748)
		(width 0.125)
		(layer "In2.Cu")
		(net 170)
	)
	(segment
		(start 69.8875 87.7534)
		(end 70.5534 87.0875)
		(width 0.125)
		(layer "In2.Cu")
		(net 170)
	)
	(segment
		(start 102.9125 83.6534)
		(end 102.9125 84.2534)
		(width 0.125)
		(layer "In2.Cu")
		(net 170)
	)
	(segment
		(start 94.0175 84.149248)
		(end 94.0175 83.64)
		(width 0.125)
		(layer "In2.Cu")
		(net 170)
	)
	(segment
		(start 101.02875 83.2875)
		(end 101.14875 83.2875)
		(width 0.125)
		(layer "In2.Cu")
		(net 170)
	)
	(segment
		(start 96.745429 82.856641)
		(end 96.914571 82.856641)
		(width 0.125)
		(layer "In2.Cu")
		(net 170)
	)
	(segment
		(start 96.17 83.875133)
		(end 96.29 83.875133)
		(width 0.125)
		(layer "In2.Cu")
		(net 170)
	)
	(segment
		(start 102.9125 84.2534)
		(end 103.3466 84.6875)
		(width 0.125)
		(layer "In2.Cu")
		(net 170)
	)
	(segment
		(start 125.468031 83.387499)
		(end 125.280532 83.2)
		(width 0.125)
		(layer "In2.Cu")
		(net 170)
	)
	(segment
		(start 104.931757 85.095314)
		(end 105.123943 85.095314)
		(width 0.125)
		(layer "In2.Cu")
		(net 170)
	)
	(segment
		(start 62.3534 109.8875)
		(end 69.6534 109.8875)
		(width 0.125)
		(layer "In2.Cu")
		(net 170)
	)
	(segment
		(start 107.7534 84.6875)
		(end 108.0534 84.3875)
		(width 0.125)
		(layer "In2.Cu")
		(net 170)
	)
	(segment
		(start 61.5875 110.6534)
		(end 62.3534 109.8875)
		(width 0.125)
		(layer "In2.Cu")
		(net 170)
	)
	(segment
		(start 69.6534 109.8875)
		(end 69.8875 109.6534)
		(width 0.125)
		(layer "In2.Cu")
		(net 170)
	)
	(segment
		(start 61.5875 112.5466)
		(end 61.5875 110.6534)
		(width 0.125)
		(layer "In2.Cu")
		(net 170)
	)
	(arc
		(start 97.6175 83.225)
		(mid 97.701707 83.021707)
		(end 97.905 82.9375)
		(width 0.125)
		(layer "In2.Cu")
		(net 170)
	)
	(arc
		(start 103.6341 84.975)
		(mid 103.652406 85.019194)
		(end 103.6966 85.0375)
		(width 0.125)
		(layer "In2.Cu")
		(net 170)
	)
	(arc
		(start 100.67625 83.64)
		(mid 100.779495 83.390745)
		(end 101.02875 83.2875)
		(width 0.125)
		(layer "In2.Cu")
		(net 170)
	)
	(arc
		(start 95.69 83.2875)
		(mid 95.939255 83.390745)
		(end 96.0425 83.64)
		(width 0.125)
		(layer "In2.Cu")
		(net 170)
	)
	(arc
		(start 94.7775 83.575)
		(mid 94.795806 83.619194)
		(end 94.84 83.6375)
		(width 0.125)
		(layer "In2.Cu")
		(net 170)
	)
	(arc
		(start 100.30125 84.2449)
		(mid 100.338594 84.335056)
		(end 100.42875 84.3724)
		(width 0.125)
		(layer "In2.Cu")
		(net 170)
	)
	(arc
		(start 101.14875 83.2875)
		(mid 101.357002 83.373761)
		(end 101.443263 83.582013)
		(width 0.125)
		(layer "In2.Cu")
		(net 170)
	)
	(arc
		(start 93.6425 84.149248)
		(mid 93.679844 84.239404)
		(end 93.77 84.276748)
		(width 0.125)
		(layer "In2.Cu")
		(net 170)
	)
	(arc
		(start 99.70125 83.16)
		(mid 99.738594 83.250156)
		(end 99.82875 83.2875)
		(width 0.125)
		(layer "In2.Cu")
		(net 170)
	)
	(arc
		(start 98.74875 83.2875)
		(mid 98.838906 83.250156)
		(end 98.87625 83.16)
		(width 0.125)
		(layer "In2.Cu")
		(net 170)
	)
	(arc
		(start 96.4175 83.18457)
		(mid 96.513548 82.952689)
		(end 96.745429 82.856641)
		(width 0.125)
		(layer "In2.Cu")
		(net 170)
	)
	(arc
		(start 99.94875 83.2875)
		(mid 100.198005 83.390745)
		(end 100.30125 83.64)
		(width 0.125)
		(layer "In2.Cu")
		(net 170)
	)
	(arc
		(start 94.49 83.2875)
		(mid 94.693293 83.371707)
		(end 94.7775 83.575)
		(width 0.125)
		(layer "In2.Cu")
		(net 170)
	)
	(arc
		(start 93.29 83.2875)
		(mid 93.539255 83.390745)
		(end 93.6425 83.64)
		(width 0.125)
		(layer "In2.Cu")
		(net 170)
	)
	(arc
		(start 97.49 84.375146)
		(mid 97.580156 84.337802)
		(end 97.6175 84.247646)
		(width 0.125)
		(layer "In2.Cu")
		(net 170)
	)
	(arc
		(start 98.87625 82.955113)
		(mid 98.979495 82.705858)
		(end 99.22875 82.602613)
		(width 0.125)
		(layer "In2.Cu")
		(net 170)
	)
	(arc
		(start 104.84035 85.003907)
		(mid 104.867122 85.068542)
		(end 104.931757 85.095314)
		(width 0.125)
		(layer "In2.Cu")
		(net 170)
	)
	(arc
		(start 96.0425 83.747633)
		(mid 96.079844 83.837789)
		(end 96.17 83.875133)
		(width 0.125)
		(layer "In2.Cu")
		(net 170)
	)
	(arc
		(start 93.89 84.276748)
		(mid 93.980156 84.239404)
		(end 94.0175 84.149248)
		(width 0.125)
		(layer "In2.Cu")
		(net 170)
	)
	(arc
		(start 104.01535 84.164616)
		(mid 104.118595 83.915361)
		(end 104.36785 83.812116)
		(width 0.125)
		(layer "In2.Cu")
		(net 170)
	)
	(arc
		(start 101.74875 83.651526)
		(mid 101.797903 83.631166)
		(end 101.818263 83.582013)
		(width 0.125)
		(layer "In2.Cu")
		(net 170)
	)
	(arc
		(start 101.443263 83.582013)
		(mid 101.463623 83.631166)
		(end 101.512776 83.651526)
		(width 0.125)
		(layer "In2.Cu")
		(net 170)
	)
	(arc
		(start 96.29 83.875133)
		(mid 96.380156 83.837789)
		(end 96.4175 83.747633)
		(width 0.125)
		(layer "In2.Cu")
		(net 170)
	)
	(arc
		(start 101.818263 83.582013)
		(mid 101.904524 83.373761)
		(end 102.112776 83.2875)
		(width 0.125)
		(layer "In2.Cu")
		(net 170)
	)
	(arc
		(start 98.155 82.9375)
		(mid 98.358293 83.021707)
		(end 98.4425 83.225)
		(width 0.125)
		(layer "In2.Cu")
		(net 170)
	)
	(arc
		(start 95.1525 83.575)
		(mid 95.236707 83.371707)
		(end 95.44 83.2875)
		(width 0.125)
		(layer "In2.Cu")
		(net 170)
	)
	(arc
		(start 99.34875 82.602613)
		(mid 99.598005 82.705858)
		(end 99.70125 82.955113)
		(width 0.125)
		(layer "In2.Cu")
		(net 170)
	)
	(arc
		(start 94.0175 83.64)
		(mid 94.120745 83.390745)
		(end 94.37 83.2875)
		(width 0.125)
		(layer "In2.Cu")
		(net 170)
	)
	(arc
		(start 96.914571 82.856641)
		(mid 97.146452 82.952689)
		(end 97.2425 83.18457)
		(width 0.125)
		(layer "In2.Cu")
		(net 170)
	)
	(arc
		(start 103.3466 84.6875)
		(mid 103.549893 84.771707)
		(end 103.6341 84.975)
		(width 0.125)
		(layer "In2.Cu")
		(net 170)
	)
	(arc
		(start 105.21535 85.003907)
		(mid 105.308023 84.780173)
		(end 105.531757 84.6875)
		(width 0.125)
		(layer "In2.Cu")
		(net 170)
	)
	(arc
		(start 95.09 83.6375)
		(mid 95.134194 83.619194)
		(end 95.1525 83.575)
		(width 0.125)
		(layer "In2.Cu")
		(net 170)
	)
	(arc
		(start 98.4425 83.225)
		(mid 98.460806 83.269194)
		(end 98.505 83.2875)
		(width 0.125)
		(layer "In2.Cu")
		(net 170)
	)
	(arc
		(start 97.2425 84.247646)
		(mid 97.279844 84.337802)
		(end 97.37 84.375146)
		(width 0.125)
		(layer "In2.Cu")
		(net 170)
	)
	(arc
		(start 105.123943 85.095314)
		(mid 105.188578 85.068542)
		(end 105.21535 85.003907)
		(width 0.125)
		(layer "In2.Cu")
		(net 170)
	)
	(arc
		(start 100.54875 84.3724)
		(mid 100.638906 84.335056)
		(end 100.67625 84.2449)
		(width 0.125)
		(layer "In2.Cu")
		(net 170)
	)
	(arc
		(start 103.95285 85.0375)
		(mid 103.997044 85.019194)
		(end 104.01535 84.975)
		(width 0.125)
		(layer "In2.Cu")
		(net 170)
	)
	(arc
		(start 104.48785 83.812116)
		(mid 104.737105 83.915361)
		(end 104.84035 84.164616)
		(width 0.125)
		(layer "In2.Cu")
		(net 170)
	)
	(segment
		(start 112.885 79.085)
		(end 114.685 79.085)
		(width 0.19)
		(layer "F.Cu")
		(net 171)
	)
	(segment
		(start 112.695532 78.895532)
		(end 112.885 79.085)
		(width 0.19)
		(layer "F.Cu")
		(net 171)
	)
	(segment
		(start 114.685 79.085)
		(end 114.8 79.2)
		(width 0.19)
		(layer "F.Cu")
		(net 171)
	)
	(segment
		(start 112.430532 78.15)
		(end 112.695532 78.415)
		(width 0.19)
		(layer "F.Cu")
		(net 171)
	)
	(segment
		(start 112.695532 78.415)
		(end 112.695532 78.895532)
		(width 0.19)
		(layer "F.Cu")
		(net 171)
	)
	(via
		(at 114.8 79.2)
		(size 0.45)
		(drill 0.1)
		(layers "F.Cu" "B.Cu")
		(net 171)
	)
	(via
		(at 104.57 69.88)
		(size 0.45)
		(drill 0.1)
		(layers "F.Cu" "B.Cu")
		(net 171)
	)
	(segment
		(start 104.673959 69.775544)
		(end 104.673959 68.135589)
		(width 0.19)
		(layer "B.Cu")
		(net 171)
	)
	(segment
		(start 104.57 69.88)
		(end 104.57 69.879503)
		(width 0.19)
		(layer "B.Cu")
		(net 171)
	)
	(segment
		(start 103.94 66.490001)
		(end 103.94 66.01)
		(width 0.19)
		(layer "B.Cu")
		(net 171)
	)
	(segment
		(start 104.22 67.68163)
		(end 104.22 66.770001)
		(width 0.19)
		(layer "B.Cu")
		(net 171)
	)
	(segment
		(start 104.673959 68.135589)
		(end 104.22 67.68163)
		(width 0.19)
		(layer "B.Cu")
		(net 171)
	)
	(segment
		(start 104.22 66.770001)
		(end 103.94 66.490001)
		(width 0.19)
		(layer "B.Cu")
		(net 171)
	)
	(segment
		(start 103.92 64.98)
		(end 103.92 65.99)
		(width 0.19)
		(layer "B.Cu")
		(net 171)
	)
	(segment
		(start 104.57 69.879503)
		(end 104.673959 69.775544)
		(width 0.19)
		(layer "B.Cu")
		(net 171)
	)
	(segment
		(start 106.943044 74.4375)
		(end 108.343044 74.4375)
		(width 0.15)
		(layer "In5.Cu")
		(net 171)
	)
	(segment
		(start 108.343044 74.4375)
		(end 110.1625 76.256956)
		(width 0.15)
		(layer "In5.Cu")
		(net 171)
	)
	(segment
		(start 104.721459 71.615915)
		(end 105.6625 72.556956)
		(width 0.15)
		(layer "In5.Cu")
		(net 171)
	)
	(segment
		(start 109.4625 77.543044)
		(end 109.4625 78.456956)
		(width 0.15)
		(layer "In5.Cu")
		(net 171)
	)
	(segment
		(start 104.57 69.88)
		(end 104.57 69.901585)
		(width 0.15)
		(layer "In5.Cu")
		(net 171)
	)
	(segment
		(start 105.6625 73.156956)
		(end 106.943044 74.4375)
		(width 0.15)
		(layer "In5.Cu")
		(net 171)
	)
	(segment
		(start 105.6625 72.556956)
		(end 105.6625 73.156956)
		(width 0.15)
		(layer "In5.Cu")
		(net 171)
	)
	(segment
		(start 110.043044 79.0375)
		(end 114.6375 79.0375)
		(width 0.15)
		(layer "In5.Cu")
		(net 171)
	)
	(segment
		(start 110.1625 76.256956)
		(end 110.1625 76.843044)
		(width 0.15)
		(layer "In5.Cu")
		(net 171)
	)
	(segment
		(start 110.1625 76.843044)
		(end 109.4625 77.543044)
		(width 0.15)
		(layer "In5.Cu")
		(net 171)
	)
	(segment
		(start 104.57 69.901585)
		(end 104.721459 70.053044)
		(width 0.15)
		(layer "In5.Cu")
		(net 171)
	)
	(segment
		(start 114.6375 79.0375)
		(end 114.8 79.2)
		(width 0.15)
		(layer "In5.Cu")
		(net 171)
	)
	(segment
		(start 109.4625 78.456956)
		(end 110.043044 79.0375)
		(width 0.15)
		(layer "In5.Cu")
		(net 171)
	)
	(segment
		(start 104.721459 70.053044)
		(end 104.721459 71.615915)
		(width 0.15)
		(layer "In5.Cu")
		(net 171)
	)
	(segment
		(start 89.69 77.8)
		(end 89.780532 77.8)
		(width 0.1)
		(layer "F.Cu")
		(net 172)
	)
	(segment
		(start 89.780532 77.8)
		(end 90.130532 78.15)
		(width 0.1)
		(layer "F.Cu")
		(net 172)
	)
	(via
		(at 89.69 77.8)
		(size 0.45)
		(drill 0.1)
		(layers "F.Cu" "B.Cu")
		(net 172)
	)
	(via
		(at 75.775532 89.105)
		(size 0.45)
		(drill 0.1)
		(layers "F.Cu" "B.Cu")
		(net 172)
	)
	(segment
		(start 84.5 83.5)
		(end 87.95 80.05)
		(width 0.1)
		(layer "In5.Cu")
		(net 172)
	)
	(segment
		(start 89.9 79.75)
		(end 89.9 78.91)
		(width 0.1)
		(layer "In5.Cu")
		(net 172)
	)
	(segment
		(start 89.69 78.7)
		(end 89.9 78.91)
		(width 0.1)
		(layer "In5.Cu")
		(net 172)
	)
	(segment
		(start 89.69 77.8)
		(end 89.69 78.7)
		(width 0.1)
		(layer "In5.Cu")
		(net 172)
	)
	(segment
		(start 76.5 85.7)
		(end 77.2 85.7)
		(width 0.1)
		(layer "In5.Cu")
		(net 172)
	)
	(segment
		(start 89.6 80.05)
		(end 89.9 79.75)
		(width 0.1)
		(layer "In5.Cu")
		(net 172)
	)
	(segment
		(start 75.775532 89.105)
		(end 76.215266 88.665266)
		(width 0.1)
		(layer "In5.Cu")
		(net 172)
	)
	(segment
		(start 78 83.5)
		(end 84.5 83.5)
		(width 0.1)
		(layer "In5.Cu")
		(net 172)
	)
	(segment
		(start 76.215266 85.984734)
		(end 76.5 85.7)
		(width 0.1)
		(layer "In5.Cu")
		(net 172)
	)
	(segment
		(start 87.95 80.05)
		(end 89.6 80.05)
		(width 0.1)
		(layer "In5.Cu")
		(net 172)
	)
	(segment
		(start 77.5 85.4)
		(end 77.5 84)
		(width 0.1)
		(layer "In5.Cu")
		(net 172)
	)
	(segment
		(start 76.215266 88.665266)
		(end 76.215266 85.984734)
		(width 0.1)
		(layer "In5.Cu")
		(net 172)
	)
	(segment
		(start 77.2 85.7)
		(end 77.5 85.4)
		(width 0.1)
		(layer "In5.Cu")
		(net 172)
	)
	(segment
		(start 77.5 84)
		(end 78 83.5)
		(width 0.1)
		(layer "In5.Cu")
		(net 172)
	)
	(via
		(at 75.775532 115.775)
		(size 0.45)
		(drill 0.1)
		(layers "F.Cu" "B.Cu")
		(net 173)
	)
	(via
		(at 82.4 135.5)
		(size 0.45)
		(drill 0.1)
		(layers "F.Cu" "B.Cu")
		(net 173)
	)
	(via
		(at 142.430532 78.15)
		(size 0.45)
		(drill 0.1)
		(layers "F.Cu" "B.Cu")
		(net 173)
	)
	(via
		(at 143.8 92.6)
		(size 0.45)
		(drill 0.1)
		(layers "F.Cu" "B.Cu")
		(net 173)
	)
	(segment
		(start 142.9 81.3)
		(end 142.9 80.2)
		(width 0.1)
		(layer "B.Cu")
		(net 173)
	)
	(segment
		(start 143.3 86.5)
		(end 142 85.2)
		(width 0.1)
		(layer "B.Cu")
		(net 173)
	)
	(segment
		(start 142.675 79.975)
		(end 142.675 78.394468)
		(width 0.1)
		(layer "B.Cu")
		(net 173)
	)
	(segment
		(start 142.9 80.2)
		(end 142.675 79.975)
		(width 0.1)
		(layer "B.Cu")
		(net 173)
	)
	(segment
		(start 143.8 92.6)
		(end 143.3 92.1)
		(width 0.1)
		(layer "B.Cu")
		(net 173)
	)
	(segment
		(start 143.3 92.1)
		(end 143.3 86.5)
		(width 0.1)
		(layer "B.Cu")
		(net 173)
	)
	(segment
		(start 142.675 78.394468)
		(end 142.430532 78.15)
		(width 0.1)
		(layer "B.Cu")
		(net 173)
	)
	(segment
		(start 142 82.2)
		(end 142.9 81.3)
		(width 0.1)
		(layer "B.Cu")
		(net 173)
	)
	(segment
		(start 142 85.2)
		(end 142 82.2)
		(width 0.1)
		(layer "B.Cu")
		(net 173)
	)
	(segment
		(start 143.800001 102.1)
		(end 143.8 92.6)
		(width 0.1)
		(layer "In5.Cu")
		(net 173)
	)
	(segment
		(start 105.765686 129.4)
		(end 112.265685 122.900001)
		(width 0.1)
		(layer "In5.Cu")
		(net 173)
	)
	(segment
		(start 112.265685 122.900001)
		(end 137.865687 122.900001)
		(width 0.1)
		(layer "In5.Cu")
		(net 173)
	)
	(segment
		(start 143.2 107.699999)
		(end 143.2 102.700001)
		(width 0.1)
		(layer "In5.Cu")
		(net 173)
	)
	(segment
		(start 143.800001 108.3)
		(end 143.2 107.699999)
		(width 0.1)
		(layer "In5.Cu")
		(net 173)
	)
	(segment
		(start 143.800001 116.965687)
		(end 143.800001 108.3)
		(width 0.1)
		(layer "In5.Cu")
		(net 173)
	)
	(segment
		(start 84 129.4)
		(end 105.765686 129.4)
		(width 0.1)
		(layer "In5.Cu")
		(net 173)
	)
	(segment
		(start 137.865687 122.900001)
		(end 143.800001 116.965687)
		(width 0.1)
		(layer "In5.Cu")
		(net 173)
	)
	(segment
		(start 82.4 135.5)
		(end 82.4 131)
		(width 0.1)
		(layer "In5.Cu")
		(net 173)
	)
	(segment
		(start 143.2 102.700001)
		(end 143.800001 102.1)
		(width 0.1)
		(layer "In5.Cu")
		(net 173)
	)
	(segment
		(start 82.4 131)
		(end 84 129.4)
		(width 0.1)
		(layer "In5.Cu")
		(net 173)
	)
	(segment
		(start 77.9 129.3)
		(end 77.9 117.899468)
		(width 0.1)
		(layer "In7.Cu")
		(net 173)
	)
	(segment
		(start 77.9 117.899468)
		(end 75.775532 115.775)
		(width 0.1)
		(layer "In7.Cu")
		(net 173)
	)
	(segment
		(start 82.4 133.8)
		(end 77.9 129.3)
		(width 0.1)
		(layer "In7.Cu")
		(net 173)
	)
	(segment
		(start 82.4 135.5)
		(end 82.4 133.8)
		(width 0.1)
		(layer "In7.Cu")
		(net 173)
	)
	(segment
		(start 233.089997 119.615)
		(end 233.49337 119.615)
		(width 0.19)
		(layer "F.Cu")
		(net 174)
	)
	(segment
		(start 232.589997 119.136795)
		(end 232.689997 119.136795)
		(width 0.19)
		(layer "F.Cu")
		(net 174)
	)
	(segment
		(start 234.430532 117.035)
		(end 234.430532 116.3475)
		(width 0.19)
		(layer "F.Cu")
		(net 174)
	)
	(segment
		(start 220.43 111.927)
		(end 221.202 111.927)
		(width 0.19)
		(layer "F.Cu")
		(net 174)
	)
	(segment
		(start 221.679501 111.992)
		(end 221.614501 111.927)
		(width 0.19)
		(layer "F.Cu")
		(net 174)
	)
	(segment
		(start 232.889997 119.336795)
		(end 232.889997 119.415)
		(width 0.19)
		(layer "F.Cu")
		(net 174)
	)
	(segment
		(start 225.585 118.82337)
		(end 225.585 112.82337)
		(width 0.19)
		(layer "F.Cu")
		(net 174)
	)
	(segment
		(start 232.189997 119.615)
		(end 226.37663 119.615)
		(width 0.19)
		(layer "F.Cu")
		(net 174)
	)
	(segment
		(start 234.271186 118.837182)
		(end 234.495532 118.612838)
		(width 0.19)
		(layer "F.Cu")
		(net 174)
	)
	(segment
		(start 232.389997 119.415)
		(end 232.389997 119.336795)
		(width 0.19)
		(layer "F.Cu")
		(net 174)
	)
	(segment
		(start 220.017499 111.927)
		(end 219.952499 111.992)
		(width 0.19)
		(layer "F.Cu")
		(net 174)
	)
	(segment
		(start 219.685408 112.015)
		(end 219.62 112.015)
		(width 0.19)
		(layer "F.Cu")
		(net 174)
	)
	(segment
		(start 225.585 112.82337)
		(end 224.75363 111.992)
		(width 0.19)
		(layer "F.Cu")
		(net 174)
	)
	(segment
		(start 219.62 112.015)
		(end 219.305 111.7)
		(width 0.19)
		(layer "F.Cu")
		(net 174)
	)
	(segment
		(start 234.495532 117.1)
		(end 234.430532 117.035)
		(width 0.19)
		(layer "F.Cu")
		(net 174)
	)
	(segment
		(start 220.43 111.927)
		(end 220.017499 111.927)
		(width 0.19)
		(layer "F.Cu")
		(net 174)
	)
	(segment
		(start 234.495532 118.612838)
		(end 234.495532 117.1)
		(width 0.19)
		(layer "F.Cu")
		(net 174)
	)
	(segment
		(start 221.614501 111.927)
		(end 221.202 111.927)
		(width 0.19)
		(layer "F.Cu")
		(net 174)
	)
	(segment
		(start 233.49337 119.615)
		(end 234.271186 118.837182)
		(width 0.19)
		(layer "F.Cu")
		(net 174)
	)
	(segment
		(start 219.708408 111.992)
		(end 219.685408 112.015)
		(width 0.19)
		(layer "F.Cu")
		(net 174)
	)
	(segment
		(start 219.305 111.7)
		(end 219.28 111.7)
		(width 0.19)
		(layer "F.Cu")
		(net 174)
	)
	(segment
		(start 219.952499 111.992)
		(end 219.708408 111.992)
		(width 0.19)
		(layer "F.Cu")
		(net 174)
	)
	(segment
		(start 226.37663 119.615)
		(end 225.585 118.82337)
		(width 0.19)
		(layer "F.Cu")
		(net 174)
	)
	(segment
		(start 224.75363 111.992)
		(end 221.679501 111.992)
		(width 0.19)
		(layer "F.Cu")
		(net 174)
	)
	(arc
		(start 232.689997 119.136795)
		(mid 232.831418 119.195374)
		(end 232.889997 119.336795)
		(width 0.19)
		(layer "F.Cu")
		(net 174)
	)
	(arc
		(start 232.189997 119.615)
		(mid 232.331418 119.556421)
		(end 232.389997 119.415)
		(width 0.19)
		(layer "F.Cu")
		(net 174)
	)
	(arc
		(start 232.889997 119.415)
		(mid 232.948576 119.556421)
		(end 233.089997 119.615)
		(width 0.19)
		(layer "F.Cu")
		(net 174)
	)
	(arc
		(start 232.389997 119.336795)
		(mid 232.448576 119.195374)
		(end 232.589997 119.136795)
		(width 0.19)
		(layer "F.Cu")
		(net 174)
	)
	(segment
		(start 233.930532 76.160532)
		(end 233.97 76.2)
		(width 0.2)
		(layer "F.Cu")
		(net 176)
	)
	(segment
		(start 231.430532 76.189468)
		(end 231.42 76.2)
		(width 0.2)
		(layer "F.Cu")
		(net 176)
	)
	(segment
		(start 231.69 82.71)
		(end 232.060532 82.71)
		(width 0.2)
		(layer "F.Cu")
		(net 176)
	)
	(segment
		(start 233.930532 76.239468)
		(end 233.97 76.2)
		(width 0.2)
		(layer "F.Cu")
		(net 176)
	)
	(segment
		(start 233.930532 77.3475)
		(end 233.930532 76.239468)
		(width 0.2)
		(layer "F.Cu")
		(net 176)
	)
	(segment
		(start 231.430532 77.3475)
		(end 231.430532 78.489468)
		(width 0.2)
		(layer "F.Cu")
		(net 176)
	)
	(segment
		(start 231.430532 73.810532)
		(end 231.42 73.8)
		(width 0.2)
		(layer "F.Cu")
		(net 176)
	)
	(segment
		(start 233.930532 75.0725)
		(end 233.930532 76.160532)
		(width 0.2)
		(layer "F.Cu")
		(net 176)
	)
	(segment
		(start 233.930532 73.660532)
		(end 233.92 73.65)
		(width 0.2)
		(layer "F.Cu")
		(net 176)
	)
	(segment
		(start 231.430532 75.0725)
		(end 231.430532 76.189468)
		(width 0.2)
		(layer "F.Cu")
		(net 176)
	)
	(segment
		(start 233.930532 77.3475)
		(end 233.930532 78.589468)
		(width 0.2)
		(layer "F.Cu")
		(net 176)
	)
	(segment
		(start 231.430532 77.3475)
		(end 231.430532 76.210532)
		(width 0.2)
		(layer "F.Cu")
		(net 176)
	)
	(segment
		(start 231.625 82.775)
		(end 231.69 82.71)
		(width 0.2)
		(layer "F.Cu")
		(net 176)
	)
	(segment
		(start 233.930532 75.0725)
		(end 233.930532 73.660532)
		(width 0.2)
		(layer "F.Cu")
		(net 176)
	)
	(segment
		(start 233.930532 78.589468)
		(end 233.92 78.6)
		(width 0.2)
		(layer "F.Cu")
		(net 176)
	)
	(segment
		(start 231.430532 78.489468)
		(end 231.42 78.5)
		(width 0.2)
		(layer "F.Cu")
		(net 176)
	)
	(segment
		(start 231.4 82.775)
		(end 231.625 82.775)
		(width 0.2)
		(layer "F.Cu")
		(net 176)
	)
	(segment
		(start 231.430532 75.0725)
		(end 231.430532 73.810532)
		(width 0.2)
		(layer "F.Cu")
		(net 176)
	)
	(segment
		(start 231.430532 76.210532)
		(end 231.42 76.2)
		(width 0.2)
		(layer "F.Cu")
		(net 176)
	)
	(via
		(at 233.92 73.65)
		(size 0.45)
		(drill 0.1)
		(layers "F.Cu" "B.Cu")
		(net 176)
	)
	(via
		(at 231.4 82.775)
		(size 0.45)
		(drill 0.1)
		(layers "F.Cu" "B.Cu")
		(net 176)
	)
	(via
		(at 204.8 75)
		(size 0.45)
		(drill 0.1)
		(layers "F.Cu" "B.Cu")
		(free yes)
		(net 176)
	)
	(via
		(at 205.4 74.4)
		(size 0.45)
		(drill 0.1)
		(layers "F.Cu" "B.Cu")
		(free yes)
		(net 176)
	)
	(via
		(at 231.42 76.2)
		(size 0.45)
		(drill 0.1)
		(layers "F.Cu" "B.Cu")
		(net 176)
	)
	(via
		(at 205.4 75.6)
		(size 0.45)
		(drill 0.1)
		(layers "F.Cu" "B.Cu")
		(free yes)
		(net 176)
	)
	(via
		(at 212.646446 74.853554)
		(size 0.45)
		(drill 0.1)
		(layers "F.Cu" "B.Cu")
		(net 176)
	)
	(via
		(at 204.8 74.4)
		(size 0.45)
		(drill 0.1)
		(layers "F.Cu" "B.Cu")
		(free yes)
		(net 176)
	)
	(via
		(at 231.42 73.8)
		(size 0.45)
		(drill 0.1)
		(layers "F.Cu" "B.Cu")
		(net 176)
	)
	(via
		(at 231.42 78.5)
		(size 0.45)
		(drill 0.1)
		(layers "F.Cu" "B.Cu")
		(net 176)
	)
	(via
		(at 204.8 75.6)
		(size 0.45)
		(drill 0.1)
		(layers "F.Cu" "B.Cu")
		(free yes)
		(net 176)
	)
	(via
		(at 205.4 75)
		(size 0.45)
		(drill 0.1)
		(layers "F.Cu" "B.Cu")
		(free yes)
		(net 176)
	)
	(via
		(at 206 75)
		(size 0.45)
		(drill 0.1)
		(layers "F.Cu" "B.Cu")
		(free yes)
		(net 176)
	)
	(via
		(at 233.92 78.6)
		(size 0.45)
		(drill 0.1)
		(layers "F.Cu" "B.Cu")
		(net 176)
	)
	(via
		(at 233.97 76.2)
		(size 0.45)
		(drill 0.1)
		(layers "F.Cu" "B.Cu")
		(net 176)
	)
	(via
		(at 232.87 73.5)
		(size 0.45)
		(drill 0.1)
		(layers "F.Cu" "B.Cu")
		(net 176)
	)
	(via
		(at 206 75.6)
		(size 0.45)
		(drill 0.1)
		(layers "F.Cu" "B.Cu")
		(free yes)
		(net 176)
	)
	(via
		(at 206 74.4)
		(size 0.45)
		(drill 0.1)
		(layers "F.Cu" "B.Cu")
		(free yes)
		(net 176)
	)
	(segment
		(start 233.92 74.35)
		(end 233.92 73.65)
		(width 0.1)
		(layer "B.Cu")
		(net 176)
	)
	(segment
		(start 234.17 74.6)
		(end 233.92 74.35)
		(width 0.1)
		(layer "B.Cu")
		(net 176)
	)
	(segment
		(start 211.171 71.229)
		(end 211.4 71)
		(width 0.1)
		(layer "B.Cu")
		(net 176)
	)
	(segment
		(start 233.97 77.2)
		(end 234.28 77.51)
		(width 0.2)
		(layer "B.Cu")
		(net 176)
	)
	(segment
		(start 213.071 71.271)
		(end 213.071 72.011)
		(width 0.1)
		(layer "B.Cu")
		(net 176)
	)
	(segment
		(start 212.8 71)
		(end 213.071 71.271)
		(width 0.1)
		(layer "B.Cu")
		(net 176)
	)
	(segment
		(start 233.97 76.2)
		(end 233.97 77.2)
		(width 0.2)
		(layer "B.Cu")
		(net 176)
	)
	(segment
		(start 212.646446 74.853554)
		(end 212.646446 74.083554)
		(width 0.3)
		(layer "B.Cu")
		(net 176)
	)
	(segment
		(start 211.171 72.011)
		(end 211.171 71.229)
		(width 0.1)
		(layer "B.Cu")
		(net 176)
	)
	(segment
		(start 212.646446 74.083554)
		(end 213.22 73.51)
		(width 0.3)
		(layer "B.Cu")
		(net 176)
	)
	(segment
		(start 211.4 71)
		(end 212.8 71)
		(width 0.1)
		(layer "B.Cu")
		(net 176)
	)
	(segment
		(start 213.071 72.011)
		(end 213.071 73.361)
		(width 0.3)
		(layer "B.Cu")
		(net 176)
	)
	(segment
		(start 234.28 77.51)
		(end 235.09 77.51)
		(width 0.2)
		(layer "B.Cu")
		(net 176)
	)
	(segment
		(start 213.071 73.361)
		(end 213.22 73.51)
		(width 0.3)
		(layer "B.Cu")
		(net 176)
	)
	(segment
		(start 234.406 74.6)
		(end 234.17 74.6)
		(width 0.1)
		(layer "B.Cu")
		(net 176)
	)
	(segment
		(start 64.5 98.8)
		(end 65.7 100)
		(width 0.1)
		(layer "F.Cu")
		(net 186)
	)
	(segment
		(start 65.15 97.95)
		(end 64.75 97.95)
		(width 0.1)
		(layer "F.Cu")
		(net 186)
	)
	(segment
		(start 65.7 100)
		(end 66.4 100)
		(width 0.1)
		(layer "F.Cu")
		(net 186)
	)
	(segment
		(start 64.5 98.2)
		(end 64.5 98.8)
		(width 0.1)
		(layer "F.Cu")
		(net 186)
	)
	(segment
		(start 64.75 97.95)
		(end 64.5 98.2)
		(width 0.1)
		(layer "F.Cu")
		(net 186)
	)
	(via
		(at 66.4 100)
		(size 0.45)
		(drill 0.1)
		(layers "F.Cu" "B.Cu")
		(net 186)
	)
	(segment
		(start 64.59 100.461)
		(end 65.939 100.461)
		(width 0.1)
		(layer "B.Cu")
		(net 186)
	)
	(segment
		(start 65.939 100.461)
		(end 66.4 100)
		(width 0.1)
		(layer "B.Cu")
		(net 186)
	)
	(segment
		(start 66.8 98.2)
		(end 66.8 99)
		(width 0.1)
		(layer "F.Cu")
		(net 194)
	)
	(segment
		(start 66.05 97.95)
		(end 66.55 97.95)
		(width 0.1)
		(layer "F.Cu")
		(net 194)
	)
	(segment
		(start 66.55 97.95)
		(end 66.8 98.2)
		(width 0.1)
		(layer "F.Cu")
		(net 194)
	)
	(via
		(at 66.8 99)
		(size 0.45)
		(drill 0.1)
		(layers "F.Cu" "B.Cu")
		(net 194)
	)
	(segment
		(start 66.338 99.462)
		(end 66.8 99)
		(width 0.1)
		(layer "B.Cu")
		(net 194)
	)
	(segment
		(start 64.59 99.462)
		(end 66.338 99.462)
		(width 0.1)
		(layer "B.Cu")
		(net 194)
	)
	(via
		(at 210.1 56.5)
		(size 0.45)
		(drill 0.1)
		(layers "F.Cu" "B.Cu")
		(net 201)
	)
	(via
		(at 203 64.8)
		(size 0.45)
		(drill 0.1)
		(layers "F.Cu" "B.Cu")
		(net 201)
	)
	(segment
		(start 202.4 65.4)
		(end 203 64.8)
		(width 0.1)
		(layer "B.Cu")
		(net 201)
	)
	(segment
		(start 209.157 58.39)
		(end 209.157 57.443)
		(width 0.15)
		(layer "B.Cu")
		(net 201)
	)
	(segment
		(start 200.4 65.4)
		(end 202.4 65.4)
		(width 0.1)
		(layer "B.Cu")
		(net 201)
	)
	(segment
		(start 200.15 65.65)
		(end 200.4 65.4)
		(width 0.1)
		(layer "B.Cu")
		(net 201)
	)
	(segment
		(start 209.157 57.443)
		(end 209.2 57.4)
		(width 0.15)
		(layer "B.Cu")
		(net 201)
	)
	(segment
		(start 209.2 57.4)
		(end 210.1 56.5)
		(width 0.1)
		(layer "B.Cu")
		(net 201)
	)
	(segment
		(start 209.157 57.443)
		(end 210.1 56.5)
		(width 0.15)
		(layer "B.Cu")
		(net 201)
	)
	(segment
		(start 200.15 65.95)
		(end 200.15 65.65)
		(width 0.1)
		(layer "B.Cu")
		(net 201)
	)
	(segment
		(start 208.6 59.8)
		(end 210.1 58.3)
		(width 0.1)
		(layer "In7.Cu")
		(net 201)
	)
	(segment
		(start 203 64.5)
		(end 203.6 63.9)
		(width 0.1)
		(layer "In7.Cu")
		(net 201)
	)
	(segment
		(start 208.6 62)
		(end 208.6 59.8)
		(width 0.1)
		(layer "In7.Cu")
		(net 201)
	)
	(segment
		(start 206.7 63.9)
		(end 208.6 62)
		(width 0.1)
		(layer "In7.Cu")
		(net 201)
	)
	(segment
		(start 210.1 58.3)
		(end 210.1 56.5)
		(width 0.1)
		(layer "In7.Cu")
		(net 201)
	)
	(segment
		(start 203.6 63.9)
		(end 206.7 63.9)
		(width 0.1)
		(layer "In7.Cu")
		(net 201)
	)
	(segment
		(start 203 64.8)
		(end 203 64.5)
		(width 0.1)
		(layer "In7.Cu")
		(net 201)
	)
	(via
		(at 210.8 56.625)
		(size 0.45)
		(drill 0.1)
		(layers "F.Cu" "B.Cu")
		(net 210)
	)
	(via
		(at 203.6 64.8)
		(size 0.45)
		(drill 0.1)
		(layers "F.Cu" "B.Cu")
		(net 210)
	)
	(segment
		(start 200.15 66.85)
		(end 200.15 67.35)
		(width 0.1)
		(layer "B.Cu")
		(net 210)
	)
	(segment
		(start 202 67.4)
		(end 203.6 65.8)
		(width 0.1)
		(layer "B.Cu")
		(net 210)
	)
	(segment
		(start 200.2 67.4)
		(end 202 67.4)
		(width 0.1)
		(layer "B.Cu")
		(net 210)
	)
	(segment
		(start 200.15 67.35)
		(end 200.2 67.4)
		(width 0.1)
		(layer "B.Cu")
		(net 210)
	)
	(segment
		(start 210.156 58.39)
		(end 210.156 57.269)
		(width 0.15)
		(layer "B.Cu")
		(net 210)
	)
	(segment
		(start 203.6 65.8)
		(end 203.6 64.8)
		(width 0.1)
		(layer "B.Cu")
		(net 210)
	)
	(segment
		(start 210.156 57.269)
		(end 210.8 56.625)
		(width 0.15)
		(layer "B.Cu")
		(net 210)
	)
	(segment
		(start 207.1 64.2)
		(end 209.1 62.2)
		(width 0.1)
		(layer "In7.Cu")
		(net 210)
	)
	(segment
		(start 209.1 62.2)
		(end 209.1 59.9)
		(width 0.1)
		(layer "In7.Cu")
		(net 210)
	)
	(segment
		(start 204.2 64.2)
		(end 207.1 64.2)
		(width 0.1)
		(layer "In7.Cu")
		(net 210)
	)
	(segment
		(start 210.8 58.2)
		(end 210.8 56.625)
		(width 0.1)
		(layer "In7.Cu")
		(net 210)
	)
	(segment
		(start 209.1 59.9)
		(end 210.8 58.2)
		(width 0.1)
		(layer "In7.Cu")
		(net 210)
	)
	(segment
		(start 203.6 64.8)
		(end 204.2 64.2)
		(width 0.1)
		(layer "In7.Cu")
		(net 210)
	)
	(segment
		(start 207.97663 112.385)
		(end 210.208338 112.385)
		(width 0.19)
		(layer "F.Cu")
		(net 212)
	)
	(segment
		(start 205.535 116.47337)
		(end 205.535 114.82663)
		(width 0.19)
		(layer "F.Cu")
		(net 212)
	)
	(segment
		(start 210.838338 112.655163)
		(end 210.838338 112.565)
		(width 0.19)
		(layer "F.Cu")
		(net 212)
	)
	(segment
		(start 205.754 119.354)
		(end 205.7 119.3)
		(width 0.19)
		(layer "F.Cu")
		(net 212)
	)
	(segment
		(start 211.018338 112.385)
		(end 217.98 112.385)
		(width 0.19)
		(layer "F.Cu")
		(net 212)
	)
	(segment
		(start 205.7 119.3)
		(end 205.7 118.984817)
		(width 0.19)
		(layer "F.Cu")
		(net 212)
	)
	(segment
		(start 217.98 112.385)
		(end 218.295 112.7)
		(width 0.19)
		(layer "F.Cu")
		(net 212)
	)
	(segment
		(start 218.295 112.7)
		(end 218.32 112.7)
		(width 0.19)
		(layer "F.Cu")
		(net 212)
	)
	(segment
		(start 210.568338 112.835163)
		(end 210.658338 112.835163)
		(width 0.19)
		(layer "F.Cu")
		(net 212)
	)
	(segment
		(start 210.388338 112.565)
		(end 210.388338 112.655163)
		(width 0.19)
		(layer "F.Cu")
		(net 212)
	)
	(segment
		(start 205.754 119.911)
		(end 205.754 119.354)
		(width 0.19)
		(layer "F.Cu")
		(net 212)
	)
	(segment
		(start 205.535 114.82663)
		(end 207.97663 112.385)
		(width 0.19)
		(layer "F.Cu")
		(net 212)
	)
	(segment
		(start 205.7 118.984817)
		(end 205.935 118.749817)
		(width 0.19)
		(layer "F.Cu")
		(net 212)
	)
	(segment
		(start 205.935 118.749817)
		(end 205.935 116.87337)
		(width 0.19)
		(layer "F.Cu")
		(net 212)
	)
	(segment
		(start 205.935 116.87337)
		(end 205.535 116.47337)
		(width 0.19)
		(layer "F.Cu")
		(net 212)
	)
	(arc
		(start 210.658338 112.835163)
		(mid 210.785617 112.782442)
		(end 210.838338 112.655163)
		(width 0.19)
		(layer "F.Cu")
		(net 212)
	)
	(arc
		(start 210.388338 112.655163)
		(mid 210.441059 112.782442)
		(end 210.568338 112.835163)
		(width 0.19)
		(layer "F.Cu")
		(net 212)
	)
	(arc
		(start 210.838338 112.565)
		(mid 210.891059 112.437721)
		(end 211.018338 112.385)
		(width 0.19)
		(layer "F.Cu")
		(net 212)
	)
	(arc
		(start 210.208338 112.385)
		(mid 210.335617 112.437721)
		(end 210.388338 112.565)
		(width 0.19)
		(layer "F.Cu")
		(net 212)
	)
	(segment
		(start 87.52 61.5)
		(end 87.52 62.5)
		(width 0.1)
		(layer "F.Cu")
		(net 213)
	)
	(segment
		(start 175.25 57.175)
		(end 175.25 58)
		(width 0.1)
		(layer "F.Cu")
		(net 213)
	)
	(segment
		(start 87.52 62.5)
		(end 86.75 62.5)
		(width 0.1)
		(layer "F.Cu")
		(net 213)
	)
	(via
		(at 118.400734 71.14)
		(size 0.45)
		(drill 0.1)
		(layers "F.Cu" "B.Cu")
		(net 213)
	)
	(via
		(at 107.442 70.612)
		(size 0.45)
		(drill 0.1)
		(layers "F.Cu" "B.Cu")
		(net 213)
	)
	(via
		(at 175.25 58)
		(size 0.45)
		(drill 0.1)
		(layers "F.Cu" "B.Cu")
		(net 213)
	)
	(via
		(at 115.484982 70.80445)
		(size 0.45)
		(drill 0.1)
		(layers "F.Cu" "B.Cu")
		(net 213)
	)
	(via
		(at 86.75 62.5)
		(size 0.45)
		(drill 0.1)
		(layers "F.Cu" "B.Cu")
		(net 213)
	)
	(via
		(at 106.3 70.6)
		(size 0.45)
		(drill 0.1)
		(layers "F.Cu" "B.Cu")
		(net 213)
	)
	(via
		(at 114.317784 70.592784)
		(size 0.45)
		(drill 0.1)
		(layers "F.Cu" "B.Cu")
		(net 213)
	)
	(via
		(at 110.35 70.65)
		(size 0.45)
		(drill 0.1)
		(layers "F.Cu" "B.Cu")
		(net 213)
	)
	(via
		(at 122.85 70.2)
		(size 0.45)
		(drill 0.1)
		(layers "F.Cu" "B.Cu")
		(net 213)
	)
	(via
		(at 111.45 70.65)
		(size 0.45)
		(drill 0.1)
		(layers "F.Cu" "B.Cu")
		(net 213)
	)
	(via
		(at 119.32 70.62)
		(size 0.45)
		(drill 0.1)
		(layers "F.Cu" "B.Cu")
		(net 213)
	)
	(via
		(at 120.6 68.3)
		(size 0.45)
		(drill 0.1)
		(layers "F.Cu" "B.Cu")
		(net 213)
	)
	(segment
		(start 105.9 71.5)
		(end 106.46 70.94)
		(width 0.2)
		(layer "B.Cu")
		(net 213)
	)
	(segment
		(start 86.55 71.8)
		(end 87.55 72.8)
		(width 0.2)
		(layer "B.Cu")
		(net 213)
	)
	(segment
		(start 86.55 70.1)
		(end 86.55 71.8)
		(width 0.2)
		(layer "B.Cu")
		(net 213)
	)
	(segment
		(start 99.48 67.25)
		(end 100.43 68.2)
		(width 0.2)
		(layer "B.Cu")
		(net 213)
	)
	(segment
		(start 98.665 68.065)
		(end 99.48 67.25)
		(width 0.2)
		(layer "B.Cu")
		(net 213)
	)
	(segment
		(start 103.9 71.5)
		(end 105.9 71.5)
		(width 0.2)
		(layer "B.Cu")
		(net 213)
	)
	(segment
		(start 122.85 70.22)
		(end 123.31 70.68)
		(width 0.3)
		(layer "B.Cu")
		(net 213)
	)
	(segment
		(start 102.1 68.2)
		(end 103.4 69.5)
		(width 0.2)
		(layer "B.Cu")
		(net 213)
	)
	(segment
		(start 106.38 69.48)
		(end 106.38 70.58)
		(width 0.3)
		(layer "B.Cu")
		(net 213)
	)
	(segment
		(start 118.37 70.6)
		(end 118.830532 70.139468)
		(width 0.3)
		(layer "B.Cu")
		(net 213)
	)
	(segment
		(start 118.830532 70.139468)
		(end 118.830532 69.46)
		(width 0.3)
		(layer "B.Cu")
		(net 213)
	)
	(segment
		(start 95.2 68.9)
		(end 95.95 68.9)
		(width 0.2)
		(layer "B.Cu")
		(net 213)
	)
	(segment
		(start 122.85 70.2)
		(end 122.85 70.23)
		(width 0.3)
		(layer "B.Cu")
		(net 213)
	)
	(segment
		(start 114.85 70.16)
		(end 114.85 69.51)
		(width 0.3)
		(layer "B.Cu")
		(net 213)
	)
	(segment
		(start 119.3 70.59)
		(end 119.281064 70.59)
		(width 0.3)
		(layer "B.Cu")
		(net 213)
	)
	(segment
		(start 87.55 72.8)
		(end 91.3 72.8)
		(width 0.2)
		(layer "B.Cu")
		(net 213)
	)
	(segment
		(start 95.95 68.9)
		(end 96.785 68.065)
		(width 0.2)
		(layer "B.Cu")
		(net 213)
	)
	(segment
		(start 122.85 70.2)
		(end 122.85 70.22)
		(width 0.3)
		(layer "B.Cu")
		(net 213)
	)
	(segment
		(start 106.46 70.66)
		(end 107.37 70.66)
		(width 0.2)
		(layer "B.Cu")
		(net 213)
	)
	(segment
		(start 87.2 69.45)
		(end 86.55 70.1)
		(width 0.2)
		(layer "B.Cu")
		(net 213)
	)
	(segment
		(start 122.85 70.23)
		(end 122.41 70.67)
		(width 0.3)
		(layer "B.Cu")
		(net 213)
	)
	(segment
		(start 110.42 70.65)
		(end 110.4 70.63)
		(width 0.3)
		(layer "B.Cu")
		(net 213)
	)
	(segment
		(start 106.38 70.58)
		(end 106.46 70.66)
		(width 0.3)
		(layer "B.Cu")
		(net 213)
	)
	(segment
		(start 114.4 70.61)
		(end 114.85 70.16)
		(width 0.3)
		(layer "B.Cu")
		(net 213)
	)
	(segment
		(start 118.850532 69.44)
		(end 118.830532 69.46)
		(width 0.3)
		(layer "B.Cu")
		(net 213)
	)
	(segment
		(start 86.75 62.5)
		(end 86.75 64.4)
		(width 0.2)
		(layer "B.Cu")
		(net 213)
	)
	(segment
		(start 118.400734 71.14)
		(end 118.400734 70.630734)
		(width 0.3)
		(layer "B.Cu")
		(net 213)
	)
	(segment
		(start 119.94 69.44)
		(end 118.850532 69.44)
		(width 0.3)
		(layer "B.Cu")
		(net 213)
	)
	(segment
		(start 87.2 64.85)
		(end 87.2 69.45)
		(width 0.2)
		(layer "B.Cu")
		(net 213)
	)
	(segment
		(start 119.94 69.95)
		(end 119.3 70.59)
		(width 0.3)
		(layer "B.Cu")
		(net 213)
	)
	(segment
		(start 115.34 70.6)
		(end 115.29 70.6)
		(width 0.3)
		(layer "B.Cu")
		(net 213)
	)
	(segment
		(start 114.8 69.46)
		(end 114.85 69.46)
		(width 0.3)
		(layer "B.Cu")
		(net 213)
	)
	(segment
		(start 176.38 58)
		(end 175.25 58)
		(width 0.1)
		(layer "B.Cu")
		(net 213)
	)
	(segment
		(start 106.46 70.94)
		(end 106.46 70.66)
		(width 0.2)
		(layer "B.Cu")
		(net 213)
	)
	(segment
		(start 111.425 69.505)
		(end 111.41 69.49)
		(width 0.3)
		(layer "B.Cu")
		(net 213)
	)
	(segment
		(start 103.4 71)
		(end 103.9 71.5)
		(width 0.2)
		(layer "B.Cu")
		(net 213)
	)
	(segment
		(start 122.85 69.6)
		(end 122.77 69.52)
		(width 0.3)
		(layer "B.Cu")
		(net 213)
	)
	(segment
		(start 103.4 69.5)
		(end 103.4 71)
		(width 0.2)
		(layer "B.Cu")
		(net 213)
	)
	(segment
		(start 115.29 70.6)
		(end 114.85 70.16)
		(width 0.3)
		(layer "B.Cu")
		(net 213)
	)
	(segment
		(start 110.375 70.625)
		(end 110.375 69.555)
		(width 0.3)
		(layer "B.Cu")
		(net 213)
	)
	(segment
		(start 122.85 70.2)
		(end 122.85 69.6)
		(width 0.3)
		(layer "B.Cu")
		(net 213)
	)
	(segment
		(start 114.85 69.51)
		(end 114.8 69.46)
		(width 0.3)
		(layer "B.Cu")
		(net 213)
	)
	(segment
		(start 110.35 70.65)
		(end 110.375 70.625)
		(width 0.3)
		(layer "B.Cu")
		(net 213)
	)
	(segment
		(start 111.41 69.49)
		(end 110.31 69.49)
		(width 0.3)
		(layer "B.Cu")
		(net 213)
	)
	(segment
		(start 110.375 69.555)
		(end 110.31 69.49)
		(width 0.3)
		(layer "B.Cu")
		(net 213)
	)
	(segment
		(start 111.45 70.65)
		(end 110.42 70.65)
		(width 0.3)
		(layer "B.Cu")
		(net 213)
	)
	(segment
		(start 96.785 68.065)
		(end 98.665 68.065)
		(width 0.2)
		(layer "B.Cu")
		(net 213)
	)
	(segment
		(start 91.3 72.8)
		(end 95.2 68.9)
		(width 0.2)
		(layer "B.Cu")
		(net 213)
	)
	(segment
		(start 86.75 64.4)
		(end 87.2 64.85)
		(width 0.2)
		(layer "B.Cu")
		(net 213)
	)
	(segment
		(start 111.45 70.65)
		(end 111.425 70.625)
		(width 0.3)
		(layer "B.Cu")
		(net 213)
	)
	(segment
		(start 118.400734 70.630734)
		(end 118.37 70.6)
		(width 0.3)
		(layer "B.Cu")
		(net 213)
	)
	(segment
		(start 119.94 69.44)
		(end 119.94 69.95)
		(width 0.3)
		(layer "B.Cu")
		(net 213)
	)
	(segment
		(start 111.425 70.625)
		(end 111.425 69.505)
		(width 0.3)
		(layer "B.Cu")
		(net 213)
	)
	(segment
		(start 119.281064 70.59)
		(end 118.830532 70.139468)
		(width 0.3)
		(layer "B.Cu")
		(net 213)
	)
	(segment
		(start 100.43 68.2)
		(end 102.1 68.2)
		(width 0.2)
		(layer "B.Cu")
		(net 213)
	)
	(segment
		(start 165.018256 67.2)
		(end 162.8 67.2)
		(width 0.1)
		(layer "In2.Cu")
		(net 213)
	)
	(segment
		(start 174.218255 58)
		(end 165.018256 67.2)
		(width 0.1)
		(layer "In2.Cu")
		(net 213)
	)
	(segment
		(start 121.1 67.8)
		(end 120.6 68.3)
		(width 0.1)
		(layer "In2.Cu")
		(net 213)
	)
	(segment
		(start 162.8 67.2)
		(end 162.2 67.8)
		(width 0.1)
		(layer "In2.Cu")
		(net 213)
	)
	(segment
		(start 162.2 67.8)
		(end 121.1 67.8)
		(width 0.1)
		(layer "In2.Cu")
		(net 213)
	)
	(segment
		(start 175.25 58)
		(end 174.218255 58)
		(width 0.1)
		(layer "In2.Cu")
		(net 213)
	)
	(segment
		(start 212 124.18)
		(end 212.58 124.18)
		(width 0.19)
		(layer "F.Cu")
		(net 214)
	)
	(segment
		(start 211.921 124.101)
		(end 212 124.18)
		(width 0.19)
		(layer "F.Cu")
		(net 214)
	)
	(segment
		(start 212.615 124.215)
		(end 214.87663 124.215)
		(width 0.19)
		(layer "F.Cu")
		(net 214)
	)
	(segment
		(start 217.89 126)
		(end 216.66163 126)
		(width 0.19)
		(layer "F.Cu")
		(net 214)
	)
	(segment
		(start 211.142 124.101)
		(end 211.921 124.101)
		(width 0.19)
		(layer "F.Cu")
		(net 214)
	)
	(segment
		(start 212.58 124.18)
		(end 212.615 124.215)
		(width 0.19)
		(layer "F.Cu")
		(net 214)
	)
	(segment
		(start 216.66163 126)
		(end 214.87663 124.215)
		(width 0.19)
		(layer "F.Cu")
		(net 214)
	)
	(segment
		(start 218.215 125.675)
		(end 217.89 126)
		(width 0.19)
		(layer "F.Cu")
		(net 214)
	)
	(segment
		(start 223.36463 104.897)
		(end 222.233501 104.897)
		(width 0.19)
		(layer "F.Cu")
		(net 215)
	)
	(segment
		(start 220.506499 104.897)
		(end 220.475 104.897)
		(width 0.19)
		(layer "F.Cu")
		(net 215)
	)
	(segment
		(start 226.32663 97.935)
		(end 229.64337 97.935)
		(width 0.19)
		(layer "F.Cu")
		(net 215)
	)
	(segment
		(start 225.685 100.553657)
		(end 225.685 102.57663)
		(width 0.19)
		(layer "F.Cu")
		(net 215)
	)
	(segment
		(start 225.685 98.57663)
		(end 226.32663 97.935)
		(width 0.19)
		(layer "F.Cu")
		(net 215)
	)
	(segment
		(start 230.430532 99.853749)
		(end 230.430532 101.0725)
		(width 0.19)
		(layer "F.Cu")
		(net 215)
	)
	(segment
		(start 230.495532 99.788749)
		(end 230.430532 99.853749)
		(width 0.19)
		(layer "F.Cu")
		(net 215)
	)
	(segment
		(start 225.885 99.853657)
		(end 225.96315 99.853657)
		(width 0.19)
		(layer "F.Cu")
		(net 215)
	)
	(segment
		(start 225.685 102.57663)
		(end 223.36463 104.897)
		(width 0.19)
		(layer "F.Cu")
		(net 215)
	)
	(segment
		(start 220.984 104.962)
		(end 220.571499 104.962)
		(width 0.19)
		(layer "F.Cu")
		(net 215)
	)
	(segment
		(start 220.4745 104.8975)
		(end 219.9315 104.8975)
		(width 0.19)
		(layer "F.Cu")
		(net 215)
	)
	(segment
		(start 219.629 105.2)
		(end 219.604 105.2)
		(width 0.19)
		(layer "F.Cu")
		(net 215)
	)
	(segment
		(start 225.96315 100.353657)
		(end 225.885 100.353657)
		(width 0.19)
		(layer "F.Cu")
		(net 215)
	)
	(segment
		(start 222.168501 104.962)
		(end 221.756 104.962)
		(width 0.19)
		(layer "F.Cu")
		(net 215)
	)
	(segment
		(start 229.64337 97.935)
		(end 230.495532 98.787162)
		(width 0.19)
		(layer "F.Cu")
		(net 215)
	)
	(segment
		(start 221.756 104.962)
		(end 220.984 104.962)
		(width 0.19)
		(layer "F.Cu")
		(net 215)
	)
	(segment
		(start 220.475 104.897)
		(end 220.4745 104.8975)
		(width 0.19)
		(layer "F.Cu")
		(net 215)
	)
	(segment
		(start 219.9315 104.8975)
		(end 219.629 105.2)
		(width 0.19)
		(layer "F.Cu")
		(net 215)
	)
	(segment
		(start 226.16315 100.053657)
		(end 226.16315 100.153657)
		(width 0.19)
		(layer "F.Cu")
		(net 215)
	)
	(segment
		(start 222.233501 104.897)
		(end 222.168501 104.962)
		(width 0.19)
		(layer "F.Cu")
		(net 215)
	)
	(segment
		(start 230.495532 98.787162)
		(end 230.495532 99.788749)
		(width 0.19)
		(layer "F.Cu")
		(net 215)
	)
	(segment
		(start 225.685 99.653657)
		(end 225.685 98.57663)
		(width 0.19)
		(layer "F.Cu")
		(net 215)
	)
	(segment
		(start 220.571499 104.962)
		(end 220.506499 104.897)
		(width 0.19)
		(layer "F.Cu")
		(net 215)
	)
	(arc
		(start 225.885 100.353657)
		(mid 225.743579 100.412236)
		(end 225.685 100.553657)
		(width 0.19)
		(layer "F.Cu")
		(net 215)
	)
	(arc
		(start 226.16315 100.153657)
		(mid 226.104571 100.295078)
		(end 225.96315 100.353657)
		(width 0.19)
		(layer "F.Cu")
		(net 215)
	)
	(arc
		(start 225.685 99.653657)
		(mid 225.743579 99.795078)
		(end 225.885 99.853657)
		(width 0.19)
		(layer "F.Cu")
		(net 215)
	)
	(arc
		(start 225.96315 99.853657)
		(mid 226.104571 99.912236)
		(end 226.16315 100.053657)
		(width 0.19)
		(layer "F.Cu")
		(net 215)
	)
	(segment
		(start 121.233 105.499)
		(end 122.501 105.499)
		(width 0.1)
		(layer "B.Cu")
		(net 217)
	)
	(segment
		(start 123.5 104)
		(end 124.5 103)
		(width 0.1)
		(layer "B.Cu")
		(net 217)
	)
	(segment
		(start 122.501 105.499)
		(end 123.5 104.5)
		(width 0.1)
		(layer "B.Cu")
		(net 217)
	)
	(segment
		(start 123.5 104.5)
		(end 123.5 104)
		(width 0.1)
		(layer "B.Cu")
		(net 217)
	)
	(segment
		(start 123.2 110.8)
		(end 124.12 110.8)
		(width 0.1)
		(layer "B.Cu")
		(net 224)
	)
	(segment
		(start 123 111)
		(end 123.2 110.8)
		(width 0.1)
		(layer "B.Cu")
		(net 224)
	)
	(segment
		(start 121.233 111.999)
		(end 122.601 111.999)
		(width 0.1)
		(layer "B.Cu")
		(net 224)
	)
	(segment
		(start 123 111.6)
		(end 123 111)
		(width 0.1)
		(layer "B.Cu")
		(net 224)
	)
	(segment
		(start 122.601 111.999)
		(end 123 111.6)
		(width 0.1)
		(layer "B.Cu")
		(net 224)
	)
	(segment
		(start 218.3165 104.8975)
		(end 218.619 105.2)
		(width 0.19)
		(layer "F.Cu")
		(net 234)
	)
	(segment
		(start 217.86087 104.8975)
		(end 218.3165 104.8975)
		(width 0.19)
		(layer "F.Cu")
		(net 234)
	)
	(segment
		(start 218.619 105.2)
		(end 218.644 105.2)
		(width 0.19)
		(layer "F.Cu")
		(net 234)
	)
	(segment
		(start 216.471 104.125)
		(end 216.4725 104.1235)
		(width 0.19)
		(layer "F.Cu")
		(net 234)
	)
	(segment
		(start 216.4725 104.1235)
		(end 217.08687 104.1235)
		(width 0.19)
		(layer "F.Cu")
		(net 234)
	)
	(segment
		(start 217.08687 104.1235)
		(end 217.86087 104.8975)
		(width 0.19)
		(layer "F.Cu")
		(net 234)
	)
	(segment
		(start 121.233 104.999)
		(end 122.501 104.999)
		(width 0.1)
		(layer "B.Cu")
		(net 235)
	)
	(segment
		(start 122.501 104.999)
		(end 123 104.5)
		(width 0.1)
		(layer "B.Cu")
		(net 235)
	)
	(segment
		(start 123 103)
		(end 124.5 101.5)
		(width 0.1)
		(layer "B.Cu")
		(net 235)
	)
	(segment
		(start 123 104.5)
		(end 123 103)
		(width 0.1)
		(layer "B.Cu")
		(net 235)
	)
	(segment
		(start 122.5 106)
		(end 123.5 105)
		(width 0.1)
		(layer "B.Cu")
		(net 236)
	)
	(segment
		(start 121.233 106)
		(end 122.5 106)
		(width 0.1)
		(layer "B.Cu")
		(net 236)
	)
	(segment
		(start 124 105)
		(end 124.5 104.5)
		(width 0.1)
		(layer "B.Cu")
		(net 236)
	)
	(segment
		(start 123.5 105)
		(end 124 105)
		(width 0.1)
		(layer "B.Cu")
		(net 236)
	)
	(segment
		(start 216.445 102.526)
		(end 216.820001 102.526)
		(width 0.19)
		(layer "F.Cu")
		(net 237)
	)
	(segment
		(start 218.271629 98.690001)
		(end 218.614001 98.690001)
		(width 0.19)
		(layer "F.Cu")
		(net 237)
	)
	(segment
		(start 216.835501 102.5105)
		(end 217.27613 102.5105)
		(width 0.19)
		(layer "F.Cu")
		(net 237)
	)
	(segment
		(start 216.820001 102.526)
		(end 216.835501 102.5105)
		(width 0.19)
		(layer "F.Cu")
		(net 237)
	)
	(segment
		(start 217.27613 102.5105)
		(end 218.06 101.72663)
		(width 0.19)
		(layer "F.Cu")
		(net 237)
	)
	(segment
		(start 218.06 98.90163)
		(end 218.271629 98.690001)
		(width 0.19)
		(layer "F.Cu")
		(net 237)
	)
	(segment
		(start 218.06 101.72663)
		(end 218.06 98.90163)
		(width 0.19)
		(layer "F.Cu")
		(net 237)
	)
	(segment
		(start 218.614001 98.690001)
		(end 218.929001 99.005001)
		(width 0.19)
		(layer "F.Cu")
		(net 237)
	)
	(segment
		(start 220.984 98.762)
		(end 220.571499 98.762)
		(width 0.19)
		(layer "F.Cu")
		(net 241)
	)
	(segment
		(start 220.506499 98.697)
		(end 220.333408 98.697)
		(width 0.19)
		(layer "F.Cu")
		(net 241)
	)
	(segment
		(start 220.984 98.762)
		(end 221.756 98.762)
		(width 0.19)
		(layer "F.Cu")
		(net 241)
	)
	(segment
		(start 222.233501 98.697)
		(end 224.385 98.697)
		(width 0.19)
		(layer "F.Cu")
		(net 241)
	)
	(segment
		(start 224.385 98.697)
		(end 224.5 98.812)
		(width 0.19)
		(layer "F.Cu")
		(net 241)
	)
	(segment
		(start 220.199001 98.695001)
		(end 219.889001 99.005001)
		(width 0.19)
		(layer "F.Cu")
		(net 241)
	)
	(segment
		(start 220.331409 98.695001)
		(end 220.199001 98.695001)
		(width 0.19)
		(layer "F.Cu")
		(net 241)
	)
	(segment
		(start 220.333408 98.697)
		(end 220.331409 98.695001)
		(width 0.19)
		(layer "F.Cu")
		(net 241)
	)
	(segment
		(start 234.430532 103.3475)
		(end 234.430532 104.035)
		(width 0.19)
		(layer "F.Cu")
		(net 241)
	)
	(segment
		(start 221.756 98.762)
		(end 222.168501 98.762)
		(width 0.19)
		(layer "F.Cu")
		(net 241)
	)
	(segment
		(start 234.495532 104.1)
		(end 234.495532 104.585)
		(width 0.19)
		(layer "F.Cu")
		(net 241)
	)
	(segment
		(start 220.571499 98.762)
		(end 220.506499 98.697)
		(width 0.19)
		(layer "F.Cu")
		(net 241)
	)
	(segment
		(start 222.168501 98.762)
		(end 222.233501 98.697)
		(width 0.19)
		(layer "F.Cu")
		(net 241)
	)
	(segment
		(start 234.495532 104.585)
		(end 234.380532 104.7)
		(width 0.19)
		(layer "F.Cu")
		(net 241)
	)
	(segment
		(start 234.430532 104.035)
		(end 234.495532 104.1)
		(width 0.19)
		(layer "F.Cu")
		(net 241)
	)
	(via
		(at 234.380532 104.7)
		(size 0.45)
		(drill 0.1)
		(layers "F.Cu" "B.Cu")
		(net 241)
	)
	(via
		(at 224.5 98.812)
		(size 0.45)
		(drill 0.1)
		(layers "F.Cu" "B.Cu")
		(net 241)
	)
	(segment
		(start 234.543032 104.5375)
		(end 234.380532 104.7)
		(width 0.15)
		(layer "In7.Cu")
		(net 241)
	)
	(segment
		(start 230.663044 97.6375)
		(end 231.9825 98.956956)
		(width 0.15)
		(layer "In7.Cu")
		(net 241)
	)
	(segment
		(start 234.113044 103.1375)
		(end 234.543032 103.567488)
		(width 0.15)
		(layer "In7.Cu")
		(net 241)
	)
	(segment
		(start 228.566364 97.845443)
		(end 228.566364 97.7775)
		(width 0.15)
		(layer "In7.Cu")
		(net 241)
	)
	(segment
		(start 226.556956 97.6375)
		(end 225.544956 98.6495)
		(width 0.15)
		(layer "In7.Cu")
		(net 241)
	)
	(segment
		(start 234.543032 103.567488)
		(end 234.543032 104.5375)
		(width 0.15)
		(layer "In7.Cu")
		(net 241)
	)
	(segment
		(start 232.963044 103.1375)
		(end 234.113044 103.1375)
		(width 0.15)
		(layer "In7.Cu")
		(net 241)
	)
	(segment
		(start 228.706364 97.6375)
		(end 230.663044 97.6375)
		(width 0.15)
		(layer "In7.Cu")
		(net 241)
	)
	(segment
		(start 228.216364 97.7775)
		(end 228.216364 97.845443)
		(width 0.15)
		(layer "In7.Cu")
		(net 241)
	)
	(segment
		(start 224.6625 98.6495)
		(end 224.5 98.812)
		(width 0.15)
		(layer "In7.Cu")
		(net 241)
	)
	(segment
		(start 228.356364 97.985443)
		(end 228.426364 97.985443)
		(width 0.15)
		(layer "In7.Cu")
		(net 241)
	)
	(segment
		(start 225.544956 98.6495)
		(end 224.6625 98.6495)
		(width 0.15)
		(layer "In7.Cu")
		(net 241)
	)
	(segment
		(start 228.076364 97.6375)
		(end 226.556956 97.6375)
		(width 0.15)
		(layer "In7.Cu")
		(net 241)
	)
	(segment
		(start 231.9825 102.156956)
		(end 232.963044 103.1375)
		(width 0.15)
		(layer "In7.Cu")
		(net 241)
	)
	(segment
		(start 231.9825 98.956956)
		(end 231.9825 102.156956)
		(width 0.15)
		(layer "In7.Cu")
		(net 241)
	)
	(arc
		(start 228.076364 97.6375)
		(mid 228.175359 97.678505)
		(end 228.216364 97.7775)
		(width 0.15)
		(layer "In7.Cu")
		(net 241)
	)
	(arc
		(start 228.566364 97.7775)
		(mid 228.607369 97.678505)
		(end 228.706364 97.6375)
		(width 0.15)
		(layer "In7.Cu")
		(net 241)
	)
	(arc
		(start 228.216364 97.845443)
		(mid 228.257369 97.944438)
		(end 228.356364 97.985443)
		(width 0.15)
		(layer "In7.Cu")
		(net 241)
	)
	(arc
		(start 228.426364 97.985443)
		(mid 228.525359 97.944438)
		(end 228.566364 97.845443)
		(width 0.15)
		(layer "In7.Cu")
		(net 241)
	)
	(segment
		(start 216.445 103.726)
		(end 216.4725 103.7535)
		(width 0.19)
		(layer "F.Cu")
		(net 242)
	)
	(segment
		(start 217.24013 103.7535)
		(end 218.01413 104.5275)
		(width 0.19)
		(layer "F.Cu")
		(net 242)
	)
	(segment
		(start 216.4725 103.7535)
		(end 217.24013 103.7535)
		(width 0.19)
		(layer "F.Cu")
		(net 242)
	)
	(segment
		(start 218.3165 104.5275)
		(end 218.619 104.225)
		(width 0.19)
		(layer "F.Cu")
		(net 242)
	)
	(segment
		(start 218.01413 104.5275)
		(end 218.3165 104.5275)
		(width 0.19)
		(layer "F.Cu")
		(net 242)
	)
	(segment
		(start 218.619 104.225)
		(end 218.644 104.225)
		(width 0.19)
		(layer "F.Cu")
		(net 242)
	)
	(via
		(at 137.030532 75.15)
		(size 0.45)
		(drill 0.1)
		(layers "F.Cu" "B.Cu")
		(net 243)
	)
	(segment
		(start 122.31 134.01)
		(end 123.25 134.95)
		(width 0.1)
		(layer "B.Cu")
		(net 244)
	)
	(segment
		(start 123.25 134.95)
		(end 124.12 134.95)
		(width 0.1)
		(layer "B.Cu")
		(net 244)
	)
	(segment
		(start 121.209 134.01)
		(end 122.31 134.01)
		(width 0.1)
		(layer "B.Cu")
		(net 244)
	)
	(segment
		(start 230.930532 99.853749)
		(end 230.930532 101.0725)
		(width 0.19)
		(layer "F.Cu")
		(net 245)
	)
	(segment
		(start 220.506499 104.527)
		(end 220.333408 104.527)
		(width 0.19)
		(layer "F.Cu")
		(net 245)
	)
	(segment
		(start 226.17337 97.565)
		(end 229.79663 97.565)
		(width 0.19)
		(layer "F.Cu")
		(net 245)
	)
	(segment
		(start 219.629 104.225)
		(end 219.604 104.225)
		(width 0.19)
		(layer "F.Cu")
		(net 245)
	)
	(segment
		(start 220.984 104.462)
		(end 221.756 104.462)
		(width 0.19)
		(layer "F.Cu")
		(net 245)
	)
	(segment
		(start 220.333408 104.527)
		(end 220.332908 104.5275)
		(width 0.19)
		(layer "F.Cu")
		(net 245)
	)
	(segment
		(start 225.315 98.42337)
		(end 226.17337 97.565)
		(width 0.19)
		(layer "F.Cu")
		(net 245)
	)
	(segment
		(start 230.865532 99.788749)
		(end 230.930532 99.853749)
		(width 0.19)
		(layer "F.Cu")
		(net 245)
	)
	(segment
		(start 220.571499 104.462)
		(end 220.506499 104.527)
		(width 0.19)
		(layer "F.Cu")
		(net 245)
	)
	(segment
		(start 230.865532 98.633902)
		(end 230.865532 99.788749)
		(width 0.19)
		(layer "F.Cu")
		(net 245)
	)
	(segment
		(start 222.233501 104.527)
		(end 223.21137 104.527)
		(width 0.19)
		(layer "F.Cu")
		(net 245)
	)
	(segment
		(start 222.168501 104.462)
		(end 222.233501 104.527)
		(width 0.19)
		(layer "F.Cu")
		(net 245)
	)
	(segment
		(start 225.315 102.42337)
		(end 225.315 98.42337)
		(width 0.19)
		(layer "F.Cu")
		(net 245)
	)
	(segment
		(start 221.756 104.462)
		(end 222.168501 104.462)
		(width 0.19)
		(layer "F.Cu")
		(net 245)
	)
	(segment
		(start 219.9315 104.5275)
		(end 219.629 104.225)
		(width 0.19)
		(layer "F.Cu")
		(net 245)
	)
	(segment
		(start 229.79663 97.565)
		(end 230.865532 98.633902)
		(width 0.19)
		(layer "F.Cu")
		(net 245)
	)
	(segment
		(start 223.21137 104.527)
		(end 225.315 102.42337)
		(width 0.19)
		(layer "F.Cu")
		(net 245)
	)
	(segment
		(start 220.332908 104.5275)
		(end 219.9315 104.5275)
		(width 0.19)
		(layer "F.Cu")
		(net 245)
	)
	(segment
		(start 220.984 104.462)
		(end 220.571499 104.462)
		(width 0.19)
		(layer "F.Cu")
		(net 245)
	)
	(segment
		(start 181.746 90.631)
		(end 183.131 90.631)
		(width 0.1)
		(layer "F.Cu")
		(net 246)
	)
	(segment
		(start 126.2 65.78)
		(end 122.12 65.78)
		(width 0.1)
		(layer "F.Cu")
		(net 246)
	)
	(segment
		(start 183.45 90.95)
		(end 183.45 91.38)
		(width 0.1)
		(layer "F.Cu")
		(net 246)
	)
	(segment
		(start 126.694212 63.49)
		(end 126.694212 65.285788)
		(width 0.1)
		(layer "F.Cu")
		(net 246)
	)
	(segment
		(start 183.131 90.631)
		(end 183.29 90.79)
		(width 0.1)
		(layer "F.Cu")
		(net 246)
	)
	(segment
		(start 88.83 62.85)
		(end 88.48 62.5)
		(width 0.1)
		(layer "F.Cu")
		(net 246)
	)
	(segment
		(start 137.730532 70.65)
		(end 137.730532 66.809468)
		(width 0.1)
		(layer "F.Cu")
		(net 246)
	)
	(segment
		(start 87.52 63.46)
		(end 88.48 62.5)
		(width 0.1)
		(layer "F.Cu")
		(net 246)
	)
	(segment
		(start 126.694212 65.285788)
		(end 126.2 65.78)
		(width 0.1)
		(layer "F.Cu")
		(net 246)
	)
	(segment
		(start 137.730532 66.809468)
		(end 137.87 66.67)
		(width 0.1)
		(layer "F.Cu")
		(net 246)
	)
	(segment
		(start 181.64 90.525)
		(end 181.746 90.631)
		(width 0.1)
		(layer "F.Cu")
		(net 246)
	)
	(segment
		(start 183.29 90.79)
		(end 183.45 90.95)
		(width 0.1)
		(layer "F.Cu")
		(net 246)
	)
	(segment
		(start 122.12 65.78)
		(end 121.4 65.06)
		(width 0.1)
		(layer "F.Cu")
		(net 246)
	)
	(segment
		(start 89.9 62.85)
		(end 88.83 62.85)
		(width 0.1)
		(layer "F.Cu")
		(net 246)
	)
	(segment
		(start 87.52 63.5)
		(end 87.52 63.46)
		(width 0.1)
		(layer "F.Cu")
		(net 246)
	)
	(via
		(at 122.82 68.27)
		(size 0.45)
		(drill 0.1)
		(layers "F.Cu" "B.Cu")
		(net 246)
	)
	(via
		(at 137.87 66.67)
		(size 0.45)
		(drill 0.1)
		(layers "F.Cu" "B.Cu")
		(net 246)
	)
	(via
		(at 87.52 63.5)
		(size 0.45)
		(drill 0.1)
		(layers "F.Cu" "B.Cu")
		(net 246)
	)
	(via
		(at 183.45 91.38)
		(size 0.45)
		(drill 0.1)
		(layers "F.Cu" "B.Cu")
		(net 246)
	)
	(via
		(at 121.4 65.06)
		(size 0.45)
		(drill 0.1)
		(layers "F.Cu" "B.Cu")
		(net 246)
	)
	(segment
		(start 170.92 85.64)
		(end 162.67 85.64)
		(width 0.1)
		(layer "B.Cu")
		(net 246)
	)
	(segment
		(start 121.4 65.06)
		(end 120.43 65.06)
		(width 0.1)
		(layer "B.Cu")
		(net 246)
	)
	(segment
		(start 122.82 66.48)
		(end 121.4 65.06)
		(width 0.1)
		(layer "B.Cu")
		(net 246)
	)
	(segment
		(start 183.45 91.38)
		(end 183.45 92.83)
		(width 0.1)
		(layer "B.Cu")
		(net 246)
	)
	(segment
		(start 159.01 81.98)
		(end 157.91 81.98)
		(width 0.1)
		(layer "B.Cu")
		(net 246)
	)
	(segment
		(start 122.82 68.27)
		(end 122.82 66.48)
		(width 0.1)
		(layer "B.Cu")
		(net 246)
	)
	(segment
		(start 142.47 67.77)
		(end 141.55 66.85)
		(width 0.1)
		(layer "B.Cu")
		(net 246)
	)
	(segment
		(start 175.22 92.898255)
		(end 175.22 91.45)
		(width 0.1)
		(layer "B.Cu")
		(net 246)
	)
	(segment
		(start 174.16 89.4)
		(end 174.16 88.88)
		(width 0.1)
		(layer "B.Cu")
		(net 246)
	)
	(segment
		(start 145.09 67.77)
		(end 142.47 67.77)
		(width 0.1)
		(layer "B.Cu")
		(net 246)
	)
	(segment
		(start 150.74 75.02)
		(end 147.79 72.07)
		(width 0.1)
		(layer "B.Cu")
		(net 246)
	)
	(segment
		(start 174.16 88.88)
		(end 170.92 85.64)
		(width 0.1)
		(layer "B.Cu")
		(net 246)
	)
	(segment
		(start 157.91 81.98)
		(end 150.95 75.02)
		(width 0.1)
		(layer "B.Cu")
		(net 246)
	)
	(segment
		(start 183.45 92.83)
		(end 182.45 93.83)
		(width 0.1)
		(layer "B.Cu")
		(net 246)
	)
	(segment
		(start 147.79 72.07)
		(end 147.79 70.47)
		(width 0.1)
		(layer "B.Cu")
		(net 246)
	)
	(segment
		(start 141.55 66.85)
		(end 138.58 66.85)
		(width 0.1)
		(layer "B.Cu")
		(net 246)
	)
	(segment
		(start 182.45 93.83)
		(end 176.151745 93.83)
		(width 0.1)
		(layer "B.Cu")
		(net 246)
	)
	(segment
		(start 175.22 91.45)
		(end 174.68 90.91)
		(width 0.1)
		(layer "B.Cu")
		(net 246)
	)
	(segment
		(start 147.79 70.47)
		(end 145.09 67.77)
		(width 0.1)
		(layer "B.Cu")
		(net 246)
	)
	(segment
		(start 138.4 66.67)
		(end 137.87 66.67)
		(width 0.1)
		(layer "B.Cu")
		(net 246)
	)
	(segment
		(start 162.67 85.64)
		(end 159.01 81.98)
		(width 0.1)
		(layer "B.Cu")
		(net 246)
	)
	(segment
		(start 176.151745 93.83)
		(end 175.22 92.898255)
		(width 0.1)
		(layer "B.Cu")
		(net 246)
	)
	(segment
		(start 174.68 89.92)
		(end 174.16 89.4)
		(width 0.1)
		(layer "B.Cu")
		(net 246)
	)
	(segment
		(start 150.95 75.02)
		(end 150.74 75.02)
		(width 0.1)
		(layer "B.Cu")
		(net 246)
	)
	(segment
		(start 138.58 66.85)
		(end 138.4 66.67)
		(width 0.1)
		(layer "B.Cu")
		(net 246)
	)
	(segment
		(start 174.68 90.91)
		(end 174.68 89.92)
		(width 0.1)
		(layer "B.Cu")
		(net 246)
	)
	(segment
		(start 121.4 65.06)
		(end 110.72 65.06)
		(width 0.1)
		(layer "In5.Cu")
		(net 246)
	)
	(segment
		(start 122.82 68.27)
		(end 122.94 68.39)
		(width 0.1)
		(layer "In5.Cu")
		(net 246)
	)
	(segment
		(start 136.15 68.39)
		(end 137.87 66.67)
		(width 0.1)
		(layer "In5.Cu")
		(net 246)
	)
	(segment
		(start 97.6 63.91)
		(end 91.52 63.91)
		(width 0.1)
		(layer "In5.Cu")
		(net 246)
	)
	(segment
		(start 98.35 64.66)
		(end 97.6 63.91)
		(width 0.1)
		(layer "In5.Cu")
		(net 246)
	)
	(segment
		(start 88.26 64.24)
		(end 87.52 63.5)
		(width 0.1)
		(layer "In5.Cu")
		(net 246)
	)
	(segment
		(start 122.94 68.39)
		(end 136.15 68.39)
		(width 0.1)
		(layer "In5.Cu")
		(net 246)
	)
	(segment
		(start 110.72 65.06)
		(end 110.32 64.66)
		(width 0.1)
		(layer "In5.Cu")
		(net 246)
	)
	(segment
		(start 91.52 63.91)
		(end 91.19 64.24)
		(width 0.1)
		(layer "In5.Cu")
		(net 246)
	)
	(segment
		(start 91.19 64.24)
		(end 88.26 64.24)
		(width 0.1)
		(layer "In5.Cu")
		(net 246)
	)
	(segment
		(start 110.32 64.66)
		(end 98.35 64.66)
		(width 0.1)
		(layer "In5.Cu")
		(net 246)
	)
	(segment
		(start 123.225 133.925)
		(end 124.12 133.925)
		(width 0.1)
		(layer "B.Cu")
		(net 247)
	)
	(segment
		(start 121.209 133.51)
		(end 122.81 133.51)
		(width 0.1)
		(layer "B.Cu")
		(net 247)
	)
	(segment
		(start 122.81 133.51)
		(end 123.225 133.925)
		(width 0.1)
		(layer "B.Cu")
		(net 247)
	)
	(segment
		(start 126.855532 84.425)
		(end 126.855532 84.775)
		(width 0.17)
		(layer "F.Cu")
		(net 249)
	)
	(segment
		(start 126.855532 84.775)
		(end 126.980532 84.9)
		(width 0.17)
		(layer "F.Cu")
		(net 249)
	)
	(segment
		(start 127.130532 84.15)
		(end 126.855532 84.425)
		(width 0.17)
		(layer "F.Cu")
		(net 249)
	)
	(via
		(at 63.3 110.91)
		(size 0.45)
		(drill 0.1)
		(layers "F.Cu" "B.Cu")
		(net 249)
	)
	(via
		(at 126.980532 84.9)
		(size 0.45)
		(drill 0.1)
		(layers "F.Cu" "B.Cu")
		(net 249)
	)
	(segment
		(start 64.59 110.96)
		(end 63.689999 110.96)
		(width 0.17)
		(layer "B.Cu")
		(net 249)
	)
	(segment
		(start 63.425 111.035)
		(end 63.3 110.91)
		(width 0.17)
		(layer "B.Cu")
		(net 249)
	)
	(segment
		(start 63.689999 110.96)
		(end 63.614999 111.035)
		(width 0.17)
		(layer "B.Cu")
		(net 249)
	)
	(segment
		(start 63.614999 111.035)
		(end 63.425 111.035)
		(width 0.17)
		(layer "B.Cu")
		(net 249)
	)
	(segment
		(start 71.8466 88.5125)
		(end 89.2466 88.5125)
		(width 0.125)
		(layer "In2.Cu")
		(net 249)
	)
	(segment
		(start 71.5125 88.8466)
		(end 71.8466 88.5125)
		(width 0.125)
		(layer "In2.Cu")
		(net 249)
	)
	(segment
		(start 116.693292 86.475)
		(end 116.693292 86.125)
		(width 0.125)
		(layer "In2.Cu")
		(net 249)
	)
	(segment
		(start 119.874792 86.4125)
		(end 124.6466 86.4125)
		(width 0.125)
		(layer "In2.Cu")
		(net 249)
	)
	(segment
		(start 115.535792 86.4125)
		(end 115.764542 86.4125)
		(width 0.125)
		(layer "In2.Cu")
		(net 249)
	)
	(segment
		(start 65.1466 111.4125)
		(end 70.8466 111.4125)
		(width 0.125)
		(layer "In2.Cu")
		(net 249)
	)
	(segment
		(start 63.112501 111.097499)
		(end 62.643401 111.097499)
		(width 0.125)
		(layer "In2.Cu")
		(net 249)
	)
	(segment
		(start 107.102542 85.446644)
		(end 107.224542 85.446644)
		(width 0.125)
		(layer "In2.Cu")
		(net 249)
	)
	(segment
		(start 116.755792 86.0625)
		(end 117.015792 86.0625)
		(width 0.125)
		(layer "In2.Cu")
		(net 249)
	)
	(segment
		(start 125.4466 85.6125)
		(end 126.268032 85.6125)
		(width 0.125)
		(layer "In2.Cu")
		(net 249)
	)
	(segment
		(start 113.674542 86.7625)
		(end 113.965792 86.7625)
		(width 0.125)
		(layer "In2.Cu")
		(net 249)
	)
	(segment
		(start 118.554542 86.7625)
		(end 118.845792 86.7625)
		(width 0.125)
		(layer "In2.Cu")
		(net 249)
	)
	(segment
		(start 64.0466 112.5125)
		(end 65.1466 111.4125)
		(width 0.125)
		(layer "In2.Cu")
		(net 249)
	)
	(segment
		(start 105.882542 85.446644)
		(end 106.004542 85.446644)
		(width 0.125)
		(layer "In2.Cu")
		(net 249)
	)
	(segment
		(start 106.971042 86.501559)
		(end 106.971042 85.578144)
		(width 0.125)
		(layer "In2.Cu")
		(net 249)
	)
	(segment
		(start 114.638292 85.582936)
		(end 114.638292 86.475)
		(width 0.125)
		(layer "In2.Cu")
		(net 249)
	)
	(segment
		(start 117.078292 86.125)
		(end 117.078292 86.475)
		(width 0.125)
		(layer "In2.Cu")
		(net 249)
	)
	(segment
		(start 111.875792 86.4125)
		(end 112.104542 86.4125)
		(width 0.125)
		(layer "In2.Cu")
		(net 249)
	)
	(segment
		(start 119.133292 86.475)
		(end 119.133292 85.660976)
		(width 0.125)
		(layer "In2.Cu")
		(net 249)
	)
	(segment
		(start 112.454542 86.7625)
		(end 112.714542 86.7625)
		(width 0.125)
		(layer "In2.Cu")
		(net 249)
	)
	(segment
		(start 108.794542 86.7625)
		(end 109.054542 86.7625)
		(width 0.125)
		(layer "In2.Cu")
		(net 249)
	)
	(segment
		(start 119.518292 85.660976)
		(end 119.518292 86.056)
		(width 0.125)
		(layer "In2.Cu")
		(net 249)
	)
	(segment
		(start 114.253292 86.475)
		(end 114.253292 85.582936)
		(width 0.125)
		(layer "In2.Cu")
		(net 249)
	)
	(segment
		(start 62.2875 111.4534)
		(end 62.2875 112.1466)
		(width 0.125)
		(layer "In2.Cu")
		(net 249)
	)
	(segment
		(start 107.356042 85.578144)
		(end 107.356042 86.721859)
		(width 0.125)
		(layer "In2.Cu")
		(net 249)
	)
	(segment
		(start 113.064542 86.4125)
		(end 113.324542 86.4125)
		(width 0.125)
		(layer "In2.Cu")
		(net 249)
	)
	(segment
		(start 63.3 110.91)
		(end 63.112501 111.097499)
		(width 0.125)
		(layer "In2.Cu")
		(net 249)
	)
	(segment
		(start 110.978292 85.579539)
		(end 110.978292 86.475)
		(width 0.125)
		(layer "In2.Cu")
		(net 249)
	)
	(segment
		(start 107.712542 87.078359)
		(end 107.834542 87.078359)
		(width 0.125)
		(layer "In2.Cu")
		(net 249)
	)
	(segment
		(start 106.136042 85.578144)
		(end 106.136042 86.501559)
		(width 0.125)
		(layer "In2.Cu")
		(net 249)
	)
	(segment
		(start 106.450101 86.815618)
		(end 106.656983 86.815618)
		(width 0.125)
		(layer "In2.Cu")
		(net 249)
	)
	(segment
		(start 116.114542 86.7625)
		(end 116.405792 86.7625)
		(width 0.125)
		(layer "In2.Cu")
		(net 249)
	)
	(segment
		(start 92.7466 85.0125)
		(end 94.6534 85.0125)
		(width 0.125)
		(layer "In2.Cu")
		(net 249)
	)
	(segment
		(start 110.593292 86.475)
		(end 110.593292 85.579539)
		(width 0.125)
		(layer "In2.Cu")
		(net 249)
	)
	(segment
		(start 62.643401 111.097499)
		(end 62.2875 111.4534)
		(width 0.125)
		(layer "In2.Cu")
		(net 249)
	)
	(segment
		(start 62.2875 112.1466)
		(end 62.6534 112.5125)
		(width 0.125)
		(layer "In2.Cu")
		(net 249)
	)
	(segment
		(start 126.268032 85.6125)
		(end 126.980532 84.9)
		(width 0.125)
		(layer "In2.Cu")
		(net 249)
	)
	(segment
		(start 110.014542 86.7625)
		(end 110.305792 86.7625)
		(width 0.125)
		(layer "In2.Cu")
		(net 249)
	)
	(segment
		(start 89.2466 88.5125)
		(end 92.7466 85.0125)
		(width 0.125)
		(layer "In2.Cu")
		(net 249)
	)
	(segment
		(start 114.384792 85.451436)
		(end 114.506792 85.451436)
		(width 0.125)
		(layer "In2.Cu")
		(net 249)
	)
	(segment
		(start 124.6466 86.4125)
		(end 125.4466 85.6125)
		(width 0.125)
		(layer "In2.Cu")
		(net 249)
	)
	(segment
		(start 71.5125 110.7466)
		(end 71.5125 88.8466)
		(width 0.125)
		(layer "In2.Cu")
		(net 249)
	)
	(segment
		(start 119.264792 85.529476)
		(end 119.386792 85.529476)
		(width 0.125)
		(layer "In2.Cu")
		(net 249)
	)
	(segment
		(start 114.925792 86.7625)
		(end 115.185792 86.7625)
		(width 0.125)
		(layer "In2.Cu")
		(net 249)
	)
	(segment
		(start 117.975792 86.4125)
		(end 118.204542 86.4125)
		(width 0.125)
		(layer "In2.Cu")
		(net 249)
	)
	(segment
		(start 108.322542 86.4125)
		(end 108.444542 86.4125)
		(width 0.125)
		(layer "In2.Cu")
		(net 249)
	)
	(segment
		(start 105.751042 86.056)
		(end 105.751042 85.578144)
		(width 0.125)
		(layer "In2.Cu")
		(net 249)
	)
	(segment
		(start 62.6534 112.5125)
		(end 64.0466 112.5125)
		(width 0.125)
		(layer "In2.Cu")
		(net 249)
	)
	(segment
		(start 96.0534 86.4125)
		(end 105.394542 86.4125)
		(width 0.125)
		(layer "In2.Cu")
		(net 249)
	)
	(segment
		(start 111.265792 86.7625)
		(end 111.525792 86.7625)
		(width 0.125)
		(layer "In2.Cu")
		(net 249)
	)
	(segment
		(start 117.365792 86.7625)
		(end 117.625792 86.7625)
		(width 0.125)
		(layer "In2.Cu")
		(net 249)
	)
	(segment
		(start 109.404542 86.4125)
		(end 109.664542 86.4125)
		(width 0.125)
		(layer "In2.Cu")
		(net 249)
	)
	(segment
		(start 70.8466 111.4125)
		(end 71.5125 110.7466)
		(width 0.125)
		(layer "In2.Cu")
		(net 249)
	)
	(segment
		(start 94.6534 85.0125)
		(end 96.0534 86.4125)
		(width 0.125)
		(layer "In2.Cu")
		(net 249)
	)
	(segment
		(start 110.724792 85.448039)
		(end 110.846792 85.448039)
		(width 0.125)
		(layer "In2.Cu")
		(net 249)
	)
	(segment
		(start 108.191042 86.721859)
		(end 108.191042 86.544)
		(width 0.125)
		(layer "In2.Cu")
		(net 249)
	)
	(arc
		(start 119.518292 86.056)
		(mid 119.622708 86.308084)
		(end 119.874792 86.4125)
		(width 0.125)
		(layer "In2.Cu")
		(net 249)
	)
	(arc
		(start 107.356042 86.721859)
		(mid 107.460458 86.973943)
		(end 107.712542 87.078359)
		(width 0.125)
		(layer "In2.Cu")
		(net 249)
	)
	(arc
		(start 105.751042 85.578144)
		(mid 105.789557 85.485159)
		(end 105.882542 85.446644)
		(width 0.125)
		(layer "In2.Cu")
		(net 249)
	)
	(arc
		(start 109.664542 86.4125)
		(mid 109.708736 86.430806)
		(end 109.727042 86.475)
		(width 0.125)
		(layer "In2.Cu")
		(net 249)
	)
	(arc
		(start 108.507042 86.475)
		(mid 108.591249 86.678293)
		(end 108.794542 86.7625)
		(width 0.125)
		(layer "In2.Cu")
		(net 249)
	)
	(arc
		(start 117.913292 86.475)
		(mid 117.931598 86.430806)
		(end 117.975792 86.4125)
		(width 0.125)
		(layer "In2.Cu")
		(net 249)
	)
	(arc
		(start 117.015792 86.0625)
		(mid 117.059986 86.080806)
		(end 117.078292 86.125)
		(width 0.125)
		(layer "In2.Cu")
		(net 249)
	)
	(arc
		(start 112.104542 86.4125)
		(mid 112.148736 86.430806)
		(end 112.167042 86.475)
		(width 0.125)
		(layer "In2.Cu")
		(net 249)
	)
	(arc
		(start 111.813292 86.475)
		(mid 111.831598 86.430806)
		(end 111.875792 86.4125)
		(width 0.125)
		(layer "In2.Cu")
		(net 249)
	)
	(arc
		(start 106.971042 85.578144)
		(mid 107.009557 85.485159)
		(end 107.102542 85.446644)
		(width 0.125)
		(layer "In2.Cu")
		(net 249)
	)
	(arc
		(start 108.444542 86.4125)
		(mid 108.488736 86.430806)
		(end 108.507042 86.475)
		(width 0.125)
		(layer "In2.Cu")
		(net 249)
	)
	(arc
		(start 118.204542 86.4125)
		(mid 118.248736 86.430806)
		(end 118.267042 86.475)
		(width 0.125)
		(layer "In2.Cu")
		(net 249)
	)
	(arc
		(start 110.593292 85.579539)
		(mid 110.631807 85.486554)
		(end 110.724792 85.448039)
		(width 0.125)
		(layer "In2.Cu")
		(net 249)
	)
	(arc
		(start 114.506792 85.451436)
		(mid 114.599777 85.489951)
		(end 114.638292 85.582936)
		(width 0.125)
		(layer "In2.Cu")
		(net 249)
	)
	(arc
		(start 110.978292 86.475)
		(mid 111.062499 86.678293)
		(end 111.265792 86.7625)
		(width 0.125)
		(layer "In2.Cu")
		(net 249)
	)
	(arc
		(start 116.405792 86.7625)
		(mid 116.609085 86.678293)
		(end 116.693292 86.475)
		(width 0.125)
		(layer "In2.Cu")
		(net 249)
	)
	(arc
		(start 113.324542 86.4125)
		(mid 113.368736 86.430806)
		(end 113.387042 86.475)
		(width 0.125)
		(layer "In2.Cu")
		(net 249)
	)
	(arc
		(start 115.764542 86.4125)
		(mid 115.808736 86.430806)
		(end 115.827042 86.475)
		(width 0.125)
		(layer "In2.Cu")
		(net 249)
	)
	(arc
		(start 115.185792 86.7625)
		(mid 115.389085 86.678293)
		(end 115.473292 86.475)
		(width 0.125)
		(layer "In2.Cu")
		(net 249)
	)
	(arc
		(start 107.224542 85.446644)
		(mid 107.317527 85.485159)
		(end 107.356042 85.578144)
		(width 0.125)
		(layer "In2.Cu")
		(net 249)
	)
	(arc
		(start 119.386792 85.529476)
		(mid 119.479777 85.567991)
		(end 119.518292 85.660976)
		(width 0.125)
		(layer "In2.Cu")
		(net 249)
	)
	(arc
		(start 110.846792 85.448039)
		(mid 110.939777 85.486554)
		(end 110.978292 85.579539)
		(width 0.125)
		(layer "In2.Cu")
		(net 249)
	)
	(arc
		(start 114.638292 86.475)
		(mid 114.722499 86.678293)
		(end 114.925792 86.7625)
		(width 0.125)
		(layer "In2.Cu")
		(net 249)
	)
	(arc
		(start 109.054542 86.7625)
		(mid 109.257835 86.678293)
		(end 109.342042 86.475)
		(width 0.125)
		(layer "In2.Cu")
		(net 249)
	)
	(arc
		(start 106.656983 86.815618)
		(mid 106.879056 86.723632)
		(end 106.971042 86.501559)
		(width 0.125)
		(layer "In2.Cu")
		(net 249)
	)
	(arc
		(start 109.342042 86.475)
		(mid 109.360348 86.430806)
		(end 109.404542 86.4125)
		(width 0.125)
		(layer "In2.Cu")
		(net 249)
	)
	(arc
		(start 113.387042 86.475)
		(mid 113.471249 86.678293)
		(end 113.674542 86.7625)
		(width 0.125)
		(layer "In2.Cu")
		(net 249)
	)
	(arc
		(start 119.133292 85.660976)
		(mid 119.171807 85.567991)
		(end 119.264792 85.529476)
		(width 0.125)
		(layer "In2.Cu")
		(net 249)
	)
	(arc
		(start 115.827042 86.475)
		(mid 115.911249 86.678293)
		(end 116.114542 86.7625)
		(width 0.125)
		(layer "In2.Cu")
		(net 249)
	)
	(arc
		(start 106.136042 86.501559)
		(mid 106.228028 86.723632)
		(end 106.450101 86.815618)
		(width 0.125)
		(layer "In2.Cu")
		(net 249)
	)
	(arc
		(start 110.305792 86.7625)
		(mid 110.509085 86.678293)
		(end 110.593292 86.475)
		(width 0.125)
		(layer "In2.Cu")
		(net 249)
	)
	(arc
		(start 117.078292 86.475)
		(mid 117.162499 86.678293)
		(end 117.365792 86.7625)
		(width 0.125)
		(layer "In2.Cu")
		(net 249)
	)
	(arc
		(start 108.191042 86.544)
		(mid 108.229557 86.451015)
		(end 108.322542 86.4125)
		(width 0.125)
		(layer "In2.Cu")
		(net 249)
	)
	(arc
		(start 111.525792 86.7625)
		(mid 111.729085 86.678293)
		(end 111.813292 86.475)
		(width 0.125)
		(layer "In2.Cu")
		(net 249)
	)
	(arc
		(start 105.394542 86.4125)
		(mid 105.646626 86.308084)
		(end 105.751042 86.056)
		(width 0.125)
		(layer "In2.Cu")
		(net 249)
	)
	(arc
		(start 113.002042 86.475)
		(mid 113.020348 86.430806)
		(end 113.064542 86.4125)
		(width 0.125)
		(layer "In2.Cu")
		(net 249)
	)
	(arc
		(start 115.473292 86.475)
		(mid 115.491598 86.430806)
		(end 115.535792 86.4125)
		(width 0.125)
		(layer "In2.Cu")
		(net 249)
	)
	(arc
		(start 109.727042 86.475)
		(mid 109.811249 86.678293)
		(end 110.014542 86.7625)
		(width 0.125)
		(layer "In2.Cu")
		(net 249)
	)
	(arc
		(start 118.845792 86.7625)
		(mid 119.049085 86.678293)
		(end 119.133292 86.475)
		(width 0.125)
		(layer "In2.Cu")
		(net 249)
	)
	(arc
		(start 114.253292 85.582936)
		(mid 114.291807 85.489951)
		(end 114.384792 85.451436)
		(width 0.125)
		(layer "In2.Cu")
		(net 249)
	)
	(arc
		(start 112.714542 86.7625)
		(mid 112.917835 86.678293)
		(end 113.002042 86.475)
		(width 0.125)
		(layer "In2.Cu")
		(net 249)
	)
	(arc
		(start 118.267042 86.475)
		(mid 118.351249 86.678293)
		(end 118.554542 86.7625)
		(width 0.125)
		(layer "In2.Cu")
		(net 249)
	)
	(arc
		(start 106.004542 85.446644)
		(mid 106.097527 85.485159)
		(end 106.136042 85.578144)
		(width 0.125)
		(layer "In2.Cu")
		(net 249)
	)
	(arc
		(start 117.625792 86.7625)
		(mid 117.829085 86.678293)
		(end 117.913292 86.475)
		(width 0.125)
		(layer "In2.Cu")
		(net 249)
	)
	(arc
		(start 107.834542 87.078359)
		(mid 108.086626 86.973943)
		(end 108.191042 86.721859)
		(width 0.125)
		(layer "In2.Cu")
		(net 249)
	)
	(arc
		(start 116.693292 86.125)
		(mid 116.711598 86.080806)
		(end 116.755792 86.0625)
		(width 0.125)
		(layer "In2.Cu")
		(net 249)
	)
	(arc
		(start 112.167042 86.475)
		(mid 112.251249 86.678293)
		(end 112.454542 86.7625)
		(width 0.125)
		(layer "In2.Cu")
		(net 249)
	)
	(arc
		(start 113.965792 86.7625)
		(mid 114.169085 86.678293)
		(end 114.253292 86.475)
		(width 0.125)
		(layer "In2.Cu")
		(net 249)
	)
	(segment
		(start 172.5 116.956532)
		(end 172.869468 117.326)
		(width 0.1)
		(layer "F.Cu")
		(net 253)
	)
	(segment
		(start 172.7 115.966)
		(end 172.5 116.166)
		(width 0.1)
		(layer "F.Cu")
		(net 253)
	)
	(segment
		(start 182.475 108.225)
		(end 182.72 107.98)
		(width 0.2)
		(layer "F.Cu")
		(net 253)
	)
	(segment
		(start 172.5 116.166)
		(end 172.5 116.956532)
		(width 0.1)
		(layer "F.Cu")
		(net 253)
	)
	(segment
		(start 173.5 115.966)
		(end 172.7 115.966)
		(width 0.1)
		(layer "F.Cu")
		(net 253)
	)
	(segment
		(start 182.475 109.06)
		(end 182.475 108.225)
		(width 0.2)
		(layer "F.Cu")
		(net 253)
	)
	(via
		(at 177.75 114.29)
		(size 0.45)
		(drill 0.1)
		(layers "F.Cu" "B.Cu")
		(remove_unused_layers yes)
		(keep_end_layers yes)
		(zone_layer_connections)
		(net 253)
	)
	(via
		(at 182.72 107.98)
		(size 0.45)
		(drill 0.1)
		(layers "F.Cu" "B.Cu")
		(remove_unused_layers yes)
		(keep_end_layers yes)
		(zone_layer_connections)
		(net 253)
	)
	(segment
		(start 180.06 114.29)
		(end 177.75 114.29)
		(width 0.2)
		(layer "In5.Cu")
		(net 253)
	)
	(segment
		(start 182.72 107.98)
		(end 182.72 111.63)
		(width 0.2)
		(layer "In5.Cu")
		(net 253)
	)
	(segment
		(start 182.72 111.63)
		(end 180.06 114.29)
		(width 0.2)
		(layer "In5.Cu")
		(net 253)
	)
	(segment
		(start 123.3 136.1)
		(end 124.6 136.1)
		(width 0.1)
		(layer "B.Cu")
		(net 257)
	)
	(segment
		(start 122.71 135.51)
		(end 123.3 136.1)
		(width 0.1)
		(layer "B.Cu")
		(net 257)
	)
	(segment
		(start 121.209 135.51)
		(end 122.71 135.51)
		(width 0.1)
		(layer "B.Cu")
		(net 257)
	)
	(segment
		(start 112.016 121.184)
		(end 111.6 121.6)
		(width 0.17)
		(layer "B.Cu")
		(net 259)
	)
	(segment
		(start 113.711 121.259)
		(end 113.086 121.259)
		(width 0.17)
		(layer "B.Cu")
		(net 259)
	)
	(segment
		(start 113.086 121.259)
		(end 113.011 121.184)
		(width 0.17)
		(layer "B.Cu")
		(net 259)
	)
	(segment
		(start 113.011 121.184)
		(end 112.016 121.184)
		(width 0.17)
		(layer "B.Cu")
		(net 259)
	)
	(segment
		(start 218.614001 98.320001)
		(end 218.924001 98.010001)
		(width 0.19)
		(layer "F.Cu")
		(net 260)
	)
	(segment
		(start 217.12287 102.1405)
		(end 217.69 101.57337)
		(width 0.19)
		(layer "F.Cu")
		(net 260)
	)
	(segment
		(start 216.835501 102.1405)
		(end 217.12287 102.1405)
		(width 0.19)
		(layer "F.Cu")
		(net 260)
	)
	(segment
		(start 217.69 101.57337)
		(end 217.69 98.74837)
		(width 0.19)
		(layer "F.Cu")
		(net 260)
	)
	(segment
		(start 217.69 98.74837)
		(end 218.118369 98.320001)
		(width 0.19)
		(layer "F.Cu")
		(net 260)
	)
	(segment
		(start 218.118369 98.320001)
		(end 218.614001 98.320001)
		(width 0.19)
		(layer "F.Cu")
		(net 260)
	)
	(segment
		(start 216.445 102.125)
		(end 216.820001 102.125)
		(width 0.19)
		(layer "F.Cu")
		(net 260)
	)
	(segment
		(start 216.820001 102.125)
		(end 216.835501 102.1405)
		(width 0.19)
		(layer "F.Cu")
		(net 260)
	)
	(segment
		(start 161.99 60.81)
		(end 161.99 62.32)
		(width 0.2)
		(layer "F.Cu")
		(net 269)
	)
	(segment
		(start 163.8 61)
		(end 163.2 60.4)
		(width 0.2)
		(layer "F.Cu")
		(net 269)
	)
	(segment
		(start 163.2 60.4)
		(end 162.4 60.4)
		(width 0.2)
		(layer "F.Cu")
		(net 269)
	)
	(segment
		(start 162.2 64.6)
		(end 163.8 63)
		(width 0.2)
		(layer "F.Cu")
		(net 269)
	)
	(segment
		(start 163.8 63)
		(end 163.8 61)
		(width 0.2)
		(layer "F.Cu")
		(net 269)
	)
	(segment
		(start 162.2 65.2)
		(end 162.2 64.6)
		(width 0.2)
		(layer "F.Cu")
		(net 269)
	)
	(segment
		(start 162.4 60.4)
		(end 161.99 60.81)
		(width 0.2)
		(layer "F.Cu")
		(net 269)
	)
	(via
		(at 162.2 65.2)
		(size 0.45)
		(drill 0.1)
		(layers "F.Cu" "B.Cu")
		(net 269)
	)
	(segment
		(start 160.58 65.32)
		(end 160.85 65.05)
		(width 0.2)
		(layer "B.Cu")
		(net 269)
	)
	(segment
		(start 163.05 64.1)
		(end 163.05 63.6)
		(width 0.2)
		(layer "B.Cu")
		(net 269)
	)
	(segment
		(start 162.2 64.71)
		(end 161.98 64.49)
		(width 0.2)
		(layer "B.Cu")
		(net 269)
	)
	(segment
		(start 163.3 63.35)
		(end 164.994 63.35)
		(width 0.2)
		(layer "B.Cu")
		(net 269)
	)
	(segment
		(start 162.2 65.2)
		(end 162.2 64.71)
		(width 0.2)
		(layer "B.Cu")
		(net 269)
	)
	(segment
		(start 161.57 65.2)
		(end 161.42 65.05)
		(width 0.2)
		(layer "B.Cu")
		(net 269)
	)
	(segment
		(start 162.2 65.2)
		(end 161.57 65.2)
		(width 0.2)
		(layer "B.Cu")
		(net 269)
	)
	(segment
		(start 165.634 62.71)
		(end 167.79 62.71)
		(width 0.2)
		(layer "B.Cu")
		(net 269)
	)
	(segment
		(start 162.66 64.49)
		(end 163.05 64.1)
		(width 0.2)
		(layer "B.Cu")
		(net 269)
	)
	(segment
		(start 167.79 62.71)
		(end 168 62.92)
		(width 0.2)
		(layer "B.Cu")
		(net 269)
	)
	(segment
		(start 164.994 63.35)
		(end 165.634 62.71)
		(width 0.2)
		(layer "B.Cu")
		(net 269)
	)
	(segment
		(start 160.58 65.74)
		(end 160.58 65.32)
		(width 0.2)
		(layer "B.Cu")
		(net 269)
	)
	(segment
		(start 160.85 65.05)
		(end 161.42 65.05)
		(width 0.2)
		(layer "B.Cu")
		(net 269)
	)
	(segment
		(start 163.05 63.6)
		(end 163.3 63.35)
		(width 0.2)
		(layer "B.Cu")
		(net 269)
	)
	(segment
		(start 161.98 64.49)
		(end 162.66 64.49)
		(width 0.2)
		(layer "B.Cu")
		(net 269)
	)
	(segment
		(start 234.930532 104.035)
		(end 234.865532 104.1)
		(width 0.19)
		(layer "F.Cu")
		(net 270)
	)
	(segment
		(start 220.473001 98.325001)
		(end 220.199001 98.325001)
		(width 0.19)
		(layer "F.Cu")
		(net 270)
	)
	(segment
		(start 234.930532 103.3475)
		(end 234.930532 104.035)
		(width 0.19)
		(layer "F.Cu")
		(net 270)
	)
	(segment
		(start 234.865532 104.585)
		(end 234.980532 104.7)
		(width 0.19)
		(layer "F.Cu")
		(net 270)
	)
	(segment
		(start 222.233501 98.327)
		(end 224.385 98.327)
		(width 0.19)
		(layer "F.Cu")
		(net 270)
	)
	(segment
		(start 222.168501 98.262)
		(end 222.233501 98.327)
		(width 0.19)
		(layer "F.Cu")
		(net 270)
	)
	(segment
		(start 220.199001 98.325001)
		(end 219.884001 98.010001)
		(width 0.19)
		(layer "F.Cu")
		(net 270)
	)
	(segment
		(start 220.475 98.327)
		(end 220.473001 98.325001)
		(width 0.19)
		(layer "F.Cu")
		(net 270)
	)
	(segment
		(start 220.984 98.262)
		(end 220.571499 98.262)
		(width 0.19)
		(layer "F.Cu")
		(net 270)
	)
	(segment
		(start 224.385 98.327)
		(end 224.5 98.212)
		(width 0.19)
		(layer "F.Cu")
		(net 270)
	)
	(segment
		(start 220.571499 98.262)
		(end 220.506499 98.327)
		(width 0.19)
		(layer "F.Cu")
		(net 270)
	)
	(segment
		(start 221.756 98.262)
		(end 220.984 98.262)
		(width 0.19)
		(layer "F.Cu")
		(net 270)
	)
	(segment
		(start 234.865532 104.1)
		(end 234.865532 104.585)
		(width 0.19)
		(layer "F.Cu")
		(net 270)
	)
	(segment
		(start 221.756 98.262)
		(end 222.168501 98.262)
		(width 0.19)
		(layer "F.Cu")
		(net 270)
	)
	(segment
		(start 220.506499 98.327)
		(end 220.475 98.327)
		(width 0.19)
		(layer "F.Cu")
		(net 270)
	)
	(via
		(at 224.5 98.212)
		(size 0.45)
		(drill 0.1)
		(layers "F.Cu" "B.Cu")
		(net 270)
	)
	(via
		(at 234.980532 104.7)
		(size 0.45)
		(drill 0.1)
		(layers "F.Cu" "B.Cu")
		(net 270)
	)
	(segment
		(start 233.076956 102.8625)
		(end 232.2575 102.043044)
		(width 0.15)
		(layer "In7.Cu")
		(net 270)
	)
	(segment
		(start 234.980532 104.7)
		(end 234.818032 104.5375)
		(width 0.15)
		(layer "In7.Cu")
		(net 270)
	)
	(segment
		(start 232.2575 98.843044)
		(end 230.776956 97.3625)
		(width 0.15)
		(layer "In7.Cu")
		(net 270)
	)
	(segment
		(start 234.818032 103.453576)
		(end 234.226956 102.8625)
		(width 0.15)
		(layer "In7.Cu")
		(net 270)
	)
	(segment
		(start 225.431044 98.3745)
		(end 224.6625 98.3745)
		(width 0.15)
		(layer "In7.Cu")
		(net 270)
	)
	(segment
		(start 232.2575 102.043044)
		(end 232.2575 98.843044)
		(width 0.15)
		(layer "In7.Cu")
		(net 270)
	)
	(segment
		(start 234.226956 102.8625)
		(end 233.076956 102.8625)
		(width 0.15)
		(layer "In7.Cu")
		(net 270)
	)
	(segment
		(start 226.443044 97.3625)
		(end 225.431044 98.3745)
		(width 0.15)
		(layer "In7.Cu")
		(net 270)
	)
	(segment
		(start 234.818032 104.5375)
		(end 234.818032 103.453576)
		(width 0.15)
		(layer "In7.Cu")
		(net 270)
	)
	(segment
		(start 230.776956 97.3625)
		(end 226.443044 97.3625)
		(width 0.15)
		(layer "In7.Cu")
		(net 270)
	)
	(segment
		(start 224.6625 98.3745)
		(end 224.5 98.212)
		(width 0.15)
		(layer "In7.Cu")
		(net 270)
	)
	(segment
		(start 190.28034 85.48034)
		(end 193.9 89.1)
		(width 0.2)
		(layer "F.Cu")
		(net 271)
	)
	(segment
		(start 192.2 99.2)
		(end 193.9 97.5)
		(width 0.2)
		(layer "F.Cu")
		(net 271)
	)
	(segment
		(start 194.226 83.7)
		(end 194.7 83.7)
		(width 0.2)
		(layer "F.Cu")
		(net 271)
	)
	(segment
		(start 190.28034 85.27034)
		(end 190.28034 85.48034)
		(width 0.2)
		(layer "F.Cu")
		(net 271)
	)
	(segment
		(start 185.75 120.505)
		(end 185.75 116.25)
		(width 0.2)
		(layer "F.Cu")
		(net 271)
	)
	(segment
		(start 194.7 83.7)
		(end 194.8 83.6)
		(width 0.2)
		(layer "F.Cu")
		(net 271)
	)
	(segment
		(start 185.72 123.298)
		(end 185.519 123.499)
		(width 0.2)
		(layer "F.Cu")
		(net 271)
	)
	(segment
		(start 190.26 85.25)
		(end 190.28034 85.22966)
		(width 0.1)
		(layer "F.Cu")
		(net 271)
	)
	(segment
		(start 190.28034 85.22966)
		(end 190.28034 85.11566)
		(width 0.1)
		(layer "F.Cu")
		(net 271)
	)
	(segment
		(start 188.5 113.5)
		(end 188.5 107.9)
		(width 0.2)
		(layer "F.Cu")
		(net 271)
	)
	(segment
		(start 185.72 122.299)
		(end 185.72 123.298)
		(width 0.2)
		(layer "F.Cu")
		(net 271)
	)
	(segment
		(start 185.99 120.405)
		(end 187.1 120.405)
		(width 0.2)
		(layer "F.Cu")
		(net 271)
	)
	(segment
		(start 194.226 84.2)
		(end 194.6 84.2)
		(width 0.2)
		(layer "F.Cu")
		(net 271)
	)
	(segment
		(start 190.28034 85.11566)
		(end 190.698 84.698)
		(width 0.1)
		(layer "F.Cu")
		(net 271)
	)
	(segment
		(start 188.5 107.9)
		(end 192.2 104.2)
		(width 0.2)
		(layer "F.Cu")
		(net 271)
	)
	(segment
		(start 185.75 116.25)
		(end 188.5 113.5)
		(width 0.2)
		(layer "F.Cu")
		(net 271)
	)
	(segment
		(start 194.6 84.2)
		(end 194.8 84)
		(width 0.2)
		(layer "F.Cu")
		(net 271)
	)
	(segment
		(start 185.72 122.299)
		(end 185.72 120.675)
		(width 0.2)
		(layer "F.Cu")
		(net 271)
	)
	(segment
		(start 185.72 120.675)
		(end 185.99 120.405)
		(width 0.2)
		(layer "F.Cu")
		(net 271)
	)
	(segment
		(start 194.8 83.2)
		(end 194.8 82.92)
		(width 0.2)
		(layer "F.Cu")
		(net 271)
	)
	(segment
		(start 194.8 83.2)
		(end 194.8 83.5)
		(width 0.2)
		(layer "F.Cu")
		(net 271)
	)
	(segment
		(start 190.26 85.25)
		(end 190.28034 85.27034)
		(width 0.2)
		(layer "F.Cu")
		(net 271)
	)
	(segment
		(start 187.1 120.405)
		(end 187 120.505)
		(width 0.2)
		(layer "F.Cu")
		(net 271)
	)
	(segment
		(start 194.8 82.92)
		(end 194.28 82.4)
		(width 0.2)
		(layer "F.Cu")
		(net 271)
	)
	(segment
		(start 194.8 83.4)
		(end 194.8 83.2)
		(width 0.2)
		(layer "F.Cu")
		(net 271)
	)
	(segment
		(start 194.8 84)
		(end 194.8 83.4)
		(width 0.2)
		(layer "F.Cu")
		(net 271)
	)
	(segment
		(start 193.9 89.1)
		(end 193.9 96.4)
		(width 0.2)
		(layer "F.Cu")
		(net 271)
	)
	(segment
		(start 194.8 83.6)
		(end 194.8 83.4)
		(width 0.2)
		(layer "F.Cu")
		(net 271)
	)
	(segment
		(start 190.698 84.698)
		(end 191.677001 84.698)
		(width 0.1)
		(layer "F.Cu")
		(net 271)
	)
	(segment
		(start 192.2 104.2)
		(end 192.2 99.2)
		(width 0.2)
		(layer "F.Cu")
		(net 271)
	)
	(segment
		(start 187 120.505)
		(end 185.75 120.505)
		(width 0.2)
		(layer "F.Cu")
		(net 271)
	)
	(segment
		(start 193.9 97.5)
		(end 193.9 96.4)
		(width 0.2)
		(layer "F.Cu")
		(net 271)
	)
	(via
		(at 193.9 96.4)
		(size 0.45)
		(drill 0.1)
		(layers "F.Cu" "B.Cu")
		(net 271)
	)
	(via
		(at 194.8 83.5)
		(size 0.45)
		(drill 0.1)
		(layers "F.Cu" "B.Cu")
		(net 271)
	)
	(via
		(at 190.26 85.25)
		(size 0.45)
		(drill 0.1)
		(layers "F.Cu" "B.Cu")
		(net 271)
	)
	(segment
		(start 194.18 83.52)
		(end 194.2 83.5)
		(width 0.2)
		(layer "B.Cu")
		(net 271)
	)
	(segment
		(start 194.18 84.1)
		(end 194.18 83.52)
		(width 0.2)
		(layer "B.Cu")
		(net 271)
	)
	(segment
		(start 194.8 83.5)
		(end 194.2 83.5)
		(width 0.2)
		(layer "B.Cu")
		(net 271)
	)
	(segment
		(start 194.8 83.5)
		(end 195.702455 83.5)
		(width 0.2)
		(layer "B.Cu")
		(net 271)
	)
	(segment
		(start 190.7 83.5)
		(end 194.2 83.5)
		(width 0.2)
		(layer "B.Cu")
		(net 271)
	)
	(segment
		(start 197.2 86.1)
		(end 208.2 86.1)
		(width 0.2)
		(layer "B.Cu")
		(net 271)
	)
	(segment
		(start 195.702455 83.5)
		(end 196.4 84.197545)
		(width 0.2)
		(layer "B.Cu")
		(net 271)
	)
	(segment
		(start 190.26 85.25)
		(end 190.28034 85.22966)
		(width 0.2)
		(layer "B.Cu")
		(net 271)
	)
	(segment
		(start 193.866 96.366)
		(end 193.9 96.4)
		(width 0.1)
		(layer "B.Cu")
		(net 271)
	)
	(segment
		(start 196.4 84.197545)
		(end 196.4 85.3)
		(width 0.2)
		(layer "B.Cu")
		(net 271)
	)
	(segment
		(start 190.28034 83.91966)
		(end 190.7 83.5)
		(width 0.2)
		(layer "B.Cu")
		(net 271)
	)
	(segment
		(start 193.86 96.366)
		(end 193.866 96.366)
		(width 0.1)
		(layer "B.Cu")
		(net 271)
	)
	(segment
		(start 196.4 85.3)
		(end 197.2 86.1)
		(width 0.2)
		(layer "B.Cu")
		(net 271)
	)
	(segment
		(start 190.28034 85.22966)
		(end 190.28034 83.91966)
		(width 0.2)
		(layer "B.Cu")
		(net 271)
	)
	(segment
		(start 208.9 85.4)
		(end 208.9 84.601)
		(width 0.2)
		(layer "B.Cu")
		(net 271)
	)
	(segment
		(start 208.2 86.1)
		(end 208.9 85.4)
		(width 0.2)
		(layer "B.Cu")
		(net 271)
	)
	(segment
		(start 111.844 120.834)
		(end 111.6 120.59)
		(width 0.17)
		(layer "B.Cu")
		(net 272)
	)
	(segment
		(start 113.086 120.759)
		(end 113.011 120.834)
		(width 0.17)
		(layer "B.Cu")
		(net 272)
	)
	(segment
		(start 113.011 120.834)
		(end 111.844 120.834)
		(width 0.17)
		(layer "B.Cu")
		(net 272)
	)
	(segment
		(start 113.711 120.759)
		(end 113.086 120.759)
		(width 0.17)
		(layer "B.Cu")
		(net 272)
	)
	(segment
		(start 159.1529 144.73)
		(end 159.835 144.73)
		(width 0.15)
		(layer "F.Cu")
		(net 279)
	)
	(segment
		(start 158.4369 145.446)
		(end 159.1529 144.73)
		(width 0.15)
		(layer "F.Cu")
		(net 279)
	)
	(segment
		(start 159.878 144.728)
		(end 160.605 144.728)
		(width 0.15)
		(layer "F.Cu")
		(net 279)
	)
	(segment
		(start 156.604414 145.446)
		(end 158.4369 145.446)
		(width 0.15)
		(layer "F.Cu")
		(net 279)
	)
	(segment
		(start 156.56 143.88)
		(end 156.56 144.38)
		(width 0.15)
		(layer "F.Cu")
		(net 279)
	)
	(segment
		(start 159.833 144.728)
		(end 159.833 144.717)
		(width 0.15)
		(layer "F.Cu")
		(net 279)
	)
	(segment
		(start 162.835132 145.523)
		(end 165.580532 145.523)
		(width 0.15)
		(layer "F.Cu")
		(net 279)
	)
	(segment
		(start 156.26 145.101586)
		(end 156.604414 145.446)
		(width 0.15)
		(layer "F.Cu")
		(net 279)
	)
	(segment
		(start 162.042132 144.73)
		(end 162.835132 145.523)
		(width 0.15)
		(layer "F.Cu")
		(net 279)
	)
	(segment
		(start 159.85 144.7)
		(end 159.878 144.728)
		(width 0.15)
		(layer "F.Cu")
		(net 279)
	)
	(segment
		(start 160.607 144.73)
		(end 162.042132 144.73)
		(width 0.15)
		(layer "F.Cu")
		(net 279)
	)
	(segment
		(start 159.833 144.717)
		(end 159.85 144.7)
		(width 0.15)
		(layer "F.Cu")
		(net 279)
	)
	(segment
		(start 156.56 144.38)
		(end 156.26 144.68)
		(width 0.15)
		(layer "F.Cu")
		(net 279)
	)
	(segment
		(start 156.26 144.68)
		(end 156.26 145.101586)
		(width 0.15)
		(layer "F.Cu")
		(net 279)
	)
	(segment
		(start 192.83 124.44)
		(end 193.19 124.08)
		(width 0.1)
		(layer "F.Cu")
		(net 280)
	)
	(segment
		(start 189.49 124.44)
		(end 192.83 124.44)
		(width 0.1)
		(layer "F.Cu")
		(net 280)
	)
	(segment
		(start 156.56 142.53)
		(end 156.21 142.18)
		(width 0.15)
		(layer "F.Cu")
		(net 281)
	)
	(segment
		(start 158.9339 142.799)
		(end 158.699 143.0339)
		(width 0.15)
		(layer "F.Cu")
		(net 281)
	)
	(segment
		(start 156.21 141.738414)
		(end 156.564414 141.384)
		(width 0.15)
		(layer "F.Cu")
		(net 281)
	)
	(segment
		(start 158.699 143.3661)
		(end 159.0649 143.732)
		(width 0.15)
		(layer "F.Cu")
		(net 281)
	)
	(segment
		(start 161.932 143.732)
		(end 160.607 143.732)
		(width 0.15)
		(layer "F.Cu")
		(net 281)
	)
	(segment
		(start 159.0649 143.732)
		(end 159.835 143.732)
		(width 0.15)
		(layer "F.Cu")
		(net 281)
	)
	(segment
		(start 158.095586 141.384)
		(end 158.9339 142.222314)
		(width 0.15)
		(layer "F.Cu")
		(net 281)
	)
	(segment
		(start 166.45 145.904532)
		(end 166.45 145.205182)
		(width 0.15)
		(layer "F.Cu")
		(net 281)
	)
	(segment
		(start 156.21 142.18)
		(end 156.21 141.738414)
		(width 0.15)
		(layer "F.Cu")
		(net 281)
	)
	(segment
		(start 158.699 143.0339)
		(end 158.699 143.3661)
		(width 0.15)
		(layer "F.Cu")
		(net 281)
	)
	(segment
		(start 156.564414 141.384)
		(end 158.095586 141.384)
		(width 0.15)
		(layer "F.Cu")
		(net 281)
	)
	(segment
		(start 160.605 143.73)
		(end 159.833 143.73)
		(width 0.15)
		(layer "F.Cu")
		(net 281)
	)
	(segment
		(start 165.580532 146.774)
		(end 166.45 145.904532)
		(width 0.15)
		(layer "F.Cu")
		(net 281)
	)
	(segment
		(start 156.56 142.98)
		(end 156.56 142.53)
		(width 0.15)
		(layer "F.Cu")
		(net 281)
	)
	(segment
		(start 158.9339 142.222314)
		(end 158.9339 142.799)
		(width 0.15)
		(layer "F.Cu")
		(net 281)
	)
	(segment
		(start 166.095818 144.851)
		(end 163.051 144.851)
		(width 0.15)
		(layer "F.Cu")
		(net 281)
	)
	(segment
		(start 163.051 144.851)
		(end 161.932 143.732)
		(width 0.15)
		(layer "F.Cu")
		(net 281)
	)
	(segment
		(start 166.45 145.205182)
		(end 166.095818 144.851)
		(width 0.15)
		(layer "F.Cu")
		(net 281)
	)
	(segment
		(start 204.95 118.4)
		(end 204.95 118.38)
		(width 0.2)
		(layer "F.Cu")
		(net 282)
	)
	(segment
		(start 203.7 133.12)
		(end 203.7 132.654)
		(width 0.2)
		(layer "F.Cu")
		(net 282)
	)
	(segment
		(start 213.02 123.68)
		(end 212.92 123.68)
		(width 0.2)
		(layer "F.Cu")
		(net 282)
	)
	(segment
		(start 201 132.5)
		(end 201.354 132.146)
		(width 0.2)
		(layer "F.Cu")
		(net 282)
	)
	(segment
		(start 212.22 120.58)
		(end 212.8 120.58)
		(width 0.2)
		(layer "F.Cu")
		(net 282)
	)
	(segment
		(start 207.354 119.004)
		(end 207.354 119.911)
		(width 0.2)
		(layer "F.Cu")
		(net 282)
	)
	(segment
		(start 213.1 127.2)
		(end 213.12 127.2)
		(width 0.2)
		(layer "F.Cu")
		(net 282)
	)
	(segment
		(start 201.354 131.488)
		(end 201.354 132.146)
		(width 0.2)
		(layer "F.Cu")
		(net 282)
	)
	(segment
		(start 211.142 123.7)
		(end 212.3 123.7)
		(width 0.2)
		(layer "F.Cu")
		(net 282)
	)
	(segment
		(start 213 127.3)
		(end 213.1 127.2)
		(width 0.2)
		(layer "F.Cu")
		(net 282)
	)
	(segment
		(start 211.9 120.9)
		(end 212.22 120.58)
		(width 0.2)
		(layer "F.Cu")
		(net 282)
	)
	(segment
		(start 203.7 132.654)
		(end 204.154 132.2)
		(width 0.2)
		(layer "F.Cu")
		(net 282)
	)
	(segment
		(start 211.142 120.9)
		(end 211.9 120.9)
		(width 0.2)
		(layer "F.Cu")
		(net 282)
	)
	(segment
		(start 207.353 132.947)
		(end 207.35 132.95)
		(width 0.2)
		(layer "F.Cu")
		(net 282)
	)
	(segment
		(start 198.1 122.5)
		(end 198.5 122.5)
		(width 0.2)
		(layer "F.Cu")
		(net 282)
	)
	(segment
		(start 212.9 123.7)
		(end 212.3 123.7)
		(width 0.2)
		(layer "F.Cu")
		(net 282)
	)
	(segment
		(start 212.92 123.68)
		(end 212.9 123.7)
		(width 0.2)
		(layer "F.Cu")
		(net 282)
	)
	(segment
		(start 200.7 132.5)
		(end 200.7 133.22)
		(width 0.2)
		(layer "F.Cu")
		(net 282)
	)
	(segment
		(start 204.95 118.4)
		(end 204.954 118.404)
		(width 0.2)
		(layer "F.Cu")
		(net 282)
	)
	(segment
		(start 204.965 118.365)
		(end 204.965 118.36)
		(width 0.2)
		(layer "F.Cu")
		(net 282)
	)
	(segment
		(start 204.154 132.2)
		(end 204.154 131.488)
		(width 0.2)
		(layer "F.Cu")
		(net 282)
	)
	(segment
		(start 207.35 119)
		(end 207.354 119.004)
		(width 0.2)
		(layer "F.Cu")
		(net 282)
	)
	(segment
		(start 161.72 57.14)
		(end 161.72 58.02)
		(width 0.1)
		(layer "F.Cu")
		(net 282)
	)
	(segment
		(start 197.7 122.9)
		(end 198.1 122.5)
		(width 0.2)
		(layer "F.Cu")
		(net 282)
	)
	(segment
		(start 161.72 58.02)
		(end 162.2 58.5)
		(width 0.1)
		(layer "F.Cu")
		(net 282)
	)
	(segment
		(start 203.6 133.22)
		(end 203.7 133.12)
		(width 0.2)
		(layer "F.Cu")
		(net 282)
	)
	(segment
		(start 207.353 131.488)
		(end 207.353 132.947)
		(width 0.2)
		(layer "F.Cu")
		(net 282)
	)
	(segment
		(start 191.5 104.2)
		(end 191.5 102)
		(width 0.1)
		(layer "F.Cu")
		(net 282)
	)
	(segment
		(start 212.8 120.58)
		(end 212.8 121.2)
		(width 0.2)
		(layer "F.Cu")
		(net 282)
	)
	(segment
		(start 207.35 118.3)
		(end 207.35 119)
		(width 0.2)
		(layer "F.Cu")
		(net 282)
	)
	(segment
		(start 199.565 122.5)
		(end 198.5 122.5)
		(width 0.2)
		(layer "F.Cu")
		(net 282)
	)
	(segment
		(start 162.2 58.5)
		(end 162.75 58.5)
		(width 0.1)
		(layer "F.Cu")
		(net 282)
	)
	(segment
		(start 211.142 127.3)
		(end 213 127.3)
		(width 0.2)
		(layer "F.Cu")
		(net 282)
	)
	(segment
		(start 204.954 118.404)
		(end 204.954 119.911)
		(width 0.2)
		(layer "F.Cu")
		(net 282)
	)
	(segment
		(start 204.95 118.38)
		(end 204.965 118.365)
		(width 0.2)
		(layer "F.Cu")
		(net 282)
	)
	(segment
		(start 207.34 118.29)
		(end 207.34 118.28)
		(width 0.2)
		(layer "F.Cu")
		(net 282)
	)
	(segment
		(start 201 132.5)
		(end 200.7 132.5)
		(width 0.2)
		(layer "F.Cu")
		(net 282)
	)
	(segment
		(start 207.35 118.3)
		(end 207.34 118.29)
		(width 0.2)
		(layer "F.Cu")
		(net 282)
	)
	(via
		(at 204.95 118.4)
		(size 0.45)
		(drill 0.1)
		(layers "F.Cu" "B.Cu")
		(net 282)
	)
	(via
		(at 191.5 102)
		(size 0.45)
		(drill 0.1)
		(layers "F.Cu" "B.Cu")
		(net 282)
	)
	(via
		(at 198.5 122.5)
		(size 0.45)
		(drill 0.1)
		(layers "F.Cu" "B.Cu")
		(remove_unused_layers yes)
		(keep_end_layers yes)
		(zone_layer_connections "In4.Cu")
		(net 282)
	)
	(via
		(at 207.35 118.3)
		(size 0.45)
		(drill 0.1)
		(layers "F.Cu" "B.Cu")
		(net 282)
	)
	(via
		(at 203.7 133.22)
		(size 0.45)
		(drill 0.1)
		(layers "F.Cu" "B.Cu")
		(net 282)
	)
	(via
		(at 212.3 123.7)
		(size 0.45)
		(drill 0.1)
		(layers "F.Cu" "B.Cu")
		(net 282)
	)
	(via
		(at 189.725 84.85)
		(size 0.45)
		(drill 0.1)
		(layers "F.Cu" "B.Cu")
		(net 282)
	)
	(via
		(at 162.75 58.5)
		(size 0.45)
		(drill 0.1)
		(layers "F.Cu" "B.Cu")
		(net 282)
	)
	(via
		(at 213.1 127.2)
		(size 0.45)
		(drill 0.1)
		(layers "F.Cu" "B.Cu")
		(net 282)
	)
	(via
		(at 200.7 132.5)
		(size 0.45)
		(drill 0.1)
		(layers "F.Cu" "B.Cu")
		(net 282)
	)
	(via
		(at 212.8 121.2)
		(size 0.45)
		(drill 0.1)
		(layers "F.Cu" "B.Cu")
		(net 282)
	)
	(via
		(at 194.6 123.8)
		(size 0.45)
		(drill 0.1)
		(layers "F.Cu" "B.Cu")
		(remove_unused_layers yes)
		(keep_end_layers yes)
		(free yes)
		(zone_layer_connections "In4.Cu")
		(net 282)
	)
	(via
		(at 194.55 122.95)
		(size 0.45)
		(drill 0.1)
		(layers "F.Cu" "B.Cu")
		(remove_unused_layers yes)
		(keep_end_layers yes)
		(free yes)
		(zone_layer_connections "In4.Cu")
		(net 282)
	)
	(via
		(at 194.6 124.3)
		(size 0.45)
		(drill 0.1)
		(layers "F.Cu" "B.Cu")
		(remove_unused_layers yes)
		(keep_end_layers yes)
		(free yes)
		(zone_layer_connections "In4.Cu")
		(net 282)
	)
	(via
		(at 207.35 132.95)
		(size 0.45)
		(drill 0.1)
		(layers "F.Cu" "B.Cu")
		(net 282)
	)
	(via
		(at 194.55 122.45)
		(size 0.45)
		(drill 0.1)
		(layers "F.Cu" "B.Cu")
		(remove_unused_layers yes)
		(keep_end_layers yes)
		(free yes)
		(zone_layer_connections "In4.Cu")
		(net 282)
	)
	(via
		(at 191.5 104.2)
		(size 0.45)
		(drill 0.1)
		(layers "F.Cu" "B.Cu")
		(net 282)
	)
	(via
		(at 173.3 85.1)
		(size 0.45)
		(drill 0.1)
		(layers "F.Cu" "B.Cu")
		(net 282)
	)
	(segment
		(start 164.63 59.33)
		(end 167.5 62.2)
		(width 0.1)
		(layer "B.Cu")
		(net 282)
	)
	(segment
		(start 192.75 85.775)
		(end 193.125 86.15)
		(width 0.1)
		(layer "B.Cu")
		(net 282)
	)
	(segment
		(start 162.6 85.1)
		(end 173.3 85.1)
		(width 0.1)
		(layer "B.Cu")
		(net 282)
	)
	(segment
		(start 193.125 88.95)
		(end 190.45 91.625)
		(width 0.1)
		(layer "B.Cu")
		(net 282)
	)
	(segment
		(start 152.2 73.6)
		(end 152.2 75.7)
		(width 0.1)
		(layer "B.Cu")
		(net 282)
	)
	(segment
		(start 152.2 75.7)
		(end 158 81.5)
		(width 0.1)
		(layer "B.Cu")
		(net 282)
	)
	(segment
		(start 207.35 132.95)
		(end 207.35 132.31)
		(width 0.2)
		(layer "B.Cu")
		(net 282)
	)
	(segment
		(start 190.45 98.925)
		(end 191.625 100.1)
		(width 0.1)
		(layer "B.Cu")
		(net 282)
	)
	(segment
		(start 159 81.5)
		(end 162.6 85.1)
		(width 0.1)
		(layer "B.Cu")
		(net 282)
	)
	(segment
		(start 168.5 62.2)
		(end 168.7 62.4)
		(width 0.1)
		(layer "B.Cu")
		(net 282)
	)
	(segment
		(start 154.9 70.9)
		(end 152.2 73.6)
		(width 0.1)
		(layer "B.Cu")
		(net 282)
	)
	(segment
		(start 167.5 62.2)
		(end 168.5 62.2)
		(width 0.1)
		(layer "B.Cu")
		(net 282)
	)
	(segment
		(start 165.5 70.9)
		(end 154.9 70.9)
		(width 0.1)
		(layer "B.Cu")
		(net 282)
	)
	(segment
		(start 168.7 62.4)
		(end 168.7 67.7)
		(width 0.1)
		(layer "B.Cu")
		(net 282)
	)
	(segment
		(start 168.7 67.7)
		(end 165.5 70.9)
		(width 0.1)
		(layer "B.Cu")
		(net 282)
	)
	(segment
		(start 190.45 91.625)
		(end 190.45 98.925)
		(width 0.1)
		(layer "B.Cu")
		(net 282)
	)
	(segment
		(start 189.725 85.5)
		(end 190 85.775)
		(width 0.1)
		(layer "B.Cu")
		(net 282)
	)
	(segment
		(start 193.125 86.15)
		(end 193.125 88.95)
		(width 0.1)
		(layer "B.Cu")
		(net 282)
	)
	(segment
		(start 162.84 59.33)
		(end 164.63 59.33)
		(width 0.1)
		(layer "B.Cu")
		(net 282)
	)
	(segment
		(start 158 81.5)
		(end 159 81.5)
		(width 0.1)
		(layer "B.Cu")
		(net 282)
	)
	(segment
		(start 191.625 101.875)
		(end 191.5 102)
		(width 0.1)
		(layer "B.Cu")
		(net 282)
	)
	(segment
		(start 190 85.775)
		(end 192.75 85.775)
		(width 0.1)
		(layer "B.Cu")
		(net 282)
	)
	(segment
		(start 162.75 59.24)
		(end 162.84 59.33)
		(width 0.1)
		(layer "B.Cu")
		(net 282)
	)
	(segment
		(start 162.75 58.5)
		(end 162.75 59.24)
		(width 0.1)
		(layer "B.Cu")
		(net 282)
	)
	(segment
		(start 161.81 59.28)
		(end 162.79 59.28)
		(width 0.1)
		(layer "B.Cu")
		(net 282)
	)
	(segment
		(start 189.725 84.85)
		(end 189.725 85.5)
		(width 0.1)
		(layer "B.Cu")
		(net 282)
	)
	(segment
		(start 191.625 100.1)
		(end 191.625 101.875)
		(width 0.1)
		(layer "B.Cu")
		(net 282)
	)
	(segment
		(start 162.79 59.28)
		(end 162.84 59.33)
		(width 0.1)
		(layer "B.Cu")
		(net 282)
	)
	(segment
		(start 194.55 107.25)
		(end 191.5 104.2)
		(width 0.1)
		(layer "In5.Cu")
		(net 282)
	)
	(segment
		(start 194.55 122.45)
		(end 194.55 107.25)
		(width 0.1)
		(layer "In5.Cu")
		(net 282)
	)
	(segment
		(start 189.475 85.1)
		(end 189.725 84.85)
		(width 0.1)
		(layer "In7.Cu")
		(net 282)
	)
	(segment
		(start 173.3 85.1)
		(end 189.475 85.1)
		(width 0.1)
		(layer "In7.Cu")
		(net 282)
	)
	(segment
		(start 208.82337 115.815)
		(end 207.915 116.72337)
		(width 0.19)
		(layer "F.Cu")
		(net 283)
	)
	(segment
		(start 218.0025 118.2175)
		(end 213.77913 118.2175)
		(width 0.19)
		(layer "F.Cu")
		(net 283)
	)
	(segment
		(start 207.7685 118.6815)
		(end 207.7685 119.137099)
		(width 0.19)
		(layer "F.Cu")
		(net 283)
	)
	(segment
		(start 218.32 117.9)
		(end 218.0025 118.2175)
		(width 0.19)
		(layer "F.Cu")
		(net 283)
	)
	(segment
		(start 207.753 119.152599)
		(end 207.753 119.911)
		(width 0.19)
		(layer "F.Cu")
		(net 283)
	)
	(segment
		(start 207.7685 119.137099)
		(end 207.753 119.152599)
		(width 0.19)
		(layer "F.Cu")
		(net 283)
	)
	(segment
		(start 207.915 118.535)
		(end 207.7685 118.6815)
		(width 0.19)
		(layer "F.Cu")
		(net 283)
	)
	(segment
		(start 213.77913 118.2175)
		(end 211.37663 115.815)
		(width 0.19)
		(layer "F.Cu")
		(net 283)
	)
	(segment
		(start 207.915 116.72337)
		(end 207.915 118.535)
		(width 0.19)
		(layer "F.Cu")
		(net 283)
	)
	(segment
		(start 211.37663 115.815)
		(end 208.82337 115.815)
		(width 0.19)
		(layer "F.Cu")
		(net 283)
	)
	(segment
		(start 205.35 119.908)
		(end 205.353 119.911)
		(width 0.19)
		(layer "F.Cu")
		(net 285)
	)
	(segment
		(start 218.295 111.7)
		(end 217.98 112.015)
		(width 0.19)
		(layer "F.Cu")
		(net 285)
	)
	(segment
		(start 205.565 117.02663)
		(end 205.565 118.65)
		(width 0.19)
		(layer "F.Cu")
		(net 285)
	)
	(segment
		(start 207.82337 112.015)
		(end 205.165 114.67337)
		(width 0.19)
		(layer "F.Cu")
		(net 285)
	)
	(segment
		(start 205.565 118.65)
		(end 205.55 118.65)
		(width 0.19)
		(layer "F.Cu")
		(net 285)
	)
	(segment
		(start 217.98 112.015)
		(end 207.82337 112.015)
		(width 0.19)
		(layer "F.Cu")
		(net 285)
	)
	(segment
		(start 205.55 118.65)
		(end 205.35 118.85)
		(width 0.19)
		(layer "F.Cu")
		(net 285)
	)
	(segment
		(start 205.165 114.67337)
		(end 205.165 116.62663)
		(width 0.19)
		(layer "F.Cu")
		(net 285)
	)
	(segment
		(start 205.35 118.85)
		(end 205.35 119.908)
		(width 0.19)
		(layer "F.Cu")
		(net 285)
	)
	(segment
		(start 205.165 116.62663)
		(end 205.565 117.02663)
		(width 0.19)
		(layer "F.Cu")
		(net 285)
	)
	(segment
		(start 218.32 111.7)
		(end 218.295 111.7)
		(width 0.19)
		(layer "F.Cu")
		(net 285)
	)
	(segment
		(start 233.930532 99.860532)
		(end 233.77 99.7)
		(width 0.3)
		(layer "F.Cu")
		(net 287)
	)
	(segment
		(start 231.430532 103.3475)
		(end 231.430532 102.260532)
		(width 0.3)
		(layer "F.Cu")
		(net 287)
	)
	(segment
		(start 231.430532 102.139468)
		(end 231.37 102.2)
		(width 0.3)
		(layer "F.Cu")
		(net 287)
	)
	(segment
		(start 231.430532 103.3475)
		(end 231.430532 104.439468)
		(width 0.3)
		(layer "F.Cu")
		(net 287)
	)
	(segment
		(start 233.930532 102.260532)
		(end 233.87 102.2)
		(width 0.3)
		(layer "F.Cu")
		(net 287)
	)
	(segment
		(start 232.060532 108.71)
		(end 232.060532 108.714468)
		(width 0.2)
		(layer "F.Cu")
		(net 287)
	)
	(segment
		(start 231.430532 101.0725)
		(end 231.430532 102.139468)
		(width 0.3)
		(layer "F.Cu")
		(net 287)
	)
	(segment
		(start 231.430532 99.860532)
		(end 231.42 99.85)
		(width 0.3)
		(layer "F.Cu")
		(net 287)
	)
	(segment
		(start 231.430532 104.439468)
		(end 231.37 104.5)
		(width 0.3)
		(layer "F.Cu")
		(net 287)
	)
	(segment
		(start 233.930532 104.389468)
		(end 233.82 104.5)
		(width 0.3)
		(layer "F.Cu")
		(net 287)
	)
	(segment
		(start 233.930532 102.139468)
		(end 233.87 102.2)
		(width 0.3)
		(layer "F.Cu")
		(net 287)
	)
	(segment
		(start 231.430532 101.0725)
		(end 231.430532 99.860532)
		(width 0.3)
		(layer "F.Cu")
		(net 287)
	)
	(segment
		(start 231.430532 102.260532)
		(end 231.37 102.2)
		(width 0.3)
		(layer "F.Cu")
		(net 287)
	)
	(segment
		(start 233.930532 101.0725)
		(end 233.930532 102.139468)
		(width 0.3)
		(layer "F.Cu")
		(net 287)
	)
	(segment
		(start 233.930532 103.3475)
		(end 233.930532 104.389468)
		(width 0.3)
		(layer "F.Cu")
		(net 287)
	)
	(segment
		(start 233.930532 101.0725)
		(end 233.930532 99.860532)
		(width 0.3)
		(layer "F.Cu")
		(net 287)
	)
	(segment
		(start 233.930532 103.3475)
		(end 233.930532 102.260532)
		(width 0.3)
		(layer "F.Cu")
		(net 287)
	)
	(segment
		(start 232.060532 108.714468)
		(end 231.1 109.675)
		(width 0.2)
		(layer "F.Cu")
		(net 287)
	)
	(via
		(at 233.77 99.7)
		(size 0.45)
		(drill 0.1)
		(layers "F.Cu" "B.Cu")
		(net 287)
	)
	(via
		(at 231.1 109.675)
		(size 0.45)
		(drill 0.1)
		(layers "F.Cu" "B.Cu")
		(net 287)
	)
	(via
		(at 233.87 102.2)
		(size 0.45)
		(drill 0.1)
		(layers "F.Cu" "B.Cu")
		(net 287)
	)
	(via
		(at 231.42 99.85)
		(size 0.45)
		(drill 0.1)
		(layers "F.Cu" "B.Cu")
		(net 287)
	)
	(via
		(at 231.37 102.2)
		(size 0.45)
		(drill 0.1)
		(layers "F.Cu" "B.Cu")
		(net 287)
	)
	(via
		(at 233.82 104.5)
		(size 0.45)
		(drill 0.1)
		(layers "F.Cu" "B.Cu")
		(net 287)
	)
	(via
		(at 231.37 104.5)
		(size 0.45)
		(drill 0.1)
		(layers "F.Cu" "B.Cu")
		(net 287)
	)
	(segment
		(start 230.55 103.6)
		(end 231.27 103.6)
		(width 0.3)
		(layer "B.Cu")
		(net 287)
	)
	(segment
		(start 229.1 110.3)
		(end 229.1 109.399999)
		(width 0.1)
		(layer "B.Cu")
		(net 287)
	)
	(segment
		(start 224.4 108.3)
		(end 223.7 109)
		(width 0.1)
		(layer "B.Cu")
		(net 287)
	)
	(segment
		(start 223.7 109)
		(end 223.7 109.85)
		(width 0.1)
		(layer "B.Cu")
		(net 287)
	)
	(segment
		(start 230.97 100.9)
		(end 231.42 100.45)
		(width 0.2)
		(layer "B.Cu")
		(net 287)
	)
	(segment
		(start 230.771 100.9)
		(end 230.97 100.9)
		(width 0.2)
		(layer "B.Cu")
		(net 287)
	)
	(segment
		(start 228.7 110.7)
		(end 229.1 110.3)
		(width 0.1)
		(layer "B.Cu")
		(net 287)
	)
	(segment
		(start 217.8 102)
		(end 222 106.2)
		(width 0.1)
		(layer "B.Cu")
		(net 287)
	)
	(segment
		(start 222 106.2)
		(end 223.8 106.2)
		(width 0.1)
		(layer "B.Cu")
		(net 287)
	)
	(segment
		(start 231.37 99.9)
		(end 231.42 99.85)
		(width 0.3)
		(layer "B.Cu")
		(net 287)
	)
	(segment
		(start 223.7 110.4)
		(end 224 110.7)
		(width 0.1)
		(layer "B.Cu")
		(net 287)
	)
	(segment
		(start 231.27 103.6)
		(end 231.37 103.7)
		(width 0.3)
		(layer "B.Cu")
		(net 287)
	)
	(segment
		(start 224.4 106.8)
		(end 224.4 108.3)
		(width 0.1)
		(layer "B.Cu")
		(net 287)
	)
	(segment
		(start 215.08 102)
		(end 217.8 102)
		(width 0.1)
		(layer "B.Cu")
		(net 287)
	)
	(segment
		(start 223.8 106.2)
		(end 224.4 106.8)
		(width 0.1)
		(layer "B.Cu")
		(net 287)
	)
	(segment
		(start 231.37 103.7)
		(end 231.37 104.5)
		(width 0.3)
		(layer "B.Cu")
		(net 287)
	)
	(segment
		(start 231.42 100.45)
		(end 231.42 99.85)
		(width 0.2)
		(layer "B.Cu")
		(net 287)
	)
	(segment
		(start 224 110.7)
		(end 228.7 110.7)
		(width 0.1)
		(layer "B.Cu")
		(net 287)
	)
	(segment
		(start 223.7 109.85)
		(end 223.7 110.4)
		(width 0.1)
		(layer "B.Cu")
		(net 287)
	)
	(segment
		(start 83.3 140.75)
		(end 82.75 140.75)
		(width 1)
		(layer "B.Cu")
		(net 289)
	)
	(segment
		(start 82.75 140.75)
		(end 81.5 139.5)
		(width 1)
		(layer "B.Cu")
		(net 289)
	)
	(segment
		(start 127.8 112.1)
		(end 129.38 112.1)
		(width 0.1)
		(layer "F.Cu")
		(net 292)
	)
	(segment
		(start 129.38 112.1)
		(end 129.68 112.4)
		(width 0.1)
		(layer "F.Cu")
		(net 292)
	)
	(segment
		(start 129.68 112.4)
		(end 132.6 112.4)
		(width 0.1)
		(layer "F.Cu")
		(net 292)
	)
	(segment
		(start 132.6 112.4)
		(end 133 112.8)
		(width 0.1)
		(layer "F.Cu")
		(net 292)
	)
	(via
		(at 137.730532 79.65)
		(size 0.45)
		(drill 0.1)
		(layers "F.Cu" "B.Cu")
		(net 292)
	)
	(via
		(at 133 112.8)
		(size 0.45)
		(drill 0.1)
		(layers "F.Cu" "B.Cu")
		(net 292)
	)
	(via
		(at 75.775532 100.535)
		(size 0.45)
		(drill 0.1)
		(layers "F.Cu" "B.Cu")
		(net 292)
	)
	(via
		(at 127.8 112.1)
		(size 0.45)
		(drill 0.1)
		(layers "F.Cu" "B.Cu")
		(free yes)
		(net 292)
	)
	(segment
		(start 133 103.9)
		(end 130.9 101.8)
		(width 0.1)
		(layer "In5.Cu")
		(net 292)
	)
	(segment
		(start 111.636857 110.568227)
		(end 110.268629 109.199999)
		(width 0.1)
		(layer "In5.Cu")
		(net 292)
	)
	(segment
		(start 105.15 110.849999)
		(end 105.15 115.58137)
		(width 0.1)
		(layer "In5.Cu")
		(net 292)
	)
	(segment
		(start 100.531371 120.199999)
		(end 88.100001 120.199999)
		(width 0.1)
		(layer "In5.Cu")
		(net 292)
	)
	(segment
		(start 76.3 108.4)
		(end 76.3 102.9)
		(width 0.1)
		(layer "In5.Cu")
		(net 292)
	)
	(segment
		(start 86.9 121.4)
		(end 79.5 121.4)
		(width 0.1)
		(layer "In5.Cu")
		(net 292)
	)
	(segment
		(start 138.4 80.319468)
		(end 137.730532 79.65)
		(width 0.1)
		(layer "In5.Cu")
		(net 292)
	)
	(segment
		(start 127.1 112.1)
		(end 126.6 111.6)
		(width 0.1)
		(layer "In5.Cu")
		(net 292)
	)
	(segment
		(start 79.5 121.4)
		(end 77.85 119.75)
		(width 0.1)
		(layer "In5.Cu")
		(net 292)
	)
	(segment
		(start 75.25 101.060532)
		(end 75.775532 100.535)
		(width 0.1)
		(layer "In5.Cu")
		(net 292)
	)
	(segment
		(start 131.6 96.2)
		(end 131.6 93.2)
		(width 0.1)
		(layer "In5.Cu")
		(net 292)
	)
	(segment
		(start 77.85 109.95)
		(end 76.3 108.4)
		(width 0.1)
		(layer "In5.Cu")
		(net 292)
	)
	(segment
		(start 131.6 93.2)
		(end 137.555532 87.244468)
		(width 0.1)
		(layer "In5.Cu")
		(net 292)
	)
	(segment
		(start 126.6 111.6)
		(end 113.4 111.6)
		(width 0.1)
		(layer "In5.Cu")
		(net 292)
	)
	(segment
		(start 137.555532 87.244468)
		(end 137.555532 83.555532)
		(width 0.1)
		(layer "In5.Cu")
		(net 292)
	)
	(segment
		(start 138.4 81.4)
		(end 138.4 80.319468)
		(width 0.1)
		(layer "In5.Cu")
		(net 292)
	)
	(segment
		(start 127.8 112.1)
		(end 127.1 112.1)
		(width 0.1)
		(layer "In5.Cu")
		(net 292)
	)
	(segment
		(start 133 112.8)
		(end 133 103.9)
		(width 0.1)
		(layer "In5.Cu")
		(net 292)
	)
	(segment
		(start 110.268629 109.199999)
		(end 106.8 109.199999)
		(width 0.1)
		(layer "In5.Cu")
		(net 292)
	)
	(segment
		(start 106.8 109.199999)
		(end 105.15 110.849999)
		(width 0.1)
		(layer "In5.Cu")
		(net 292)
	)
	(segment
		(start 130.9 96.9)
		(end 131.6 96.2)
		(width 0.1)
		(layer "In5.Cu")
		(net 292)
	)
	(segment
		(start 75.25 101.85)
		(end 75.25 101.060532)
		(width 0.1)
		(layer "In5.Cu")
		(net 292)
	)
	(segment
		(start 112.368227 110.568227)
		(end 111.636857 110.568227)
		(width 0.1)
		(layer "In5.Cu")
		(net 292)
	)
	(segment
		(start 88.100001 120.199999)
		(end 86.9 121.4)
		(width 0.1)
		(layer "In5.Cu")
		(net 292)
	)
	(segment
		(start 137.2 83.2)
		(end 137.2 82.6)
		(width 0.1)
		(layer "In5.Cu")
		(net 292)
	)
	(segment
		(start 77.85 119.75)
		(end 77.85 109.95)
		(width 0.1)
		(layer "In5.Cu")
		(net 292)
	)
	(segment
		(start 130.9 101.8)
		(end 130.9 96.9)
		(width 0.1)
		(layer "In5.Cu")
		(net 292)
	)
	(segment
		(start 113.4 111.6)
		(end 112.368227 110.568227)
		(width 0.1)
		(layer "In5.Cu")
		(net 292)
	)
	(segment
		(start 137.2 82.6)
		(end 138.4 81.4)
		(width 0.1)
		(layer "In5.Cu")
		(net 292)
	)
	(segment
		(start 137.555532 83.555532)
		(end 137.2 83.2)
		(width 0.1)
		(layer "In5.Cu")
		(net 292)
	)
	(segment
		(start 105.15 115.58137)
		(end 100.531371 120.199999)
		(width 0.1)
		(layer "In5.Cu")
		(net 292)
	)
	(segment
		(start 76.3 102.9)
		(end 75.25 101.85)
		(width 0.1)
		(layer "In5.Cu")
		(net 292)
	)
	(segment
		(start 196.6 78.28)
		(end 195.88 79)
		(width 0.2)
		(layer "F.Cu")
		(net 293)
	)
	(segment
		(start 197.249 78.28)
		(end 196.6 78.28)
		(width 0.2)
		(layer "F.Cu")
		(net 293)
	)
	(segment
		(start 195.88 79)
		(end 195.68 79)
		(width 0.2)
		(layer "F.Cu")
		(net 293)
	)
	(segment
		(start 204.482 77.882)
		(end 203.95 77.882)
		(width 0.2)
		(layer "F.Cu")
		(net 294)
	)
	(segment
		(start 204.7 78.1)
		(end 205.32 78.1)
		(width 0.2)
		(layer "F.Cu")
		(net 294)
	)
	(segment
		(start 205.32 78.1)
		(end 205.52 77.9)
		(width 0.2)
		(layer "F.Cu")
		(net 294)
	)
	(segment
		(start 204.7 78.1)
		(end 204.482 77.882)
		(width 0.2)
		(layer "F.Cu")
		(net 294)
	)
	(via
		(at 204.7 78.1)
		(size 0.45)
		(drill 0.1)
		(layers "F.Cu" "B.Cu")
		(net 294)
	)
	(segment
		(start 208.9 79.92)
		(end 208.28 79.3)
		(width 0.2)
		(layer "B.Cu")
		(net 294)
	)
	(segment
		(start 208.28 78.48)
		(end 207.85 78.05)
		(width 0.2)
		(layer "B.Cu")
		(net 294)
	)
	(segment
		(start 208.9 81.25)
		(end 208.9 79.92)
		(width 0.2)
		(layer "B.Cu")
		(net 294)
	)
	(segment
		(start 206.65 78.4)
		(end 205 78.4)
		(width 0.2)
		(layer "B.Cu")
		(net 294)
	)
	(segment
		(start 208.28 79.3)
		(end 208.28 78.48)
		(width 0.2)
		(layer "B.Cu")
		(net 294)
	)
	(segment
		(start 205 78.4)
		(end 204.7 78.1)
		(width 0.2)
		(layer "B.Cu")
		(net 294)
	)
	(segment
		(start 208.85 83.15)
		(end 208.9 83.2)
		(width 0.2)
		(layer "B.Cu")
		(net 294)
	)
	(segment
		(start 208.85 81.3)
		(end 208.85 83.15)
		(width 0.2)
		(layer "B.Cu")
		(net 294)
	)
	(segment
		(start 208.28 81.3)
		(end 208.85 81.3)
		(width 0.2)
		(layer "B.Cu")
		(net 294)
	)
	(segment
		(start 207.85 78.05)
		(end 207 78.05)
		(width 0.2)
		(layer "B.Cu")
		(net 294)
	)
	(segment
		(start 207 78.05)
		(end 206.65 78.4)
		(width 0.2)
		(layer "B.Cu")
		(net 294)
	)
	(segment
		(start 208.85 81.3)
		(end 208.9 81.25)
		(width 0.2)
		(layer "B.Cu")
		(net 294)
	)
	(segment
		(start 67 110.4)
		(end 67 114.4)
		(width 0.2)
		(layer "F.Cu")
		(net 295)
	)
	(segment
		(start 76.75 129.25)
		(end 76.75 130)
		(width 0.2)
		(layer "F.Cu")
		(net 295)
	)
	(segment
		(start 77.2 129.2)
		(end 76.8 129.2)
		(width 0.2)
		(layer "F.Cu")
		(net 295)
	)
	(segment
		(start 77.5 126.7)
		(end 77.5 128.9)
		(width 0.2)
		(layer "F.Cu")
		(net 295)
	)
	(segment
		(start 67 114.4)
		(end 71.4 118.8)
		(width 0.2)
		(layer "F.Cu")
		(net 295)
	)
	(segment
		(start 71.4 121.7)
		(end 74.8 125.1)
		(width 0.2)
		(layer "F.Cu")
		(net 295)
	)
	(segment
		(start 76.8 129.2)
		(end 76.75 129.25)
		(width 0.2)
		(layer "F.Cu")
		(net 295)
	)
	(segment
		(start 70.4 79.7)
		(end 70.1 80)
		(width 0.2)
		(layer "F.Cu")
		(net 295)
	)
	(segment
		(start 74.8 125.1)
		(end 75.9 125.1)
		(width 0.2)
		(layer "F.Cu")
		(net 295)
	)
	(segment
		(start 71.3 98.6)
		(end 71.3 94.4)
		(width 0.2)
		(layer "F.Cu")
		(net 295)
	)
	(segment
		(start 70.1 80)
		(end 70.1 93.2)
		(width 0.2)
		(layer "F.Cu")
		(net 295)
	)
	(segment
		(start 77.5 128.9)
		(end 77.2 129.2)
		(width 0.2)
		(layer "F.Cu")
		(net 295)
	)
	(segment
		(start 70.1 93.2)
		(end 71.3 94.4)
		(width 0.2)
		(layer "F.Cu")
		(net 295)
	)
	(segment
		(start 68.4 101.5)
		(end 71.3 98.6)
		(width 0.2)
		(layer "F.Cu")
		(net 295)
	)
	(segment
		(start 75.9 125.1)
		(end 77.5 126.7)
		(width 0.2)
		(layer "F.Cu")
		(net 295)
	)
	(segment
		(start 71.4 118.8)
		(end 71.4 121.7)
		(width 0.2)
		(layer "F.Cu")
		(net 295)
	)
	(segment
		(start 70.4 71.8)
		(end 70.4 79.7)
		(width 0.2)
		(layer "F.Cu")
		(net 295)
	)
	(segment
		(start 68.4 109)
		(end 67 110.4)
		(width 0.2)
		(layer "F.Cu")
		(net 295)
	)
	(segment
		(start 68.4 109)
		(end 68.4 101.5)
		(width 0.2)
		(layer "F.Cu")
		(net 295)
	)
	(via
		(at 70.4 71.8)
		(size 0.45)
		(drill 0.1)
		(layers "F.Cu" "B.Cu")
		(net 295)
	)
	(via
		(at 76.4 131.2)
		(size 0.45)
		(drill 0.1)
		(layers "F.Cu" "B.Cu")
		(free yes)
		(net 295)
	)
	(via
		(at 76.4 130.4)
		(size 0.45)
		(drill 0.1)
		(layers "F.Cu" "B.Cu")
		(free yes)
		(net 295)
	)
	(via
		(at 76 130)
		(size 0.45)
		(drill 0.1)
		(layers "F.Cu" "B.Cu")
		(free yes)
		(net 295)
	)
	(via
		(at 76.8 130.8)
		(size 0.45)
		(drill 0.1)
		(layers "F.Cu" "B.Cu")
		(free yes)
		(net 295)
	)
	(via
		(at 76.75 130)
		(size 0.45)
		(drill 0.1)
		(layers "F.Cu" "B.Cu")
		(free yes)
		(net 295)
	)
	(via
		(at 77.2 130.4)
		(size 0.45)
		(drill 0.1)
		(layers "F.Cu" "B.Cu")
		(free yes)
		(net 295)
	)
	(via
		(at 77.2 131.2)
		(size 0.45)
		(drill 0.1)
		(layers "F.Cu" "B.Cu")
		(free yes)
		(net 295)
	)
	(via
		(at 77.6 130.8)
		(size 0.45)
		(drill 0.1)
		(layers "F.Cu" "B.Cu")
		(free yes)
		(net 295)
	)
	(via
		(at 76 130.8)
		(size 0.45)
		(drill 0.1)
		(layers "F.Cu" "B.Cu")
		(free yes)
		(net 295)
	)
	(segment
		(start 70.4 71.1)
		(end 75 66.5)
		(width 0.2)
		(layer "B.Cu")
		(net 295)
	)
	(segment
		(start 75 66.5)
		(end 75.52 66.5)
		(width 0.2)
		(layer "B.Cu")
		(net 295)
	)
	(segment
		(start 70.4 71.8)
		(end 70.4 71.1)
		(width 0.2)
		(layer "B.Cu")
		(net 295)
	)
	(via
		(at 98.2 128.6)
		(size 0.45)
		(drill 0.1)
		(layers "F.Cu" "B.Cu")
		(free yes)
		(net 297)
	)
	(via
		(at 79.585532 128.475)
		(size 0.45)
		(drill 0.1)
		(layers "F.Cu" "B.Cu")
		(net 297)
	)
	(via
		(at 79.585532 123.395)
		(size 0.45)
		(drill 0.1)
		(layers "F.Cu" "B.Cu")
		(net 297)
	)
	(via
		(at 96.4 128)
		(size 0.45)
		(drill 0.1)
		(layers "F.Cu" "B.Cu")
		(free yes)
		(net 297)
	)
	(via
		(at 80.855532 127.205)
		(size 0.45)
		(drill 0.1)
		(layers "F.Cu" "B.Cu")
		(net 297)
	)
	(via
		(at 97 128)
		(size 0.45)
		(drill 0.1)
		(layers "F.Cu" "B.Cu")
		(free yes)
		(net 297)
	)
	(via
		(at 84.665532 128.475)
		(size 0.45)
		(drill 0.1)
		(layers "F.Cu" "B.Cu")
		(net 297)
	)
	(via
		(at 98.2 128)
		(size 0.45)
		(drill 0.1)
		(layers "F.Cu" "B.Cu")
		(free yes)
		(net 297)
	)
	(via
		(at 97 128.6)
		(size 0.45)
		(drill 0.1)
		(layers "F.Cu" "B.Cu")
		(free yes)
		(net 297)
	)
	(via
		(at 96.4 128.6)
		(size 0.45)
		(drill 0.1)
		(layers "F.Cu" "B.Cu")
		(free yes)
		(net 297)
	)
	(via
		(at 79.585532 125.935)
		(size 0.45)
		(drill 0.1)
		(layers "F.Cu" "B.Cu")
		(net 297)
	)
	(segment
		(start 106.430532 85.65)
		(end 106.695532 85.915)
		(width 0.19)
		(layer "F.Cu")
		(net 299)
	)
	(segment
		(start 214.554132 83.802)
		(end 214.554132 83.777)
		(width 0.19)
		(layer "F.Cu")
		(net 299)
	)
	(segment
		(start 214.854132 83.477)
		(end 214.854132 82.915)
		(width 0.19)
		(layer "F.Cu")
		(net 299)
	)
	(segment
		(start 106.695532 87.185)
		(end 106.580532 87.3)
		(width 0.19)
		(layer "F.Cu")
		(net 299)
	)
	(segment
		(start 106.695532 85.915)
		(end 106.695532 87.185)
		(width 0.19)
		(layer "F.Cu")
		(net 299)
	)
	(segment
		(start 214.554132 83.777)
		(end 214.854132 83.477)
		(width 0.19)
		(layer "F.Cu")
		(net 299)
	)
	(segment
		(start 214.854132 82.915)
		(end 214.739132 82.8)
		(width 0.19)
		(layer "F.Cu")
		(net 299)
	)
	(via
		(at 214.739132 82.8)
		(size 0.45)
		(drill 0.1)
		(layers "F.Cu" "B.Cu")
		(net 299)
	)
	(via
		(at 106.580532 87.3)
		(size 0.45)
		(drill 0.1)
		(layers "F.Cu" "B.Cu")
		(net 299)
	)
	(segment
		(start 196.943044 75.7625)
		(end 197.743044 74.9625)
		(width 0.15)
		(layer "In7.Cu")
		(net 299)
	)
	(segment
		(start 106.743032 87.1375)
		(end 106.743032 83.937488)
		(width 0.15)
		(layer "In7.Cu")
		(net 299)
	)
	(segment
		(start 148.556956 72.8625)
		(end 185.756956 72.8625)
		(width 0.15)
		(layer "In7.Cu")
		(net 299)
	)
	(segment
		(start 107.343044 76.9375)
		(end 106.543044 76.9375)
		(width 0.15)
		(layer "In7.Cu")
		(net 299)
	)
	(segment
		(start 106.343044 74.4625)
		(end 106.6625 74.143044)
		(width 0.15)
		(layer "In7.Cu")
		(net 299)
	)
	(segment
		(start 106.0625 83.256956)
		(end 106.0625 82.456956)
		(width 0.15)
		(layer "In7.Cu")
		(net 299)
	)
	(segment
		(start 203.156956 74.9625)
		(end 204.656956 76.4625)
		(width 0.15)
		(layer "In7.Cu")
		(net 299)
	)
	(segment
		(start 212.481956 83.9875)
		(end 214.443044 83.9875)
		(width 0.15)
		(layer "In7.Cu")
		(net 299)
	)
	(segment
		(start 106.6625 74.143044)
		(end 106.6625 73.743044)
		(width 0.15)
		(layer "In7.Cu")
		(net 299)
	)
	(segment
		(start 214.901632 83.528912)
		(end 214.901632 82.9625)
		(width 0.15)
		(layer "In7.Cu")
		(net 299)
	)
	(segment
		(start 188.656956 75.7625)
		(end 196.943044 75.7625)
		(width 0.15)
		(layer "In7.Cu")
		(net 299)
	)
	(segment
		(start 208.2375 77.943044)
		(end 208.2375 79.943044)
		(width 0.15)
		(layer "In7.Cu")
		(net 299)
	)
	(segment
		(start 107.143044 73.2625)
		(end 107.543044 73.2625)
		(width 0.15)
		(layer "In7.Cu")
		(net 299)
	)
	(segment
		(start 208.656956 80.3625)
		(end 209.756956 80.3625)
		(width 0.15)
		(layer "In7.Cu")
		(net 299)
	)
	(segment
		(start 185.756956 72.8625)
		(end 188.656956 75.7625)
		(width 0.15)
		(layer "In7.Cu")
		(net 299)
	)
	(segment
		(start 108.0625 78.543044)
		(end 108.0625 77.656956)
		(width 0.15)
		(layer "In7.Cu")
		(net 299)
	)
	(segment
		(start 197.743044 74.9625)
		(end 203.156956 74.9625)
		(width 0.15)
		(layer "In7.Cu")
		(net 299)
	)
	(segment
		(start 107.8625 72.393044)
		(end 108.7125 71.543044)
		(width 0.15)
		(layer "In7.Cu")
		(net 299)
	)
	(segment
		(start 115.053085 60.952459)
		(end 137.791369 60.952459)
		(width 0.15)
		(layer "In7.Cu")
		(net 299)
	)
	(segment
		(start 106.543044 76.9375)
		(end 105.5625 75.956956)
		(width 0.15)
		(layer "In7.Cu")
		(net 299)
	)
	(segment
		(start 105.5625 81.956956)
		(end 105.5625 80.443044)
		(width 0.15)
		(layer "In7.Cu")
		(net 299)
	)
	(segment
		(start 106.743044 79.2625)
		(end 107.343044 79.2625)
		(width 0.15)
		(layer "In7.Cu")
		(net 299)
	)
	(segment
		(start 107.8625 72.943044)
		(end 107.8625 72.393044)
		(width 0.15)
		(layer "In7.Cu")
		(net 299)
	)
	(segment
		(start 144.530637 67.691727)
		(end 144.530637 68.836181)
		(width 0.15)
		(layer "In7.Cu")
		(net 299)
	)
	(segment
		(start 209.756956 80.3625)
		(end 211.1375 81.743044)
		(width 0.15)
		(layer "In7.Cu")
		(net 299)
	)
	(segment
		(start 105.5625 75.956956)
		(end 105.5625 74.843044)
		(width 0.15)
		(layer "In7.Cu")
		(net 299)
	)
	(segment
		(start 106.0625 82.456956)
		(end 105.5625 81.956956)
		(width 0.15)
		(layer "In7.Cu")
		(net 299)
	)
	(segment
		(start 105.5625 74.843044)
		(end 105.943044 74.4625)
		(width 0.15)
		(layer "In7.Cu")
		(net 299)
	)
	(segment
		(start 105.5625 80.443044)
		(end 106.743044 79.2625)
		(width 0.15)
		(layer "In7.Cu")
		(net 299)
	)
	(segment
		(start 144.530637 68.836181)
		(end 148.556956 72.8625)
		(width 0.15)
		(layer "In7.Cu")
		(net 299)
	)
	(segment
		(start 211.1375 81.743044)
		(end 211.1375 82.643044)
		(width 0.15)
		(layer "In7.Cu")
		(net 299)
	)
	(segment
		(start 108.0625 77.656956)
		(end 107.343044 76.9375)
		(width 0.15)
		(layer "In7.Cu")
		(net 299)
	)
	(segment
		(start 214.901632 82.9625)
		(end 214.739132 82.8)
		(width 0.15)
		(layer "In7.Cu")
		(net 299)
	)
	(segment
		(start 108.7125 67.293044)
		(end 115.053085 60.952459)
		(width 0.15)
		(layer "In7.Cu")
		(net 299)
	)
	(segment
		(start 106.6625 73.743044)
		(end 107.143044 73.2625)
		(width 0.15)
		(layer "In7.Cu")
		(net 299)
	)
	(segment
		(start 106.580532 87.3)
		(end 106.743032 87.1375)
		(width 0.15)
		(layer "In7.Cu")
		(net 299)
	)
	(segment
		(start 211.1375 82.643044)
		(end 212.481956 83.9875)
		(width 0.15)
		(layer "In7.Cu")
		(net 299)
	)
	(segment
		(start 107.543044 73.2625)
		(end 107.8625 72.943044)
		(width 0.15)
		(layer "In7.Cu")
		(net 299)
	)
	(segment
		(start 105.943044 74.4625)
		(end 106.343044 74.4625)
		(width 0.15)
		(layer "In7.Cu")
		(net 299)
	)
	(segment
		(start 214.443044 83.9875)
		(end 214.901632 83.528912)
		(width 0.15)
		(layer "In7.Cu")
		(net 299)
	)
	(segment
		(start 204.656956 76.4625)
		(end 206.756956 76.4625)
		(width 0.15)
		(layer "In7.Cu")
		(net 299)
	)
	(segment
		(start 208.2375 79.943044)
		(end 208.656956 80.3625)
		(width 0.15)
		(layer "In7.Cu")
		(net 299)
	)
	(segment
		(start 107.343044 79.2625)
		(end 108.0625 78.543044)
		(width 0.15)
		(layer "In7.Cu")
		(net 299)
	)
	(segment
		(start 206.756956 76.4625)
		(end 208.2375 77.943044)
		(width 0.15)
		(layer "In7.Cu")
		(net 299)
	)
	(segment
		(start 106.743032 83.937488)
		(end 106.0625 83.256956)
		(width 0.15)
		(layer "In7.Cu")
		(net 299)
	)
	(segment
		(start 137.791369 60.952459)
		(end 144.530637 67.691727)
		(width 0.15)
		(layer "In7.Cu")
		(net 299)
	)
	(segment
		(start 108.7125 71.543044)
		(end 108.7125 67.293044)
		(width 0.15)
		(layer "In7.Cu")
		(net 299)
	)
	(segment
		(start 214.554132 84.787)
		(end 214.554132 84.762)
		(width 0.19)
		(layer "F.Cu")
		(net 302)
	)
	(segment
		(start 214.854132 85.384238)
		(end 214.854132 85.087)
		(width 0.19)
		(layer "F.Cu")
		(net 302)
	)
	(segment
		(start 214.279632 86.406855)
		(end 214.279632 85.958738)
		(width 0.19)
		(layer "F.Cu")
		(net 302)
	)
	(segment
		(start 214.263632 86.872856)
		(end 214.263632 86.422855)
		(width 0.19)
		(layer "F.Cu")
		(net 302)
	)
	(segment
		(start 214.854132 85.087)
		(end 214.554132 84.787)
		(width 0.19)
		(layer "F.Cu")
		(net 302)
	)
	(segment
		(start 214.279632 85.958738)
		(end 214.854132 85.384238)
		(width 0.19)
		(layer "F.Cu")
		(net 302)
	)
	(segment
		(start 214.263632 86.422855)
		(end 214.279632 86.406855)
		(width 0.19)
		(layer "F.Cu")
		(net 302)
	)
	(segment
		(start 81.2 119.1)
		(end 79.5 119.1)
		(width 0.1)
		(layer "F.Cu")
		(net 305)
	)
	(segment
		(start 79 116.2)
		(end 78 115.2)
		(width 0.1)
		(layer "F.Cu")
		(net 305)
	)
	(segment
		(start 87.4 135.6)
		(end 87.4 132.9)
		(width 0.1)
		(layer "F.Cu")
		(net 305)
	)
	(segment
		(start 81.4 129.06863)
		(end 81.4 119.3)
		(width 0.1)
		(layer "F.Cu")
		(net 305)
	)
	(segment
		(start 79.5 119.1)
		(end 79 118.6)
		(width 0.1)
		(layer "F.Cu")
		(net 305)
	)
	(segment
		(start 75.200532 115.2)
		(end 74.505532 114.505)
		(width 0.1)
		(layer "F.Cu")
		(net 305)
	)
	(segment
		(start 78 115.2)
		(end 75.200532 115.2)
		(width 0.1)
		(layer "F.Cu")
		(net 305)
	)
	(segment
		(start 84.33137 132)
		(end 81.4 129.06863)
		(width 0.1)
		(layer "F.Cu")
		(net 305)
	)
	(segment
		(start 81.4 119.3)
		(end 81.2 119.1)
		(width 0.1)
		(layer "F.Cu")
		(net 305)
	)
	(segment
		(start 86.5 132)
		(end 84.33137 132)
		(width 0.1)
		(layer "F.Cu")
		(net 305)
	)
	(segment
		(start 87.4 132.9)
		(end 86.5 132)
		(width 0.1)
		(layer "F.Cu")
		(net 305)
	)
	(segment
		(start 79 118.6)
		(end 79 116.2)
		(width 0.1)
		(layer "F.Cu")
		(net 305)
	)
	(via
		(at 74.505532 114.505)
		(size 0.45)
		(drill 0.1)
		(layers "F.Cu" "B.Cu")
		(net 305)
	)
	(via
		(at 145 93.4)
		(size 0.45)
		(drill 0.1)
		(layers "F.Cu" "B.Cu")
		(net 305)
	)
	(via
		(at 87.4 135.6)
		(size 0.45)
		(drill 0.1)
		(layers "F.Cu" "B.Cu")
		(net 305)
	)
	(via
		(at 137.930532 78.15)
		(size 0.45)
		(drill 0.1)
		(layers "F.Cu" "B.Cu")
		(net 305)
	)
	(segment
		(start 140.9 78.9)
		(end 138.680532 78.9)
		(width 0.1)
		(layer "B.Cu")
		(net 305)
	)
	(segment
		(start 138.680532 78.9)
		(end 137.930532 78.15)
		(width 0.1)
		(layer "B.Cu")
		(net 305)
	)
	(segment
		(start 141.1 81.45)
		(end 141.1 79.1)
		(width 0.1)
		(layer "B.Cu")
		(net 305)
	)
	(segment
		(start 143.15 93.9)
		(end 142.65 93.4)
		(width 0.1)
		(layer "B.Cu")
		(net 305)
	)
	(segment
		(start 142.65 87.2)
		(end 141.275 85.825)
		(width 0.1)
		(layer "B.Cu")
		(net 305)
	)
	(segment
		(start 141.275 85.825)
		(end 141.275 81.625)
		(width 0.1)
		(layer "B.Cu")
		(net 305)
	)
	(segment
		(start 144.5 93.9)
		(end 143.15 93.9)
		(width 0.1)
		(layer "B.Cu")
		(net 305)
	)
	(segment
		(start 142.65 93.4)
		(end 142.65 87.2)
		(width 0.1)
		(layer "B.Cu")
		(net 305)
	)
	(segment
		(start 145 93.4)
		(end 144.5 93.9)
		(width 0.1)
		(layer "B.Cu")
		(net 305)
	)
	(segment
		(start 141.275 81.625)
		(end 141.1 81.45)
		(width 0.1)
		(layer "B.Cu")
		(net 305)
	)
	(segment
		(start 141.1 79.1)
		(end 140.9 78.9)
		(width 0.1)
		(layer "B.Cu")
		(net 305)
	)
	(segment
		(start 144.999997 102.7)
		(end 144.4 103.299997)
		(width 0.1)
		(layer "In5.Cu")
		(net 305)
	)
	(segment
		(start 87.85 135.6)
		(end 87.4 135.6)
		(width 0.1)
		(layer "In5.Cu")
		(net 305)
	)
	(segment
		(start 145 93.4)
		(end 144.999997 93.400003)
		(width 0.1)
		(layer "In5.Cu")
		(net 305)
	)
	(segment
		(start 144.999997 107.799997)
		(end 144.999997 117.462741)
		(width 0.1)
		(layer "In5.Cu")
		(net 305)
	)
	(segment
		(start 144.4 103.299997)
		(end 144.4 107.2)
		(width 0.1)
		(layer "In5.Cu")
		(net 305)
	)
	(segment
		(start 92.85 130.6)
		(end 87.85 135.6)
		(width 0.1)
		(layer "In5.Cu")
		(net 305)
	)
	(segment
		(start 144.999997 117.462741)
		(end 138.362739 124.099999)
		(width 0.1)
		(layer "In5.Cu")
		(net 305)
	)
	(segment
		(start 112.762743 124.099999)
		(end 106.262742 130.6)
		(width 0.1)
		(layer "In5.Cu")
		(net 305)
	)
	(segment
		(start 106.262742 130.6)
		(end 92.85 130.6)
		(width 0.1)
		(layer "In5.Cu")
		(net 305)
	)
	(segment
		(start 144.4 107.2)
		(end 144.999997 107.799997)
		(width 0.1)
		(layer "In5.Cu")
		(net 305)
	)
	(segment
		(start 144.999997 93.400003)
		(end 144.999997 102.7)
		(width 0.1)
		(layer "In5.Cu")
		(net 305)
	)
	(segment
		(start 138.362739 124.099999)
		(end 112.762743 124.099999)
		(width 0.1)
		(layer "In5.Cu")
		(net 305)
	)
	(segment
		(start 212.544132 84.797)
		(end 212.859132 85.112)
		(width 0.19)
		(layer "F.Cu")
		(net 310)
	)
	(segment
		(start 213.065632 86.872856)
		(end 213.065632 86.422855)
		(width 0.19)
		(layer "F.Cu")
		(net 310)
	)
	(segment
		(start 212.859132 85.112)
		(end 212.859132 85.670762)
		(width 0.19)
		(layer "F.Cu")
		(net 310)
	)
	(segment
		(start 212.859132 85.670762)
		(end 213.080632 85.892262)
		(width 0.19)
		(layer "F.Cu")
		(net 310)
	)
	(segment
		(start 213.065632 86.422855)
		(end 213.080632 86.407855)
		(width 0.19)
		(layer "F.Cu")
		(net 310)
	)
	(segment
		(start 212.544132 84.772)
		(end 212.544132 84.797)
		(width 0.19)
		(layer "F.Cu")
		(net 310)
	)
	(segment
		(start 213.080632 86.407855)
		(end 213.080632 85.892262)
		(width 0.19)
		(layer "F.Cu")
		(net 310)
	)
	(segment
		(start 213.544132 83.812)
		(end 213.544132 83.787)
		(width 0.19)
		(layer "F.Cu")
		(net 311)
	)
	(segment
		(start 106.430532 73.65)
		(end 106.695532 73.385)
		(width 0.19)
		(layer "F.Cu")
		(net 311)
	)
	(segment
		(start 213.229132 83.472)
		(end 213.229132 82.915)
		(width 0.19)
		(layer "F.Cu")
		(net 311)
	)
	(segment
		(start 106.695532 72.915)
		(end 106.580532 72.8)
		(width 0.19)
		(layer "F.Cu")
		(net 311)
	)
	(segment
		(start 213.229132 82.915)
		(end 213.344132 82.8)
		(width 0.19)
		(layer "F.Cu")
		(net 311)
	)
	(segment
		(start 213.544132 83.787)
		(end 213.229132 83.472)
		(width 0.19)
		(layer "F.Cu")
		(net 311)
	)
	(segment
		(start 106.695532 73.385)
		(end 106.695532 72.915)
		(width 0.19)
		(layer "F.Cu")
		(net 311)
	)
	(via
		(at 213.344132 82.8)
		(size 0.45)
		(drill 0.1)
		(layers "F.Cu" "B.Cu")
		(net 311)
	)
	(via
		(at 106.580532 72.8)
		(size 0.45)
		(drill 0.1)
		(layers "F.Cu" "B.Cu")
		(net 311)
	)
	(segment
		(start 146.227694 68.633238)
		(end 149.056956 71.4625)
		(width 0.15)
		(layer "In7.Cu")
		(net 311)
	)
	(segment
		(start 106.743032 66.862512)
		(end 114.350142 59.255402)
		(width 0.15)
		(layer "In7.Cu")
		(net 311)
	)
	(segment
		(start 208.656956 73.2625)
		(end 210.7375 75.343044)
		(width 0.15)
		(layer "In7.Cu")
		(net 311)
	)
	(segment
		(start 106.580532 72.8)
		(end 106.743032 72.6375)
		(width 0.15)
		(layer "In7.Cu")
		(net 311)
	)
	(segment
		(start 213.181632 81.287176)
		(end 213.181632 82.6375)
		(width 0.15)
		(layer "In7.Cu")
		(net 311)
	)
	(segment
		(start 196.843044 73.4625)
		(end 197.043044 73.2625)
		(width 0.15)
		(layer "In7.Cu")
		(net 311)
	)
	(segment
		(start 106.743032 72.6375)
		(end 106.743032 66.862512)
		(width 0.15)
		(layer "In7.Cu")
		(net 311)
	)
	(segment
		(start 213.181632 82.6375)
		(end 213.344132 82.8)
		(width 0.15)
		(layer "In7.Cu")
		(net 311)
	)
	(segment
		(start 197.043044 73.2625)
		(end 208.656956 73.2625)
		(width 0.15)
		(layer "In7.Cu")
		(net 311)
	)
	(segment
		(start 188.556956 73.4625)
		(end 196.843044 73.4625)
		(width 0.15)
		(layer "In7.Cu")
		(net 311)
	)
	(segment
		(start 138.494314 59.255402)
		(end 146.227694 66.988782)
		(width 0.15)
		(layer "In7.Cu")
		(net 311)
	)
	(segment
		(start 146.227694 66.988782)
		(end 146.227694 68.633238)
		(width 0.15)
		(layer "In7.Cu")
		(net 311)
	)
	(segment
		(start 114.350142 59.255402)
		(end 138.494314 59.255402)
		(width 0.15)
		(layer "In7.Cu")
		(net 311)
	)
	(segment
		(start 210.7375 75.343044)
		(end 210.7375 78.843044)
		(width 0.15)
		(layer "In7.Cu")
		(net 311)
	)
	(segment
		(start 186.556956 71.4625)
		(end 188.556956 73.4625)
		(width 0.15)
		(layer "In7.Cu")
		(net 311)
	)
	(segment
		(start 149.056956 71.4625)
		(end 186.556956 71.4625)
		(width 0.15)
		(layer "In7.Cu")
		(net 311)
	)
	(segment
		(start 210.7375 78.843044)
		(end 213.181632 81.287176)
		(width 0.15)
		(layer "In7.Cu")
		(net 311)
	)
	(segment
		(start 154.9 119.202001)
		(end 153.777999 119.202001)
		(width 0.1)
		(layer "F.Cu")
		(net 317)
	)
	(segment
		(start 153.777999 119.202001)
		(end 153.73 119.25)
		(width 0.1)
		(layer "F.Cu")
		(net 317)
	)
	(segment
		(start 154.9 119.202001)
		(end 154.922001 119.202001)
		(width 0.1)
		(layer "F.Cu")
		(net 317)
	)
	(segment
		(start 154.922001 119.202001)
		(end 156.12 120.4)
		(width 0.1)
		(layer "F.Cu")
		(net 317)
	)
	(segment
		(start 154.902001 119.2)
		(end 154.9 119.202001)
		(width 0.1)
		(layer "F.Cu")
		(net 317)
	)
	(via
		(at 135.030532 73.65)
		(size 0.45)
		(drill 0.1)
		(layers "F.Cu" "B.Cu")
		(net 317)
	)
	(via
		(at 154.9 119.202001)
		(size 0.45)
		(drill 0.1)
		(layers "F.Cu" "B.Cu")
		(net 317)
	)
	(via
		(at 139.4 100.45)
		(size 0.45)
		(drill 0.1)
		(layers "F.Cu" "B.Cu")
		(net 317)
	)
	(segment
		(start 152.2 111.05)
		(end 152.2 109.724262)
		(width 0.1)
		(layer "B.Cu")
		(net 317)
	)
	(segment
		(start 154.9 119.202001)
		(end 157.447999 119.202001)
		(width 0.1)
		(layer "B.Cu")
		(net 317)
	)
	(segment
		(start 158.55 117.4)
		(end 152.2 111.05)
		(width 0.1)
		(layer "B.Cu")
		(net 317)
	)
	(segment
		(start 145.525736 103.049998)
		(end 142.775736 103.049998)
		(width 0.1)
		(layer "B.Cu")
		(net 317)
	)
	(segment
		(start 140.125736 100.399998)
		(end 139.450002 100.399998)
		(width 0.1)
		(layer "B.Cu")
		(net 317)
	)
	(segment
		(start 158.55 118.1)
		(end 158.55 117.4)
		(width 0.1)
		(layer "B.Cu")
		(net 317)
	)
	(segment
		(start 152.2 109.724262)
		(end 145.525736 103.049998)
		(width 0.1)
		(layer "B.Cu")
		(net 317)
	)
	(segment
		(start 139.450002 100.399998)
		(end 139.4 100.45)
		(width 0.1)
		(layer "B.Cu")
		(net 317)
	)
	(segment
		(start 142.775736 103.049998)
		(end 140.125736 100.399998)
		(width 0.1)
		(layer "B.Cu")
		(net 317)
	)
	(segment
		(start 157.447999 119.202001)
		(end 158.55 118.1)
		(width 0.1)
		(layer "B.Cu")
		(net 317)
	)
	(segment
		(start 133.75 88.9)
		(end 129.75 88.9)
		(width 0.1)
		(layer "In7.Cu")
		(net 317)
	)
	(segment
		(start 140.5 98.65)
		(end 140.1 98.25)
		(width 0.1)
		(layer "In7.Cu")
		(net 317)
	)
	(segment
		(start 141.05 98.65)
		(end 140.5 98.65)
		(width 0.1)
		(layer "In7.Cu")
		(net 317)
	)
	(segment
		(start 132.35 81.7)
		(end 132.75 81.7)
		(width 0.1)
		(layer "In7.Cu")
		(net 317)
	)
	(segment
		(start 134.85 77.55)
		(end 135.55 76.85)
		(width 0.1)
		(layer "In7.Cu")
		(net 317)
	)
	(segment
		(start 129.4 88.2)
		(end 129.65 87.95)
		(width 0.1)
		(layer "In7.Cu")
		(net 317)
	)
	(segment
		(start 131.95 82.1)
		(end 132.35 81.7)
		(width 0.1)
		(layer "In7.Cu")
		(net 317)
	)
	(segment
		(start 140.1 98.25)
		(end 140.1 95.25)
		(width 0.1)
		(layer "In7.Cu")
		(net 317)
	)
	(segment
		(start 136.4 73.35)
		(end 136.2 73.15)
		(width 0.1)
		(layer "In7.Cu")
		(net 317)
	)
	(segment
		(start 135.530532 73.15)
		(end 135.030532 73.65)
		(width 0.1)
		(layer "In7.Cu")
		(net 317)
	)
	(segment
		(start 135.55 76.85)
		(end 135.55 74.85)
		(width 0.1)
		(layer "In7.Cu")
		(net 317)
	)
	(segment
		(start 133 81.45)
		(end 133 80.6)
		(width 0.1)
		(layer "In7.Cu")
		(net 317)
	)
	(segment
		(start 140.8 100.45)
		(end 141.65 99.6)
		(width 0.1)
		(layer "In7.Cu")
		(net 317)
	)
	(segment
		(start 135.55 74.85)
		(end 136.4 74)
		(width 0.1)
		(layer "In7.Cu")
		(net 317)
	)
	(segment
		(start 129.4 88.55)
		(end 129.4 88.2)
		(width 0.1)
		(layer "In7.Cu")
		(net 317)
	)
	(segment
		(start 133 80.6)
		(end 134.85 78.75)
		(width 0.1)
		(layer "In7.Cu")
		(net 317)
	)
	(segment
		(start 136.4 74)
		(end 136.4 73.35)
		(width 0.1)
		(layer "In7.Cu")
		(net 317)
	)
	(segment
		(start 131.15 83.65)
		(end 131.95 82.85)
		(width 0.1)
		(layer "In7.Cu")
		(net 317)
	)
	(segment
		(start 131.95 82.85)
		(end 131.95 82.1)
		(width 0.1)
		(layer "In7.Cu")
		(net 317)
	)
	(segment
		(start 139.4 100.45)
		(end 140.8 100.45)
		(width 0.1)
		(layer "In7.Cu")
		(net 317)
	)
	(segment
		(start 129.65 87.95)
		(end 130.45 87.95)
		(width 0.1)
		(layer "In7.Cu")
		(net 317)
	)
	(segment
		(start 134.85 78.75)
		(end 134.85 77.55)
		(width 0.1)
		(layer "In7.Cu")
		(net 317)
	)
	(segment
		(start 131.15 84.3)
		(end 131.15 83.65)
		(width 0.1)
		(layer "In7.Cu")
		(net 317)
	)
	(segment
		(start 132.75 81.7)
		(end 133 81.45)
		(width 0.1)
		(layer "In7.Cu")
		(net 317)
	)
	(segment
		(start 131.1 84.35)
		(end 131.15 84.3)
		(width 0.1)
		(layer "In7.Cu")
		(net 317)
	)
	(segment
		(start 136.2 73.15)
		(end 135.530532 73.15)
		(width 0.1)
		(layer "In7.Cu")
		(net 317)
	)
	(segment
		(start 141.65 99.6)
		(end 141.65 99.25)
		(width 0.1)
		(layer "In7.Cu")
		(net 317)
	)
	(segment
		(start 131.1 87.3)
		(end 131.1 84.35)
		(width 0.1)
		(layer "In7.Cu")
		(net 317)
	)
	(segment
		(start 129.75 88.9)
		(end 129.4 88.55)
		(width 0.1)
		(layer "In7.Cu")
		(net 317)
	)
	(segment
		(start 130.45 87.95)
		(end 131.1 87.3)
		(width 0.1)
		(layer "In7.Cu")
		(net 317)
	)
	(segment
		(start 140.1 95.25)
		(end 133.75 88.9)
		(width 0.1)
		(layer "In7.Cu")
		(net 317)
	)
	(segment
		(start 141.65 99.25)
		(end 141.05 98.65)
		(width 0.1)
		(layer "In7.Cu")
		(net 317)
	)
	(segment
		(start 110.35 71.65)
		(end 111.8 73.1)
		(width 0.1)
		(layer "F.Cu")
		(net 319)
	)
	(segment
		(start 98 70.95)
		(end 98.25 71.2)
		(width 0.1)
		(layer "F.Cu")
		(net 319)
	)
	(segment
		(start 101.6 71.65)
		(end 110.35 71.65)
		(width 0.1)
		(layer "F.Cu")
		(net 319)
	)
	(segment
		(start 97.45 69.95)
		(end 98 70.5)
		(width 0.1)
		(layer "F.Cu")
		(net 319)
	)
	(segment
		(start 74.5 78.32)
		(end 74.5 77.33)
		(width 0.1)
		(layer "F.Cu")
		(net 319)
	)
	(segment
		(start 111.8 73.1)
		(end 123.3 73.1)
		(width 0.1)
		(layer "F.Cu")
		(net 319)
	)
	(segment
		(start 126.5 73.9)
		(end 127.3 74.7)
		(width 0.1)
		(layer "F.Cu")
		(net 319)
	)
	(segment
		(start 126.5 72.65)
		(end 126.7 72.45)
		(width 0.1)
		(layer "F.Cu")
		(net 319)
	)
	(segment
		(start 95.25 69.25)
		(end 95.25 68)
		(width 0.1)
		(layer "F.Cu")
		(net 319)
	)
	(segment
		(start 126.5 73.9)
		(end 126.5 72.65)
		(width 0.1)
		(layer "F.Cu")
		(net 319)
	)
	(segment
		(start 135.230532 75.15)
		(end 134.780532 74.7)
		(width 0.1)
		(layer "F.Cu")
		(net 319)
	)
	(segment
		(start 126.7 71.85)
		(end 126.5 71.65)
		(width 0.1)
		(layer "F.Cu")
		(net 319)
	)
	(segment
		(start 76 76.9)
		(end 75.57 77.33)
		(width 0.1)
		(layer "F.Cu")
		(net 319)
	)
	(segment
		(start 97.45 69.95)
		(end 95.95 69.95)
		(width 0.1)
		(layer "F.Cu")
		(net 319)
	)
	(segment
		(start 127.3 74.7)
		(end 134.780532 74.7)
		(width 0.1)
		(layer "F.Cu")
		(net 319)
	)
	(segment
		(start 124.25 71.65)
		(end 126.5 71.65)
		(width 0.1)
		(layer "F.Cu")
		(net 319)
	)
	(segment
		(start 95.95 69.95)
		(end 95.25 69.25)
		(width 0.1)
		(layer "F.Cu")
		(net 319)
	)
	(segment
		(start 124 71.9)
		(end 124 72.4)
		(width 0.1)
		(layer "F.Cu")
		(net 319)
	)
	(segment
		(start 75.57 77.33)
		(end 74.5 77.33)
		(width 0.1)
		(layer "F.Cu")
		(net 319)
	)
	(segment
		(start 123.3 73.1)
		(end 124 72.4)
		(width 0.1)
		(layer "F.Cu")
		(net 319)
	)
	(segment
		(start 101.15 71.2)
		(end 98.25 71.2)
		(width 0.1)
		(layer "F.Cu")
		(net 319)
	)
	(segment
		(start 98 70.95)
		(end 98 70.5)
		(width 0.1)
		(layer "F.Cu")
		(net 319)
	)
	(segment
		(start 101.6 71.65)
		(end 101.15 71.2)
		(width 0.1)
		(layer "F.Cu")
		(net 319)
	)
	(segment
		(start 124 71.9)
		(end 124.25 71.65)
		(width 0.1)
		(layer "F.Cu")
		(net 319)
	)
	(segment
		(start 126.7 72.45)
		(end 126.7 71.85)
		(width 0.1)
		(layer "F.Cu")
		(net 319)
	)
	(via
		(at 76 76.9)
		(size 0.45)
		(drill 0.1)
		(layers "F.Cu" "B.Cu")
		(net 319)
	)
	(via
		(at 95.25 68)
		(size 0.45)
		(drill 0.1)
		(layers "F.Cu" "B.Cu")
		(net 319)
	)
	(segment
		(start 79.6 73)
		(end 79.6 76.1)
		(width 0.1)
		(layer "In7.Cu")
		(net 319)
	)
	(segment
		(start 79.6 73)
		(end 83.8 68.8)
		(width 0.1)
		(layer "In7.Cu")
		(net 319)
	)
	(segment
		(start 78.25 77.45)
		(end 79.6 76.1)
		(width 0.1)
		(layer "In7.Cu")
		(net 319)
	)
	(segment
		(start 76.55 77.45)
		(end 76 76.9)
		(width 0.1)
		(layer "In7.Cu")
		(net 319)
	)
	(segment
		(start 95.25 68)
		(end 90.95 68)
		(width 0.1)
		(layer "In7.Cu")
		(net 319)
	)
	(segment
		(start 90.15 68.8)
		(end 83.8 68.8)
		(width 0.1)
		(layer "In7.Cu")
		(net 319)
	)
	(segment
		(start 76.55 77.45)
		(end 78.25 77.45)
		(width 0.1)
		(layer "In7.Cu")
		(net 319)
	)
	(segment
		(start 90.95 68)
		(end 90.15 68.8)
		(width 0.1)
		(layer "In7.Cu")
		(net 319)
	)
	(via
		(at 83.9 77.85)
		(size 0.45)
		(drill 0.1)
		(layers "F.Cu" "B.Cu")
		(net 321)
	)
	(via
		(at 136.130532 75.15)
		(size 0.45)
		(drill 0.1)
		(layers "F.Cu" "B.Cu")
		(net 321)
	)
	(segment
		(start 77.85 80.9)
		(end 82.5 80.9)
		(width 0.1)
		(layer "B.Cu")
		(net 321)
	)
	(segment
		(start 79.85 92.25)
		(end 78.1 92.25)
		(width 0.1)
		(layer "B.Cu")
		(net 321)
	)
	(segment
		(start 80.1 92.5)
		(end 79.85 92.25)
		(width 0.1)
		(layer "B.Cu")
		(net 321)
	)
	(segment
		(start 83.25 78.2)
		(end 83.55 78.2)
		(width 0.1)
		(layer "B.Cu")
		(net 321)
	)
	(segment
		(start 80.25 105.35)
		(end 80.1 105.2)
		(width 0.1)
		(layer "B.Cu")
		(net 321)
	)
	(segment
		(start 80.1 105.2)
		(end 80.1 92.5)
		(width 0.1)
		(layer "B.Cu")
		(net 321)
	)
	(segment
		(start 83.55 78.2)
		(end 83.9 77.85)
		(width 0.1)
		(layer "B.Cu")
		(net 321)
	)
	(segment
		(start 82.9 80.5)
		(end 82.9 78.55)
		(width 0.1)
		(layer "B.Cu")
		(net 321)
	)
	(segment
		(start 80.25 106.279468)
		(end 80.25 105.35)
		(width 0.1)
		(layer "B.Cu")
		(net 321)
	)
	(segment
		(start 78.1 92.25)
		(end 77.65 91.8)
		(width 0.1)
		(layer "B.Cu")
		(net 321)
	)
	(segment
		(start 77.65 91.8)
		(end 77.65 81.1)
		(width 0.1)
		(layer "B.Cu")
		(net 321)
	)
	(segment
		(start 80.855532 106.885)
		(end 80.25 106.279468)
		(width 0.1)
		(layer "B.Cu")
		(net 321)
	)
	(segment
		(start 82.9 78.55)
		(end 83.25 78.2)
		(width 0.1)
		(layer "B.Cu")
		(net 321)
	)
	(segment
		(start 77.65 81.1)
		(end 77.85 80.9)
		(width 0.1)
		(layer "B.Cu")
		(net 321)
	)
	(segment
		(start 82.5 80.9)
		(end 82.9 80.5)
		(width 0.1)
		(layer "B.Cu")
		(net 321)
	)
	(segment
		(start 102.9 74.7)
		(end 102.9 75.2)
		(width 0.1)
		(layer "In5.Cu")
		(net 321)
	)
	(segment
		(start 102.9 75.2)
		(end 102.5 75.6)
		(width 0.1)
		(layer "In5.Cu")
		(net 321)
	)
	(segment
		(start 136.4 74.880532)
		(end 136.4 73.1)
		(width 0.1)
		(layer "In5.Cu")
		(net 321)
	)
	(segment
		(start 100.2 74.1)
		(end 98.8 74.1)
		(width 0.1)
		(layer "In5.Cu")
		(net 321)
	)
	(segment
		(start 133.8 71.4)
		(end 133.8 70.9)
		(width 0.1)
		(layer "In5.Cu")
		(net 321)
	)
	(segment
		(start 102.5 75.6)
		(end 101.7 75.6)
		(width 0.1)
		(layer "In5.Cu")
		(net 321)
	)
	(segment
		(start 84.55 77.85)
		(end 86.6 75.8)
		(width 0.1)
		(layer "In5.Cu")
		(net 321)
	)
	(segment
		(start 94.7 74.7)
		(end 93.6 75.8)
		(width 0.1)
		(layer "In5.Cu")
		(net 321)
	)
	(segment
		(start 93.6 75.8)
		(end 86.6 75.8)
		(width 0.1)
		(layer "In5.Cu")
		(net 321)
	)
	(segment
		(start 103.7 72.8)
		(end 103.7 73.9)
		(width 0.1)
		(layer "In5.Cu")
		(net 321)
	)
	(segment
		(start 103.6 70)
		(end 103.6 70.9)
		(width 0.1)
		(layer "In5.Cu")
		(net 321)
	)
	(segment
		(start 98.2 74.7)
		(end 94.7 74.7)
		(width 0.1)
		(layer "In5.Cu")
		(net 321)
	)
	(segment
		(start 136.4 73.1)
		(end 135.6 72.3)
		(width 0.1)
		(layer "In5.Cu")
		(net 321)
	)
	(segment
		(start 103.6 70.9)
		(end 104 71.3)
		(width 0.1)
		(layer "In5.Cu")
		(net 321)
	)
	(segment
		(start 135.6 72.3)
		(end 134.7 72.3)
		(width 0.1)
		(layer "In5.Cu")
		(net 321)
	)
	(segment
		(start 104 71.3)
		(end 104 72.5)
		(width 0.1)
		(layer "In5.Cu")
		(net 321)
	)
	(segment
		(start 104.1 69.5)
		(end 103.6 70)
		(width 0.1)
		(layer "In5.Cu")
		(net 321)
	)
	(segment
		(start 104 72.5)
		(end 103.7 72.8)
		(width 0.1)
		(layer "In5.Cu")
		(net 321)
	)
	(segment
		(start 136.130532 75.15)
		(end 136.4 74.880532)
		(width 0.1)
		(layer "In5.Cu")
		(net 321)
	)
	(segment
		(start 133.1 70.2)
		(end 126.5 70.2)
		(width 0.1)
		(layer "In5.Cu")
		(net 321)
	)
	(segment
		(start 125.8 69.5)
		(end 104.1 69.5)
		(width 0.1)
		(layer "In5.Cu")
		(net 321)
	)
	(segment
		(start 101.7 75.6)
		(end 100.2 74.1)
		(width 0.1)
		(layer "In5.Cu")
		(net 321)
	)
	(segment
		(start 133.8 70.9)
		(end 133.1 70.2)
		(width 0.1)
		(layer "In5.Cu")
		(net 321)
	)
	(segment
		(start 103.7 73.9)
		(end 102.9 74.7)
		(width 0.1)
		(layer "In5.Cu")
		(net 321)
	)
	(segment
		(start 126.5 70.2)
		(end 125.8 69.5)
		(width 0.1)
		(layer "In5.Cu")
		(net 321)
	)
	(segment
		(start 98.8 74.1)
		(end 98.2 74.7)
		(width 0.1)
		(layer "In5.Cu")
		(net 321)
	)
	(segment
		(start 134.7 72.3)
		(end 133.8 71.4)
		(width 0.1)
		(layer "In5.Cu")
		(net 321)
	)
	(segment
		(start 83.9 77.85)
		(end 84.55 77.85)
		(width 0.1)
		(layer "In5.Cu")
		(net 321)
	)
	(segment
		(start 215.524132 84.787)
		(end 215.524132 84.762)
		(width 0.19)
		(layer "F.Cu")
		(net 322)
	)
	(segment
		(start 215.224132 85.537498)
		(end 215.224132 85.087)
		(width 0.19)
		(layer "F.Cu")
		(net 322)
	)
	(segment
		(start 214.665632 86.872856)
		(end 214.665632 86.422855)
		(width 0.19)
		(layer "F.Cu")
		(net 322)
	)
	(segment
		(start 214.649632 86.111998)
		(end 215.224132 85.537498)
		(width 0.19)
		(layer "F.Cu")
		(net 322)
	)
	(segment
		(start 214.665632 86.422855)
		(end 214.649632 86.406855)
		(width 0.19)
		(layer "F.Cu")
		(net 322)
	)
	(segment
		(start 215.224132 85.087)
		(end 215.524132 84.787)
		(width 0.19)
		(layer "F.Cu")
		(net 322)
	)
	(segment
		(start 214.649632 86.406855)
		(end 214.649632 86.111998)
		(width 0.19)
		(layer "F.Cu")
		(net 322)
	)
	(segment
		(start 215.524132 83.802)
		(end 215.524132 83.777)
		(width 0.19)
		(layer "F.Cu")
		(net 324)
	)
	(segment
		(start 215.524132 83.777)
		(end 215.224132 83.477)
		(width 0.19)
		(layer "F.Cu")
		(net 324)
	)
	(segment
		(start 215.224132 82.915)
		(end 215.339132 82.8)
		(width 0.19)
		(layer "F.Cu")
		(net 324)
	)
	(segment
		(start 107.330532 85.65)
		(end 107.065532 85.915)
		(width 0.19)
		(layer "F.Cu")
		(net 324)
	)
	(segment
		(start 107.065532 87.185)
		(end 107.180532 87.3)
		(width 0.19)
		(layer "F.Cu")
		(net 324)
	)
	(segment
		(start 215.224132 83.477)
		(end 215.224132 82.915)
		(width 0.19)
		(layer "F.Cu")
		(net 324)
	)
	(segment
		(start 107.065532 85.915)
		(end 107.065532 87.185)
		(width 0.19)
		(layer "F.Cu")
		(net 324)
	)
	(via
		(at 215.339132 82.8)
		(size 0.45)
		(drill 0.1)
		(layers "F.Cu" "B.Cu")
		(net 324)
	)
	(via
		(at 107.180532 87.3)
		(size 0.45)
		(drill 0.1)
		(layers "F.Cu" "B.Cu")
		(net 324)
	)
	(segment
		(start 206.643044 76.7375)
		(end 207.9625 78.056956)
		(width 0.15)
		(layer "In7.Cu")
		(net 324)
	)
	(segment
		(start 148.443044 73.1375)
		(end 185.643044 73.1375)
		(width 0.15)
		(layer "In7.Cu")
		(net 324)
	)
	(segment
		(start 215.176632 82.9625)
		(end 215.339132 82.8)
		(width 0.15)
		(layer "In7.Cu")
		(net 324)
	)
	(segment
		(start 210.8625 82.756956)
		(end 212.368044 84.2625)
		(width 0.15)
		(layer "In7.Cu")
		(net 324)
	)
	(segment
		(start 107.456956 76.6625)
		(end 106.656956 76.6625)
		(width 0.15)
		(layer "In7.Cu")
		(net 324)
	)
	(segment
		(start 208.543044 80.6375)
		(end 209.643044 80.6375)
		(width 0.15)
		(layer "In7.Cu")
		(net 324)
	)
	(segment
		(start 106.9375 73.856956)
		(end 107.256956 73.5375)
		(width 0.15)
		(layer "In7.Cu")
		(net 324)
	)
	(segment
		(start 207.9625 80.056956)
		(end 208.543044 80.6375)
		(width 0.15)
		(layer "In7.Cu")
		(net 324)
	)
	(segment
		(start 105.8375 74.956956)
		(end 106.056956 74.7375)
		(width 0.15)
		(layer "In7.Cu")
		(net 324)
	)
	(segment
		(start 144.255636 67.805636)
		(end 144.255636 68.950092)
		(width 0.15)
		(layer "In7.Cu")
		(net 324)
	)
	(segment
		(start 210.8625 81.856956)
		(end 210.8625 82.756956)
		(width 0.15)
		(layer "In7.Cu")
		(net 324)
	)
	(segment
		(start 214.556956 84.2625)
		(end 215.176632 83.642824)
		(width 0.15)
		(layer "In7.Cu")
		(net 324)
	)
	(segment
		(start 107.656956 73.5375)
		(end 108.1375 73.056956)
		(width 0.15)
		(layer "In7.Cu")
		(net 324)
	)
	(segment
		(start 106.056956 74.7375)
		(end 106.456956 74.7375)
		(width 0.15)
		(layer "In7.Cu")
		(net 324)
	)
	(segment
		(start 108.9875 67.406956)
		(end 115.166995 61.227461)
		(width 0.15)
		(layer "In7.Cu")
		(net 324)
	)
	(segment
		(start 105.8375 75.843044)
		(end 105.8375 74.956956)
		(width 0.15)
		(layer "In7.Cu")
		(net 324)
	)
	(segment
		(start 108.3375 78.656956)
		(end 108.3375 77.543044)
		(width 0.15)
		(layer "In7.Cu")
		(net 324)
	)
	(segment
		(start 107.180532 87.3)
		(end 107.018032 87.1375)
		(width 0.15)
		(layer "In7.Cu")
		(net 324)
	)
	(segment
		(start 106.856956 79.5375)
		(end 107.456956 79.5375)
		(width 0.15)
		(layer "In7.Cu")
		(net 324)
	)
	(segment
		(start 185.643044 73.1375)
		(end 188.543044 76.0375)
		(width 0.15)
		(layer "In7.Cu")
		(net 324)
	)
	(segment
		(start 107.018032 83.823576)
		(end 106.3375 83.143044)
		(width 0.15)
		(layer "In7.Cu")
		(net 324)
	)
	(segment
		(start 144.255636 68.950092)
		(end 148.443044 73.1375)
		(width 0.15)
		(layer "In7.Cu")
		(net 324)
	)
	(segment
		(start 209.643044 80.6375)
		(end 210.8625 81.856956)
		(width 0.15)
		(layer "In7.Cu")
		(net 324)
	)
	(segment
		(start 108.3375 77.543044)
		(end 107.456956 76.6625)
		(width 0.15)
		(layer "In7.Cu")
		(net 324)
	)
	(segment
		(start 204.543044 76.7375)
		(end 206.643044 76.7375)
		(width 0.15)
		(layer "In7.Cu")
		(net 324)
	)
	(segment
		(start 115.166995 61.227461)
		(end 137.677461 61.227461)
		(width 0.15)
		(layer "In7.Cu")
		(net 324)
	)
	(segment
		(start 105.8375 81.843044)
		(end 105.8375 80.556956)
		(width 0.15)
		(layer "In7.Cu")
		(net 324)
	)
	(segment
		(start 108.9875 71.656956)
		(end 108.9875 67.406956)
		(width 0.15)
		(layer "In7.Cu")
		(net 324)
	)
	(segment
		(start 106.456956 74.7375)
		(end 106.9375 74.256956)
		(width 0.15)
		(layer "In7.Cu")
		(net 324)
	)
	(segment
		(start 207.9625 78.056956)
		(end 207.9625 80.056956)
		(width 0.15)
		(layer "In7.Cu")
		(net 324)
	)
	(segment
		(start 106.3375 83.143044)
		(end 106.3375 82.343044)
		(width 0.15)
		(layer "In7.Cu")
		(net 324)
	)
	(segment
		(start 203.043044 75.2375)
		(end 204.543044 76.7375)
		(width 0.15)
		(layer "In7.Cu")
		(net 324)
	)
	(segment
		(start 106.9375 74.256956)
		(end 106.9375 73.856956)
		(width 0.15)
		(layer "In7.Cu")
		(net 324)
	)
	(segment
		(start 105.8375 80.556956)
		(end 106.856956 79.5375)
		(width 0.15)
		(layer "In7.Cu")
		(net 324)
	)
	(segment
		(start 197.856956 75.2375)
		(end 203.043044 75.2375)
		(width 0.15)
		(layer "In7.Cu")
		(net 324)
	)
	(segment
		(start 106.656956 76.6625)
		(end 105.8375 75.843044)
		(width 0.15)
		(layer "In7.Cu")
		(net 324)
	)
	(segment
		(start 188.543044 76.0375)
		(end 197.056956 76.0375)
		(width 0.15)
		(layer "In7.Cu")
		(net 324)
	)
	(segment
		(start 106.3375 82.343044)
		(end 105.8375 81.843044)
		(width 0.15)
		(layer "In7.Cu")
		(net 324)
	)
	(segment
		(start 215.176632 83.642824)
		(end 215.176632 82.9625)
		(width 0.15)
		(layer "In7.Cu")
		(net 324)
	)
	(segment
		(start 108.1375 73.056956)
		(end 108.1375 72.506956)
		(width 0.15)
		(layer "In7.Cu")
		(net 324)
	)
	(segment
		(start 108.1375 72.506956)
		(end 108.9875 71.656956)
		(width 0.15)
		(layer "In7.Cu")
		(net 324)
	)
	(segment
		(start 107.456956 79.5375)
		(end 108.3375 78.656956)
		(width 0.15)
		(layer "In7.Cu")
		(net 324)
	)
	(segment
		(start 137.677461 61.227461)
		(end 144.255636 67.805636)
		(width 0.15)
		(layer "In7.Cu")
		(net 324)
	)
	(segment
		(start 107.256956 73.5375)
		(end 107.656956 73.5375)
		(width 0.15)
		(layer "In7.Cu")
		(net 324)
	)
	(segment
		(start 197.056956 76.0375)
		(end 197.856956 75.2375)
		(width 0.15)
		(layer "In7.Cu")
		(net 324)
	)
	(segment
		(start 212.368044 84.2625)
		(end 214.556956 84.2625)
		(width 0.15)
		(layer "In7.Cu")
		(net 324)
	)
	(segment
		(start 107.018032 87.1375)
		(end 107.018032 83.823576)
		(width 0.15)
		(layer "In7.Cu")
		(net 324)
	)
	(segment
		(start 212.544132 83.787)
		(end 212.859132 83.472)
		(width 0.19)
		(layer "F.Cu")
		(net 329)
	)
	(segment
		(start 212.859132 82.915)
		(end 212.744132 82.8)
		(width 0.19)
		(layer "F.Cu")
		(net 329)
	)
	(segment
		(start 212.544132 83.812)
		(end 212.544132 83.787)
		(width 0.19)
		(layer "F.Cu")
		(net 329)
	)
	(segment
		(start 212.859132 83.472)
		(end 212.859132 82.915)
		(width 0.19)
		(layer "F.Cu")
		(net 329)
	)
	(segment
		(start 107.330532 73.65)
		(end 107.065532 73.385)
		(width 0.19)
		(layer "F.Cu")
		(net 329)
	)
	(segment
		(start 107.065532 72.915)
		(end 107.180532 72.8)
		(width 0.19)
		(layer "F.Cu")
		(net 329)
	)
	(segment
		(start 107.065532 73.385)
		(end 107.065532 72.915)
		(width 0.19)
		(layer "F.Cu")
		(net 329)
	)
	(via
		(at 212.744132 82.8)
		(size 0.45)
		(drill 0.1)
		(layers "F.Cu" "B.Cu")
		(net 329)
	)
	(via
		(at 107.180532 72.8)
		(size 0.45)
		(drill 0.1)
		(layers "F.Cu" "B.Cu")
		(net 329)
	)
	(segment
		(start 138.380403 59.530405)
		(end 145.952691 67.102693)
		(width 0.15)
		(layer "In7.Cu")
		(net 329)
	)
	(segment
		(start 210.4625 75.456956)
		(end 210.4625 78.956956)
		(width 0.15)
		(layer "In7.Cu")
		(net 329)
	)
	(segment
		(start 126.951279 59.530405)
		(end 138.380403 59.530405)
		(width 0.15)
		(layer "In7.Cu")
		(net 329)
	)
	(segment
		(start 197.156956 73.5375)
		(end 208.543044 73.5375)
		(width 0.15)
		(layer "In7.Cu")
		(net 329)
	)
	(segment
		(start 145.952691 67.102693)
		(end 145.952691 68.747147)
		(width 0.15)
		(layer "In7.Cu")
		(net 329)
	)
	(segment
		(start 212.906632 81.401088)
		(end 212.906632 82.6375)
		(width 0.15)
		(layer "In7.Cu")
		(net 329)
	)
	(segment
		(start 114.464051 59.530405)
		(end 126.321279 59.530405)
		(width 0.15)
		(layer "In7.Cu")
		(net 329)
	)
	(segment
		(start 186.443044 71.7375)
		(end 188.443044 73.7375)
		(width 0.15)
		(layer "In7.Cu")
		(net 329)
	)
	(segment
		(start 107.018032 72.6375)
		(end 107.018032 66.976424)
		(width 0.15)
		(layer "In7.Cu")
		(net 329)
	)
	(segment
		(start 208.543044 73.5375)
		(end 210.4625 75.456956)
		(width 0.15)
		(layer "In7.Cu")
		(net 329)
	)
	(segment
		(start 145.952691 68.747147)
		(end 148.943044 71.7375)
		(width 0.15)
		(layer "In7.Cu")
		(net 329)
	)
	(segment
		(start 212.906632 82.6375)
		(end 212.744132 82.8)
		(width 0.15)
		(layer "In7.Cu")
		(net 329)
	)
	(segment
		(start 126.461279 59.670405)
		(end 126.461279 59.966186)
		(width 0.15)
		(layer "In7.Cu")
		(net 329)
	)
	(segment
		(start 126.601279 60.106186)
		(end 126.671279 60.106186)
		(width 0.15)
		(layer "In7.Cu")
		(net 329)
	)
	(segment
		(start 188.443044 73.7375)
		(end 196.956956 73.7375)
		(width 0.15)
		(layer "In7.Cu")
		(net 329)
	)
	(segment
		(start 148.943044 71.7375)
		(end 186.443044 71.7375)
		(width 0.15)
		(layer "In7.Cu")
		(net 329)
	)
	(segment
		(start 210.4625 78.956956)
		(end 212.906632 81.401088)
		(width 0.15)
		(layer "In7.Cu")
		(net 329)
	)
	(segment
		(start 107.018032 66.976424)
		(end 114.464051 59.530405)
		(width 0.15)
		(layer "In7.Cu")
		(net 329)
	)
	(segment
		(start 196.956956 73.7375)
		(end 197.156956 73.5375)
		(width 0.15)
		(layer "In7.Cu")
		(net 329)
	)
	(segment
		(start 126.811279 59.966186)
		(end 126.811279 59.670405)
		(width 0.15)
		(layer "In7.Cu")
		(net 329)
	)
	(segment
		(start 107.180532 72.8)
		(end 107.018032 72.6375)
		(width 0.15)
		(layer "In7.Cu")
		(net 329)
	)
	(arc
		(start 126.321279 59.530405)
		(mid 126.420274 59.57141)
		(end 126.461279 59.670405)
		(width 0.15)
		(layer "In7.Cu")
		(net 329)
	)
	(arc
		(start 126.811279 59.670405)
		(mid 126.852284 59.57141)
		(end 126.951279 59.530405)
		(width 0.15)
		(layer "In7.Cu")
		(net 329)
	)
	(arc
		(start 126.461279 59.966186)
		(mid 126.502284 60.065181)
		(end 126.601279 60.106186)
		(width 0.15)
		(layer "In7.Cu")
		(net 329)
	)
	(arc
		(start 126.671279 60.106186)
		(mid 126.770274 60.065181)
		(end 126.811279 59.966186)
		(width 0.15)
		(layer "In7.Cu")
		(net 329)
	)
	(segment
		(start 89.030532 73.65)
		(end 88.180532 72.8)
		(width 0.1)
		(layer "F.Cu")
		(net 330)
	)
	(segment
		(start 88.180532 72.8)
		(end 87.6 72.8)
		(width 0.1)
		(layer "F.Cu")
		(net 330)
	)
	(segment
		(start 87.6 72.8)
		(end 87 72.2)
		(width 0.1)
		(layer "F.Cu")
		(net 330)
	)
	(segment
		(start 86.2 72.2)
		(end 87 72.2)
		(width 0.1)
		(layer "F.Cu")
		(net 330)
	)
	(segment
		(start 86.2 72.2)
		(end 85.8 72.6)
		(width 0.1)
		(layer "F.Cu")
		(net 330)
	)
	(via
		(at 77.045532 78.945)
		(size 0.45)
		(drill 0.1)
		(layers "F.Cu" "B.Cu")
		(net 330)
	)
	(via
		(at 85.8 72.6)
		(size 0.45)
		(drill 0.1)
		(layers "F.Cu" "B.Cu")
		(net 330)
	)
	(segment
		(start 80.4 73.2)
		(end 85.2 73.2)
		(width 0.1)
		(layer "In7.Cu")
		(net 330)
	)
	(segment
		(start 80 73.6)
		(end 80.4 73.2)
		(width 0.1)
		(layer "In7.Cu")
		(net 330)
	)
	(segment
		(start 80 76)
		(end 80 73.6)
		(width 0.1)
		(layer "In7.Cu")
		(net 330)
	)
	(segment
		(start 77.045532 78.945)
		(end 77.045532 78.154468)
		(width 0.1)
		(layer "In7.Cu")
		(net 330)
	)
	(segment
		(start 85.2 73.2)
		(end 85.8 72.6)
		(width 0.1)
		(layer "In7.Cu")
		(net 330)
	)
	(segment
		(start 78.2 77.8)
		(end 80 76)
		(width 0.1)
		(layer "In7.Cu")
		(net 330)
	)
	(segment
		(start 77.045532 78.154468)
		(end 77.4 77.8)
		(width 0.1)
		(layer "In7.Cu")
		(net 330)
	)
	(segment
		(start 77.4 77.8)
		(end 78.2 77.8)
		(width 0.1)
		(layer "In7.Cu")
		(net 330)
	)
	(segment
		(start 154.5 119.75)
		(end 154.85 119.75)
		(width 0.1)
		(layer "F.Cu")
		(net 331)
	)
	(segment
		(start 155.1 120)
		(end 155.1 121.2)
		(width 0.1)
		(layer "F.Cu")
		(net 331)
	)
	(segment
		(start 153.73 119.75)
		(end 154.5 119.75)
		(width 0.1)
		(layer "F.Cu")
		(net 331)
	)
	(segment
		(start 154.85 119.75)
		(end 155.1 120)
		(width 0.1)
		(layer "F.Cu")
		(net 331)
	)
	(segment
		(start 155.1 121.2)
		(end 155.3 121.4)
		(width 0.1)
		(layer "F.Cu")
		(net 331)
	)
	(segment
		(start 155.3 121.4)
		(end 156.12 121.4)
		(width 0.1)
		(layer "F.Cu")
		(net 331)
	)
	(via
		(at 139.35 99.65)
		(size 0.45)
		(drill 0.1)
		(layers "F.Cu" "B.Cu")
		(net 331)
	)
	(via
		(at 154.5 119.75)
		(size 0.45)
		(drill 0.1)
		(layers "F.Cu" "B.Cu")
		(net 331)
	)
	(via
		(at 135.930532 73.65)
		(size 0.45)
		(drill 0.1)
		(layers "F.Cu" "B.Cu")
		(net 331)
	)
	(segment
		(start 157.35 119.75)
		(end 158.85 118.25)
		(width 0.1)
		(layer "B.Cu")
		(net 331)
	)
	(segment
		(start 142.9 102.75)
		(end 140.25 100.1)
		(width 0.1)
		(layer "B.Cu")
		(net 331)
	)
	(segment
		(start 139.8 100.1)
		(end 139.35 99.65)
		(width 0.1)
		(layer "B.Cu")
		(net 331)
	)
	(segment
		(start 154.5 119.75)
		(end 157.35 119.75)
		(width 0.1)
		(layer "B.Cu")
		(net 331)
	)
	(segment
		(start 158.85 118.25)
		(end 158.85 117.275736)
		(width 0.1)
		(layer "B.Cu")
		(net 331)
	)
	(segment
		(start 152.499999 110.925735)
		(end 152.499999 109.599999)
		(width 0.1)
		(layer "B.Cu")
		(net 331)
	)
	(segment
		(start 152.499999 109.599999)
		(end 145.65 102.75)
		(width 0.1)
		(layer "B.Cu")
		(net 331)
	)
	(segment
		(start 145.65 102.75)
		(end 142.9 102.75)
		(width 0.1)
		(layer "B.Cu")
		(net 331)
	)
	(segment
		(start 158.85 117.275736)
		(end 152.499999 110.925735)
		(width 0.1)
		(layer "B.Cu")
		(net 331)
	)
	(segment
		(start 140.25 100.1)
		(end 139.8 100.1)
		(width 0.1)
		(layer "B.Cu")
		(net 331)
	)
	(segment
		(start 131.05 82.85)
		(end 131.05 81.55)
		(width 0.1)
		(layer "In7.Cu")
		(net 331)
	)
	(segment
		(start 139.35 99.65)
		(end 139.75 99.25)
		(width 0.1)
		(layer "In7.Cu")
		(net 331)
	)
	(segment
		(start 132.6 80.2)
		(end 133.9 78.9)
		(width 0.1)
		(layer "In7.Cu")
		(net 331)
	)
	(segment
		(start 133.9 78.9)
		(end 133.9 77.9)
		(width 0.1)
		(layer "In7.Cu")
		(net 331)
	)
	(segment
		(start 129.2 88.1)
		(end 129.55 87.75)
		(width 0.1)
		(layer "In7.Cu")
		(net 331)
	)
	(segment
		(start 130.9 87.217158)
		(end 130.9 84.849799)
		(width 0.1)
		(layer "In7.Cu")
		(net 331)
	)
	(segment
		(start 131.05 81.55)
		(end 131.2 81.4)
		(width 0.1)
		(layer "In7.Cu")
		(net 331)
	)
	(segment
		(start 130.35 83.55)
		(end 131.05 82.85)
		(width 0.1)
		(layer "In7.Cu")
		(net 331)
	)
	(segment
		(start 130.35 84.299799)
		(end 130.35 83.55)
		(width 0.1)
		(layer "In7.Cu")
		(net 331)
	)
	(segment
		(start 129.55 87.75)
		(end 130.367158 87.75)
		(width 0.1)
		(layer "In7.Cu")
		(net 331)
	)
	(segment
		(start 130.367158 87.75)
		(end 130.9 87.217158)
		(width 0.1)
		(layer "In7.Cu")
		(net 331)
	)
	(segment
		(start 130.9 84.849799)
		(end 130.35 84.299799)
		(width 0.1)
		(layer "In7.Cu")
		(net 331)
	)
	(segment
		(start 131.2 80.6)
		(end 131.6 80.2)
		(width 0.1)
		(layer "In7.Cu")
		(net 331)
	)
	(segment
		(start 139.75 99.25)
		(end 139.75 95.394974)
		(width 0.1)
		(layer "In7.Cu")
		(net 331)
	)
	(segment
		(start 129.2 88.844974)
		(end 129.2 88.1)
		(width 0.1)
		(layer "In7.Cu")
		(net 331)
	)
	(segment
		(start 139.75 95.394974)
		(end 133.605025 89.249999)
		(width 0.1)
		(layer "In7.Cu")
		(net 331)
	)
	(segment
		(start 129.605025 89.249999)
		(end 129.2 88.844974)
		(width 0.1)
		(layer "In7.Cu")
		(net 331)
	)
	(segment
		(start 131.6 80.2)
		(end 132.6 80.2)
		(width 0.1)
		(layer "In7.Cu")
		(net 331)
	)
	(segment
		(start 134.65 77.15)
		(end 134.65 76.35)
		(width 0.1)
		(layer "In7.Cu")
		(net 331)
	)
	(segment
		(start 135.35 74.230532)
		(end 135.930532 73.65)
		(width 0.1)
		(layer "In7.Cu")
		(net 331)
	)
	(segment
		(start 131.2 81.4)
		(end 131.2 80.6)
		(width 0.1)
		(layer "In7.Cu")
		(net 331)
	)
	(segment
		(start 135.35 75.65)
		(end 135.35 74.230532)
		(width 0.1)
		(layer "In7.Cu")
		(net 331)
	)
	(segment
		(start 133.9 77.9)
		(end 134.65 77.15)
		(width 0.1)
		(layer "In7.Cu")
		(net 331)
	)
	(segment
		(start 133.605025 89.249999)
		(end 129.605025 89.249999)
		(width 0.1)
		(layer "In7.Cu")
		(net 331)
	)
	(segment
		(start 134.65 76.35)
		(end 135.35 75.65)
		(width 0.1)
		(layer "In7.Cu")
		(net 331)
	)
	(segment
		(start 213.229132 85.112)
		(end 213.544132 84.797)
		(width 0.19)
		(layer "F.Cu")
		(net 333)
	)
	(segment
		(start 213.544132 84.797)
		(end 213.544132 84.772)
		(width 0.19)
		(layer "F.Cu")
		(net 333)
	)
	(segment
		(start 213.229132 85.517502)
		(end 213.229132 85.112)
		(width 0.19)
		(layer "F.Cu")
		(net 333)
	)
	(segment
		(start 213.465632 86.422855)
		(end 213.450632 86.407855)
		(width 0.19)
		(layer "F.Cu")
		(net 333)
	)
	(segment
		(start 213.465632 86.872856)
		(end 213.465632 86.422855)
		(width 0.19)
		(layer "F.Cu")
		(net 333)
	)
	(segment
		(start 213.450632 86.407855)
		(end 213.450632 85.739002)
		(width 0.19)
		(layer "F.Cu")
		(net 333)
	)
	(segment
		(start 213.450632 85.739002)
		(end 213.229132 85.517502)
		(width 0.19)
		(layer "F.Cu")
		(net 333)
	)
	(segment
		(start 210.9 77.3)
		(end 210.72 77.48)
		(width 0.2)
		(layer "F.Cu")
		(net 334)
	)
	(segment
		(start 211.5 77.3)
		(end 210.9 77.3)
		(width 0.2)
		(layer "F.Cu")
		(net 334)
	)
	(segment
		(start 218.5 74.4)
		(end 218.990049 74.4)
		(width 0.2)
		(layer "F.Cu")
		(net 334)
	)
	(segment
		(start 211.68 81.98)
		(end 211.7 82)
		(width 0.2)
		(layer "F.Cu")
		(net 334)
	)
	(segment
		(start 210.72 78)
		(end 210.72 78.47)
		(width 0.2)
		(layer "F.Cu")
		(net 334)
	)
	(segment
		(start 211.68 81.3)
		(end 211.68 81.98)
		(width 0.2)
		(layer "F.Cu")
		(net 334)
	)
	(segment
		(start 210.95 78.7)
		(end 210.95 79.35)
		(width 0.2)
		(layer "F.Cu")
		(net 334)
	)
	(segment
		(start 210.72 77.48)
		(end 210.72 78)
		(width 0.2)
		(layer "F.Cu")
		(net 334)
	)
	(segment
		(start 211.45 81.07)
		(end 211.68 81.3)
		(width 0.2)
		(layer "F.Cu")
		(net 334)
	)
	(segment
		(start 218.990049 74.4)
		(end 219.29 74.699951)
		(width 0.2)
		(layer "F.Cu")
		(net 334)
	)
	(segment
		(start 210.72 78.47)
		(end 210.95 78.7)
		(width 0.2)
		(layer "F.Cu")
		(net 334)
	)
	(segment
		(start 219.12 74.699951)
		(end 219.12 73.599951)
		(width 0.2)
		(layer "F.Cu")
		(net 334)
	)
	(segment
		(start 211.45 80.25)
		(end 211.45 81.07)
		(width 0.2)
		(layer "F.Cu")
		(net 334)
	)
	(via
		(at 222.7 79.6)
		(size 0.45)
		(drill 0.1)
		(layers "F.Cu" "B.Cu")
		(net 334)
	)
	(via
		(at 211.5 77.3)
		(size 0.45)
		(drill 0.1)
		(layers "F.Cu" "B.Cu")
		(net 334)
	)
	(via
		(at 220.3 81.05)
		(size 0.45)
		(drill 0.1)
		(layers "F.Cu" "B.Cu")
		(net 334)
	)
	(via
		(at 218.5 74.4)
		(size 0.45)
		(drill 0.1)
		(layers "F.Cu" "B.Cu")
		(net 334)
	)
	(via
		(at 211.7 82)
		(size 0.45)
		(drill 0.1)
		(layers "F.Cu" "B.Cu")
		(net 334)
	)
	(segment
		(start 213.27 70.17)
		(end 213.071 69.971)
		(width 0.3)
		(layer "B.Cu")
		(net 334)
	)
	(segment
		(start 211.7 80.2)
		(end 211.7 80)
		(width 0.2)
		(layer "B.Cu")
		(net 334)
	)
	(segment
		(start 216.17 70.17)
		(end 218.5 72.5)
		(width 0.3)
		(layer "B.Cu")
		(net 334)
	)
	(segment
		(start 220.3 81.05)
		(end 220.3 80.265)
		(width 0.2)
		(layer "B.Cu")
		(net 334)
	)
	(segment
		(start 211.7 79.7)
		(end 211.5 79.5)
		(width 0.2)
		(layer "B.Cu")
		(net 334)
	)
	(segment
		(start 213.32 80.2)
		(end 213.32 81.214)
		(width 0.1)
		(layer "B.Cu")
		(net 334)
	)
	(segment
		(start 213.32 81.214)
		(end 213.309 81.225)
		(width 0.1)
		(layer "B.Cu")
		(net 334)
	)
	(segment
		(start 222.4 82.78)
		(end 223.02 82.78)
		(width 0.2)
		(layer "B.Cu")
		(net 334)
	)
	(segment
		(start 219.025 76.44)
		(end 219.025 74.925)
		(width 0.2)
		(layer "B.Cu")
		(net 334)
	)
	(segment
		(start 223.02 82.78)
		(end 223.57 82.23)
		(width 0.2)
		(layer "B.Cu")
		(net 334)
	)
	(segment
		(start 223.57 79.9)
		(end 223 79.9)
		(width 0.2)
		(layer "B.Cu")
		(net 334)
	)
	(segment
		(start 219.025 75.115)
		(end 219.04 75.1)
		(width 0.2)
		(layer "B.Cu")
		(net 334)
	)
	(segment
		(start 214.5 70.17)
		(end 213.27 70.17)
		(width 0.3)
		(layer "B.Cu")
		(net 334)
	)
	(segment
		(start 211.9 80.2)
		(end 211.7 80.4)
		(width 0.2)
		(layer "B.Cu")
		(net 334)
	)
	(segment
		(start 218.5 72.5)
		(end 218.5 74.4)
		(width 0.3)
		(layer "B.Cu")
		(net 334)
	)
	(segment
		(start 212.048 76.73)
		(end 212.048 76.752)
		(width 0.2)
		(layer "B.Cu")
		(net 334)
	)
	(segment
		(start 220.3 80.265)
		(end 220.325 80.24)
		(width 0.2)
		(layer "B.Cu")
		(net 334)
	)
	(segment
		(start 219.025 76.44)
		(end 219.025 75.115)
		(width 0.2)
		(layer "B.Cu")
		(net 334)
	)
	(segment
		(start 223.57 82.23)
		(end 223.57 79.9)
		(width 0.2)
		(layer "B.Cu")
		(net 334)
	)
	(segment
		(start 223 79.9)
		(end 222.7 79.6)
		(width 0.2)
		(layer "B.Cu")
		(net 334)
	)
	(segment
		(start 214.5 70.17)
		(end 216.17 70.17)
		(width 0.3)
		(layer "B.Cu")
		(net 334)
	)
	(segment
		(start 213.071 69.31)
		(end 213.071 69.971)
		(width 0.3)
		(layer "B.Cu")
		(net 334)
	)
	(segment
		(start 213.32 80.2)
		(end 211.95 80.2)
		(width 0.2)
		(layer "B.Cu")
		(net 334)
	)
	(segment
		(start 211.95 80.2)
		(end 211.9 80.2)
		(width 0.2)
		(layer "B.Cu")
		(net 334)
	)
	(segment
		(start 211.9 80.2)
		(end 211.7 80)
		(width 0.2)
		(layer "B.Cu")
		(net 334)
	)
	(segment
		(start 221.9 79.315)
		(end 222.415 79.315)
		(width 0.2)
		(layer "B.Cu")
		(net 334)
	)
	(segment
		(start 211.5 77.3)
		(end 211.5 79.5)
		(width 0.2)
		(layer "B.Cu")
		(net 334)
	)
	(segment
		(start 219.04 74.94)
		(end 218.5 74.4)
		(width 0.2)
		(layer "B.Cu")
		(net 334)
	)
	(segment
		(start 222.415 79.315)
		(end 222.7 79.6)
		(width 0.2)
		(layer "B.Cu")
		(net 334)
	)
	(segment
		(start 211.95 80.2)
		(end 211.7 80.2)
		(width 0.2)
		(layer "B.Cu")
		(net 334)
	)
	(segment
		(start 211.7 80.4)
		(end 211.7 80.2)
		(width 0.2)
		(layer "B.Cu")
		(net 334)
	)
	(segment
		(start 220.3 81.82)
		(end 220.3 81.05)
		(width 0.2)
		(layer "B.Cu")
		(net 334)
	)
	(segment
		(start 219.04 75.1)
		(end 219.04 74.94)
		(width 0.2)
		(layer "B.Cu")
		(net 334)
	)
	(segment
		(start 211.7 80)
		(end 211.7 79.7)
		(width 0.2)
		(layer "B.Cu")
		(net 334)
	)
	(segment
		(start 219.025 74.925)
		(end 218.5 74.4)
		(width 0.2)
		(layer "B.Cu")
		(net 334)
	)
	(segment
		(start 211.7 82)
		(end 211.7 80.4)
		(width 0.2)
		(layer "B.Cu")
		(net 334)
	)
	(segment
		(start 212.048 76.752)
		(end 211.5 77.3)
		(width 0.2)
		(layer "B.Cu")
		(net 334)
	)
	(segment
		(start 218.5 76.8)
		(end 218.2 76.8)
		(width 0.3)
		(layer "In5.Cu")
		(net 334)
	)
	(segment
		(start 220.3 79.95)
		(end 220.3 81.05)
		(width 0.3)
		(layer "In5.Cu")
		(net 334)
	)
	(segment
		(start 218.5 76.5)
		(end 218.5 76.8)
		(width 0.3)
		(layer "In5.Cu")
		(net 334)
	)
	(segment
		(start 220.65 79.6)
		(end 220.3 79.25)
		(width 0.3)
		(layer "In5.Cu")
		(net 334)
	)
	(segment
		(start 220.3 78.6)
		(end 220.3 79.25)
		(width 0.3)
		(layer "In5.Cu")
		(net 334)
	)
	(segment
		(start 218.2 76.8)
		(end 218.5 76.5)
		(width 0.3)
		(layer "In5.Cu")
		(net 334)
	)
	(segment
		(start 218.5 74.4)
		(end 218.5 76.5)
		(width 0.3)
		(layer "In5.Cu")
		(net 334)
	)
	(segment
		(start 220.3 79.6)
		(end 220.3 79.95)
		(width 0.3)
		(layer "In5.Cu")
		(net 334)
	)
	(segment
		(start 216.1 77.3)
		(end 211.5 77.3)
		(width 0.3)
		(layer "In5.Cu")
		(net 334)
	)
	(segment
		(start 220.85 79.6)
		(end 220.3 79.6)
		(width 0.3)
		(layer "In5.Cu")
		(net 334)
	)
	(segment
		(start 220.65 79.6)
		(end 220.3 79.95)
		(width 0.3)
		(layer "In5.Cu")
		(net 334)
	)
	(segment
		(start 220.3 79.25)
		(end 220.3 79.6)
		(width 0.3)
		(layer "In5.Cu")
		(net 334)
	)
	(segment
		(start 216.1 77.3)
		(end 216.6 76.8)
		(width 0.3)
		(layer "In5.Cu")
		(net 334)
	)
	(segment
		(start 220.85 79.6)
		(end 220.65 79.6)
		(width 0.3)
		(layer "In5.Cu")
		(net 334)
	)
	(segment
		(start 218.5 76.8)
		(end 220.3 78.6)
		(width 0.3)
		(layer "In5.Cu")
		(net 334)
	)
	(segment
		(start 222.7 79.6)
		(end 220.85 79.6)
		(width 0.3)
		(layer "In5.Cu")
		(net 334)
	)
	(segment
		(start 218.2 76.8)
		(end 216.6 76.8)
		(width 0.3)
		(layer "In5.Cu")
		(net 334)
	)
	(segment
		(start 221.38 81.85)
		(end 222.37 81.85)
		(width 0.1)
		(layer "B.Cu")
		(net 339)
	)
	(segment
		(start 221.35 81.47)
		(end 221.35 81.82)
		(width 0.1)
		(layer "B.Cu")
		(net 339)
	)
	(segment
		(start 221.35 81.82)
		(end 221.38 81.85)
		(width 0.1)
		(layer "B.Cu")
		(net 339)
	)
	(segment
		(start 222.37 81.85)
		(end 222.4 81.82)
		(width 0.1)
		(layer "B.Cu")
		(net 339)
	)
	(segment
		(start 220.975 80.24)
		(end 220.975 81.095)
		(width 0.1)
		(layer "B.Cu")
		(net 339)
	)
	(segment
		(start 220.975 81.095)
		(end 221.35 81.47)
		(width 0.1)
		(layer "B.Cu")
		(net 339)
	)
	(segment
		(start 139.1 85.3)
		(end 139.1 87.5)
		(width 0.1)
		(layer "F.Cu")
		(net 341)
	)
	(segment
		(start 139.980532 84.8)
		(end 139.6 84.8)
		(width 0.1)
		(layer "F.Cu")
		(net 341)
	)
	(segment
		(start 139.1 87.5)
		(end 138.5 88.1)
		(width 0.1)
		(layer "F.Cu")
		(net 341)
	)
	(segment
		(start 128.65 94.7)
		(end 131.85 97.9)
		(width 0.1)
		(layer "F.Cu")
		(net 341)
	)
	(segment
		(start 102.5 84.85)
		(end 102.9 84.45)
		(width 0.1)
		(layer "F.Cu")
		(net 341)
	)
	(segment
		(start 106 89.55)
		(end 108.2 91.75)
		(width 0.1)
		(layer "F.Cu")
		(net 341)
	)
	(segment
		(start 102.9 83.8)
		(end 102.9 84.45)
		(width 0.1)
		(layer "F.Cu")
		(net 341)
	)
	(segment
		(start 140.630532 84.15)
		(end 139.980532 84.8)
		(width 0.1)
		(layer "F.Cu")
		(net 341)
	)
	(segment
		(start 103.1 83.6)
		(end 106.55 83.6)
		(width 0.1)
		(layer "F.Cu")
		(net 341)
	)
	(segment
		(start 139.6 84.8)
		(end 139.1 85.3)
		(width 0.1)
		(layer "F.Cu")
		(net 341)
	)
	(segment
		(start 106.8 84.65)
		(end 106.8 83.85)
		(width 0.1)
		(layer "F.Cu")
		(net 341)
	)
	(segment
		(start 106 89.55)
		(end 106 85.45)
		(width 0.1)
		(layer "F.Cu")
		(net 341)
	)
	(segment
		(start 102.5 84.85)
		(end 101.9 84.85)
		(width 0.1)
		(layer "F.Cu")
		(net 341)
	)
	(segment
		(start 106.8 83.85)
		(end 106.55 83.6)
		(width 0.1)
		(layer "F.Cu")
		(net 341)
	)
	(segment
		(start 108.2 91.75)
		(end 118.95 91.75)
		(width 0.1)
		(layer "F.Cu")
		(net 341)
	)
	(segment
		(start 128.2 94.7)
		(end 128.65 94.7)
		(width 0.1)
		(layer "F.Cu")
		(net 341)
	)
	(segment
		(start 106 85.45)
		(end 106.8 84.65)
		(width 0.1)
		(layer "F.Cu")
		(net 341)
	)
	(segment
		(start 103.1 83.6)
		(end 102.9 83.8)
		(width 0.1)
		(layer "F.Cu")
		(net 341)
	)
	(via
		(at 102.6 72.65)
		(size 0.45)
		(drill 0.1)
		(layers "F.Cu" "B.Cu")
		(net 341)
	)
	(via
		(at 118.95 91.75)
		(size 0.45)
		(drill 0.1)
		(layers "F.Cu" "B.Cu")
		(net 341)
	)
	(via
		(at 79.15 70.75)
		(size 0.45)
		(drill 0.1)
		(layers "F.Cu" "B.Cu")
		(net 341)
	)
	(via
		(at 128.2 94.7)
		(size 0.45)
		(drill 0.1)
		(layers "F.Cu" "B.Cu")
		(net 341)
	)
	(via
		(at 101.9 84.85)
		(size 0.45)
		(drill 0.1)
		(layers "F.Cu" "B.Cu")
		(net 341)
	)
	(via
		(at 131.85 97.9)
		(size 0.45)
		(drill 0.1)
		(layers "F.Cu" "B.Cu")
		(net 341)
	)
	(via
		(at 138.5 88.1)
		(size 0.45)
		(drill 0.1)
		(layers "F.Cu" "B.Cu")
		(net 341)
	)
	(segment
		(start 77.6 67.8)
		(end 76.48 66.68)
		(width 0.1)
		(layer "B.Cu")
		(net 341)
	)
	(segment
		(start 84.665532 78.945)
		(end 84.665532 77.390532)
		(width 0.1)
		(layer "B.Cu")
		(net 341)
	)
	(segment
		(start 76.48 66.68)
		(end 76.48 66.5)
		(width 0.1)
		(layer "B.Cu")
		(net 341)
	)
	(segment
		(start 80.4 72)
		(end 77.6 69.2)
		(width 0.1)
		(layer "B.Cu")
		(net 341)
	)
	(segment
		(start 77.6 69.2)
		(end 77.6 67.8)
		(width 0.1)
		(layer "B.Cu")
		(net 341)
	)
	(segment
		(start 83 75.725)
		(end 83 73.4)
		(width 0.1)
		(layer "B.Cu")
		(net 341)
	)
	(segment
		(start 83 73.4)
		(end 81.6 72)
		(width 0.1)
		(layer "B.Cu")
		(net 341)
	)
	(segment
		(start 76.48 65.5)
		(end 76.48 66.5)
		(width 0.1)
		(layer "B.Cu")
		(net 341)
	)
	(segment
		(start 84.665532 77.390532)
		(end 83 75.725)
		(width 0.1)
		(layer "B.Cu")
		(net 341)
	)
	(segment
		(start 81.6 72)
		(end 80.4 72)
		(width 0.1)
		(layer "B.Cu")
		(net 341)
	)
	(segment
		(start 79.5 70.4)
		(end 86 70.4)
		(width 0.1)
		(layer "In5.Cu")
		(net 341)
	)
	(segment
		(start 79.15 70.75)
		(end 79.5 70.4)
		(width 0.1)
		(layer "In5.Cu")
		(net 341)
	)
	(segment
		(start 98.25 69.75)
		(end 101.45 69.75)
		(width 0.1)
		(layer "In5.Cu")
		(net 341)
	)
	(segment
		(start 87.45 68.95)
		(end 88.65 68.95)
		(width 0.1)
		(layer "In5.Cu")
		(net 341)
	)
	(segment
		(start 102.7 72.55)
		(end 102.6 72.65)
		(width 0.1)
		(layer "In5.Cu")
		(net 341)
	)
	(segment
		(start 94.65 69.7)
		(end 95.3 69.05)
		(width 0.1)
		(layer "In5.Cu")
		(net 341)
	)
	(segment
		(start 86 70.4)
		(end 87.45 68.95)
		(width 0.1)
		(layer "In5.Cu")
		(net 341)
	)
	(segment
		(start 101.45 69.75)
		(end 102.7 71)
		(width 0.1)
		(layer "In5.Cu")
		(net 341)
	)
	(segment
		(start 88.65 68.95)
		(end 89.4 69.7)
		(width 0.1)
		(layer "In5.Cu")
		(net 341)
	)
	(segment
		(start 121.9 94.7)
		(end 118.95 91.75)
		(width 0.1)
		(layer "In5.Cu")
		(net 341)
	)
	(segment
		(start 102.7 71)
		(end 102.7 72.55)
		(width 0.1)
		(layer "In5.Cu")
		(net 341)
	)
	(segment
		(start 138.5 88.1)
		(end 132.85 93.75)
		(width 0.1)
		(layer "In5.Cu")
		(net 341)
	)
	(segment
		(start 132.85 93.75)
		(end 132.85 96.9)
		(width 0.1)
		(layer "In5.Cu")
		(net 341)
	)
	(segment
		(start 97.55 69.05)
		(end 98.25 69.75)
		(width 0.1)
		(layer "In5.Cu")
		(net 341)
	)
	(segment
		(start 132.85 96.9)
		(end 131.85 97.9)
		(width 0.1)
		(layer "In5.Cu")
		(net 341)
	)
	(segment
		(start 128.2 94.7)
		(end 121.9 94.7)
		(width 0.1)
		(layer "In5.Cu")
		(net 341)
	)
	(segment
		(start 89.4 69.7)
		(end 94.65 69.7)
		(width 0.1)
		(layer "In5.Cu")
		(net 341)
	)
	(segment
		(start 95.3 69.05)
		(end 97.55 69.05)
		(width 0.1)
		(layer "In5.Cu")
		(net 341)
	)
	(segment
		(start 103.8 77.15)
		(end 103.8 75.95)
		(width 0.1)
		(layer "In7.Cu")
		(net 341)
	)
	(segment
		(start 102.7 72)
		(end 102.7 72.55)
		(width 0.1)
		(layer "In7.Cu")
		(net 341)
	)
	(segment
		(start 103.35 71.35)
		(end 102.7 72)
		(width 0.1)
		(layer "In7.Cu")
		(net 341)
	)
	(segment
		(start 105.95 72.85)
		(end 104.45 71.35)
		(width 0.1)
		(layer "In7.Cu")
		(net 341)
	)
	(segment
		(start 104.85 80.45)
		(end 104.85 78.2)
		(width 0.1)
		(layer "In7.Cu")
		(net 341)
	)
	(segment
		(start 101.65 83.65)
		(end 104.85 80.45)
		(width 0.1)
		(layer "In7.Cu")
		(net 341)
	)
	(segment
		(start 103.8 75.95)
		(end 105.95 73.8)
		(width 0.1)
		(layer "In7.Cu")
		(net 341)
	)
	(segment
		(start 103.8 77.15)
		(end 104.85 78.2)
		(width 0.1)
		(layer "In7.Cu")
		(net 341)
	)
	(segment
		(start 101.9 84.85)
		(end 101.65 84.6)
		(width 0.1)
		(layer "In7.Cu")
		(net 341)
	)
	(segment
		(start 105.95 73.8)
		(end 105.95 72.85)
		(width 0.1)
		(layer "In7.Cu")
		(net 341)
	)
	(segment
		(start 103.35 71.35)
		(end 104.45 71.35)
		(width 0.1)
		(layer "In7.Cu")
		(net 341)
	)
	(segment
		(start 101.65 84.6)
		(end 101.65 83.65)
		(width 0.1)
		(layer "In7.Cu")
		(net 341)
	)
	(segment
		(start 102.7 72.55)
		(end 102.6 72.65)
		(width 0.1)
		(layer "In7.Cu")
		(net 341)
	)
	(segment
		(start 81.7 73.6)
		(end 81.2 74.1)
		(width 0.1)
		(layer "F.Cu")
		(net 342)
	)
	(segment
		(start 132.85 83.35)
		(end 132.8 83.3)
		(width 0.1)
		(layer "F.Cu")
		(net 342)
	)
	(segment
		(start 80.5 73.8)
		(end 80.5 72.4)
		(width 0.1)
		(layer "F.Cu")
		(net 342)
	)
	(segment
		(start 132.85 83.35)
		(end 140.730532 83.35)
		(width 0.1)
		(layer "F.Cu")
		(net 342)
	)
	(segment
		(start 80.8 74.1)
		(end 80.5 73.8)
		(width 0.1)
		(layer "F.Cu")
		(net 342)
	)
	(segment
		(start 141.530532 84.15)
		(end 140.730532 83.35)
		(width 0.1)
		(layer "F.Cu")
		(net 342)
	)
	(segment
		(start 80.8 74.1)
		(end 81.2 74.1)
		(width 0.1)
		(layer "F.Cu")
		(net 342)
	)
	(segment
		(start 94.75 67.5)
		(end 95.7 67.5)
		(width 0.1)
		(layer "F.Cu")
		(net 342)
	)
	(segment
		(start 95.7 67.5)
		(end 96.05 67.85)
		(width 0.1)
		(layer "F.Cu")
		(net 342)
	)
	(segment
		(start 93.05 69.2)
		(end 94.75 67.5)
		(width 0.1)
		(layer "F.Cu")
		(net 342)
	)
	(segment
		(start 132.8 83.3)
		(end 132.8 82.15)
		(width 0.1)
		(layer "F.Cu")
		(net 342)
	)
	(segment
		(start 83.7 69.2)
		(end 93.05 69.2)
		(width 0.1)
		(layer "F.Cu")
		(net 342)
	)
	(segment
		(start 80.5 72.4)
		(end 83.7 69.2)
		(width 0.1)
		(layer "F.Cu")
		(net 342)
	)
	(via
		(at 132.8 82.15)
		(size 0.45)
		(drill 0.1)
		(layers "F.Cu" "B.Cu")
		(net 342)
	)
	(via
		(at 81.7 73.6)
		(size 0.45)
		(drill 0.1)
		(layers "F.Cu" "B.Cu")
		(net 342)
	)
	(via
		(at 107.8 64.2)
		(size 0.45)
		(drill 0.1)
		(layers "F.Cu" "B.Cu")
		(net 342)
	)
	(via
		(at 100.8 63.5)
		(size 0.45)
		(drill 0.1)
		(layers "F.Cu" "B.Cu")
		(net 342)
	)
	(via
		(at 96.05 67.85)
		(size 0.45)
		(drill 0.1)
		(layers "F.Cu" "B.Cu")
		(net 342)
	)
	(segment
		(start 133 77.5)
		(end 133 81.95)
		(width 0.1)
		(layer "B.Cu")
		(net 342)
	)
	(segment
		(start 82.3 79.5)
		(end 82.7 79.1)
		(width 0.1)
		(layer "B.Cu")
		(net 342)
	)
	(segment
		(start 133 73.6)
		(end 133 75.7)
		(width 0.1)
		(layer "B.Cu")
		(net 342)
	)
	(segment
		(start 133 75.7)
		(end 132.8 75.9)
		(width 0.1)
		(layer "B.Cu")
		(net 342)
	)
	(segment
		(start 132.1 70.5)
		(end 132.1 72.7)
		(width 0.1)
		(layer "B.Cu")
		(net 342)
	)
	(segment
		(start 79.585532 78.945)
		(end 80.140532 79.5)
		(width 0.1)
		(layer "B.Cu")
		(net 342)
	)
	(segment
		(start 80.140532 79.5)
		(end 82.3 79.5)
		(width 0.1)
		(layer "B.Cu")
		(net 342)
	)
	(segment
		(start 125.8 64.2)
		(end 132.1 70.5)
		(width 0.1)
		(layer "B.Cu")
		(net 342)
	)
	(segment
		(start 132.8 77.3)
		(end 133 77.5)
		(width 0.1)
		(layer "B.Cu")
		(net 342)
	)
	(segment
		(start 82.7 74.6)
		(end 81.7 73.6)
		(width 0.1)
		(layer "B.Cu")
		(net 342)
	)
	(segment
		(start 107.8 64.2)
		(end 125.8 64.2)
		(width 0.1)
		(layer "B.Cu")
		(net 342)
	)
	(segment
		(start 133 81.95)
		(end 132.8 82.15)
		(width 0.1)
		(layer "B.Cu")
		(net 342)
	)
	(segment
		(start 132.1 72.7)
		(end 133 73.6)
		(width 0.1)
		(layer "B.Cu")
		(net 342)
	)
	(segment
		(start 132.8 75.9)
		(end 132.8 77.3)
		(width 0.1)
		(layer "B.Cu")
		(net 342)
	)
	(segment
		(start 82.7 79.1)
		(end 82.7 74.6)
		(width 0.1)
		(layer "B.Cu")
		(net 342)
	)
	(segment
		(start 106 63.5)
		(end 100.8 63.5)
		(width 0.1)
		(layer "In5.Cu")
		(net 342)
	)
	(segment
		(start 107.8 64.2)
		(end 106.7 64.2)
		(width 0.1)
		(layer "In5.Cu")
		(net 342)
	)
	(segment
		(start 106.7 64.2)
		(end 106 63.5)
		(width 0.1)
		(layer "In5.Cu")
		(net 342)
	)
	(segment
		(start 96.05 67.85)
		(end 96.45 67.85)
		(width 0.1)
		(layer "In7.Cu")
		(net 342)
	)
	(segment
		(start 96.45 67.85)
		(end 100.8 63.5)
		(width 0.1)
		(layer "In7.Cu")
		(net 342)
	)
	(segment
		(start 218.755632 92.0335)
		(end 218.57187 92.0335)
		(width 0.19)
		(layer "F.Cu")
		(net 344)
	)
	(segment
		(start 218.57187 92.0335)
		(end 218.015 91.47663)
		(width 0.19)
		(layer "F.Cu")
		(net 344)
	)
	(segment
		(start 216.814633 90.370856)
		(end 216.364632 90.370856)
		(width 0.19)
		(layer "F.Cu")
		(net 344)
	)
	(segment
		(start 219.059132 92.337)
		(end 218.755632 92.0335)
		(width 0.19)
		(layer "F.Cu")
		(net 344)
	)
	(segment
		(start 217.695226 90.356856)
		(end 216.828633 90.356856)
		(width 0.19)
		(layer "F.Cu")
		(net 344)
	)
	(segment
		(start 216.828633 90.356856)
		(end 216.814633 90.370856)
		(width 0.19)
		(layer "F.Cu")
		(net 344)
	)
	(segment
		(start 219.084132 92.337)
		(end 219.059132 92.337)
		(width 0.19)
		(layer "F.Cu")
		(net 344)
	)
	(segment
		(start 218.015 91.47663)
		(end 218.015 90.67663)
		(width 0.19)
		(layer "F.Cu")
		(net 344)
	)
	(segment
		(start 218.015 90.67663)
		(end 217.695226 90.356856)
		(width 0.19)
		(layer "F.Cu")
		(net 344)
	)
	(segment
		(start 222.96463 92.097)
		(end 222.266633 92.097)
		(width 0.19)
		(layer "F.Cu")
		(net 345)
	)
	(segment
		(start 222.266633 92.097)
		(end 222.201633 92.162)
		(width 0.19)
		(layer "F.Cu")
		(net 345)
	)
	(segment
		(start 221.789132 92.162)
		(end 221.017132 92.162)
		(width 0.19)
		(layer "F.Cu")
		(net 345)
	)
	(segment
		(start 223.6 90.9)
		(end 223.485 91.015)
		(width 0.19)
		(layer "F.Cu")
		(net 345)
	)
	(segment
		(start 221.017132 92.162)
		(end 220.219132 92.162)
		(width 0.19)
		(layer "F.Cu")
		(net 345)
	)
	(segment
		(start 223.485 91.57663)
		(end 222.96463 92.097)
		(width 0.19)
		(layer "F.Cu")
		(net 345)
	)
	(segment
		(start 230.430532 87.385)
		(end 230.495532 87.32)
		(width 0.19)
		(layer "F.Cu")
		(net 345)
	)
	(segment
		(start 222.201633 92.162)
		(end 221.789132 92.162)
		(width 0.19)
		(layer "F.Cu")
		(net 345)
	)
	(segment
		(start 230.430532 88.0725)
		(end 230.430532 87.385)
		(width 0.19)
		(layer "F.Cu")
		(net 345)
	)
	(segment
		(start 220.219132 92.162)
		(end 220.044132 92.337)
		(width 0.19)
		(layer "F.Cu")
		(net 345)
	)
	(segment
		(start 223.485 91.015)
		(end 223.485 91.57663)
		(width 0.19)
		(layer "F.Cu")
		(net 345)
	)
	(segment
		(start 230.495532 87.32)
		(end 230.495532 86.865)
		(width 0.19)
		(layer "F.Cu")
		(net 345)
	)
	(segment
		(start 230.495532 86.865)
		(end 230.380532 86.75)
		(width 0.19)
		(layer "F.Cu")
		(net 345)
	)
	(via
		(at 230.380532 86.75)
		(size 0.45)
		(drill 0.1)
		(layers "F.Cu" "B.Cu")
		(net 345)
	)
	(via
		(at 223.6 90.9)
		(size 0.45)
		(drill 0.1)
		(layers "F.Cu" "B.Cu")
		(net 345)
	)
	(segment
		(start 221.9375 86.456956)
		(end 221.9375 87.743044)
		(width 0.15)
		(layer "In7.Cu")
		(net 345)
	)
	(segment
		(start 225.569413 85.398728)
		(end 225.658185 85.398728)
		(width 0.15)
		(layer "In7.Cu")
		(net 345)
	)
	(segment
		(start 225.308185 85.1375)
		(end 223.256956 85.1375)
		(width 0.15)
		(layer "In7.Cu")
		(net 345)
	)
	(segment
		(start 230.543032 86.5875)
		(end 230.380532 86.75)
		(width 0.15)
		(layer "In7.Cu")
		(net 345)
	)
	(segment
		(start 225.919413 85.1375)
		(end 230.013044 85.1375)
		(width 0.15)
		(layer "In7.Cu")
		(net 345)
	)
	(segment
		(start 230.013044 85.1375)
		(end 230.543032 85.667488)
		(width 0.15)
		(layer "In7.Cu")
		(net 345)
	)
	(segment
		(start 221.9375 87.743044)
		(end 223.4375 89.243044)
		(width 0.15)
		(layer "In7.Cu")
		(net 345)
	)
	(segment
		(start 223.4375 90.7375)
		(end 223.6 90.9)
		(width 0.15)
		(layer "In7.Cu")
		(net 345)
	)
	(segment
		(start 230.543032 85.667488)
		(end 230.543032 86.5875)
		(width 0.15)
		(layer "In7.Cu")
		(net 345)
	)
	(segment
		(start 223.256956 85.1375)
		(end 221.9375 86.456956)
		(width 0.15)
		(layer "In7.Cu")
		(net 345)
	)
	(segment
		(start 223.4375 89.243044)
		(end 223.4375 90.7375)
		(width 0.15)
		(layer "In7.Cu")
		(net 345)
	)
	(arc
		(start 225.788799 85.268114)
		(mid 225.827055 85.175756)
		(end 225.919413 85.1375)
		(width 0.15)
		(layer "In7.Cu")
		(net 345)
	)
	(arc
		(start 225.658185 85.398728)
		(mid 225.750543 85.360472)
		(end 225.788799 85.268114)
		(width 0.15)
		(layer "In7.Cu")
		(net 345)
	)
	(arc
		(start 225.308185 85.1375)
		(mid 225.400543 85.175756)
		(end 225.438799 85.268114)
		(width 0.15)
		(layer "In7.Cu")
		(net 345)
	)
	(arc
		(start 225.438799 85.268114)
		(mid 225.477055 85.360472)
		(end 225.569413 85.398728)
		(width 0.15)
		(layer "In7.Cu")
		(net 345)
	)
	(segment
		(start 222.201633 87.012)
		(end 222.266633 87.077)
		(width 0.19)
		(layer "F.Cu")
		(net 347)
	)
	(segment
		(start 234.865532 91.631251)
		(end 234.865532 91.885)
		(width 0.19)
		(layer "F.Cu")
		(net 347)
	)
	(segment
		(start 234.930532 91.566251)
		(end 234.865532 91.631251)
		(width 0.19)
		(layer "F.Cu")
		(net 347)
	)
	(segment
		(start 221.789132 87.012)
		(end 222.201633 87.012)
		(width 0.19)
		(layer "F.Cu")
		(net 347)
	)
	(segment
		(start 234.865532 91.885)
		(end 234.980532 92)
		(width 0.19)
		(layer "F.Cu")
		(net 347)
	)
	(segment
		(start 221.017132 87.012)
		(end 220.306132 87.012)
		(width 0.19)
		(layer "F.Cu")
		(net 347)
	)
	(segment
		(start 221.789132 87.012)
		(end 221.017132 87.012)
		(width 0.19)
		(layer "F.Cu")
		(net 347)
	)
	(segment
		(start 222.785 87.077)
		(end 222.9 86.962)
		(width 0.19)
		(layer "F.Cu")
		(net 347)
	)
	(segment
		(start 222.266633 87.077)
		(end 222.785 87.077)
		(width 0.19)
		(layer "F.Cu")
		(net 347)
	)
	(segment
		(start 220.306132 87.012)
		(end 220.044132 86.75)
		(width 0.19)
		(layer "F.Cu")
		(net 347)
	)
	(segment
		(start 234.930532 90.3475)
		(end 234.930532 91.566251)
		(width 0.19)
		(layer "F.Cu")
		(net 347)
	)
	(via
		(at 222.9 86.962)
		(size 0.45)
		(drill 0.1)
		(layers "F.Cu" "B.Cu")
		(net 347)
	)
	(via
		(at 234.980532 92)
		(size 0.45)
		(drill 0.1)
		(layers "F.Cu" "B.Cu")
		(net 347)
	)
	(segment
		(start 225.304602 87.462)
		(end 225.304602 87.021286)
		(width 0.15)
		(layer "In7.Cu")
		(net 347)
	)
	(segment
		(start 234.980532 92)
		(end 234.818032 91.8375)
		(width 0.15)
		(layer "In7.Cu")
		(net 347)
	)
	(segment
		(start 234.818032 91.8375)
		(end 234.818032 88.983576)
		(width 0.15)
		(layer "In7.Cu")
		(net 347)
	)
	(segment
		(start 222.9 86.962)
		(end 223.0625 87.1245)
		(width 0.15)
		(layer "In7.Cu")
		(net 347)
	)
	(segment
		(start 225.682816 86.643072)
		(end 225.951388 86.643072)
		(width 0.15)
		(layer "In7.Cu")
		(net 347)
	)
	(segment
		(start 223.0625 87.1245)
		(end 224.392102 87.1245)
		(width 0.15)
		(layer "In7.Cu")
		(net 347)
	)
	(segment
		(start 234.818032 88.983576)
		(end 233.496956 87.6625)
		(width 0.15)
		(layer "In7.Cu")
		(net 347)
	)
	(segment
		(start 224.792102 87.5245)
		(end 225.242102 87.5245)
		(width 0.15)
		(layer "In7.Cu")
		(net 347)
	)
	(segment
		(start 226.432816 87.1245)
		(end 227.418956 87.1245)
		(width 0.15)
		(layer "In7.Cu")
		(net 347)
	)
	(segment
		(start 233.496956 87.6625)
		(end 227.956956 87.6625)
		(width 0.15)
		(layer "In7.Cu")
		(net 347)
	)
	(segment
		(start 227.418956 87.1245)
		(end 227.956956 87.6625)
		(width 0.15)
		(layer "In7.Cu")
		(net 347)
	)
	(arc
		(start 225.242102 87.5245)
		(mid 225.286296 87.506194)
		(end 225.304602 87.462)
		(width 0.15)
		(layer "In7.Cu")
		(net 347)
	)
	(arc
		(start 225.951388 86.643072)
		(mid 226.218826 86.753848)
		(end 226.329602 87.021286)
		(width 0.15)
		(layer "In7.Cu")
		(net 347)
	)
	(arc
		(start 224.729602 87.462)
		(mid 224.747908 87.506194)
		(end 224.792102 87.5245)
		(width 0.15)
		(layer "In7.Cu")
		(net 347)
	)
	(arc
		(start 225.304602 87.021286)
		(mid 225.415378 86.753848)
		(end 225.682816 86.643072)
		(width 0.15)
		(layer "In7.Cu")
		(net 347)
	)
	(arc
		(start 226.329602 87.021286)
		(mid 226.359833 87.094269)
		(end 226.432816 87.1245)
		(width 0.15)
		(layer "In7.Cu")
		(net 347)
	)
	(arc
		(start 224.392102 87.1245)
		(mid 224.630751 87.223351)
		(end 224.729602 87.462)
		(width 0.15)
		(layer "In7.Cu")
		(net 347)
	)
	(segment
		(start 219.084132 86.75)
		(end 219.059132 86.75)
		(width 0.19)
		(layer "F.Cu")
		(net 354)
	)
	(segment
		(start 216.814633 88.772856)
		(end 216.364632 88.772856)
		(width 0.19)
		(layer "F.Cu")
		(net 354)
	)
	(segment
		(start 218.015 87.52337)
		(end 218.015 88.37337)
		(width 0.19)
		(layer "F.Cu")
		(net 354)
	)
	(segment
		(start 218.015 88.37337)
		(end 217.600514 88.787856)
		(width 0.19)
		(layer "F.Cu")
		(net 354)
	)
	(segment
		(start 218.744132 87.065)
		(end 218.47337 87.065)
		(width 0.19)
		(layer "F.Cu")
		(net 354)
	)
	(segment
		(start 218.47337 87.065)
		(end 218.015 87.52337)
		(width 0.19)
		(layer "F.Cu")
		(net 354)
	)
	(segment
		(start 217.600514 88.787856)
		(end 216.829633 88.787856)
		(width 0.19)
		(layer "F.Cu")
		(net 354)
	)
	(segment
		(start 216.829633 88.787856)
		(end 216.814633 88.772856)
		(width 0.19)
		(layer "F.Cu")
		(net 354)
	)
	(segment
		(start 219.059132 86.75)
		(end 218.744132 87.065)
		(width 0.19)
		(layer "F.Cu")
		(net 354)
	)
	(segment
		(start 84.25 72.25)
		(end 81.7 72.25)
		(width 0.1)
		(layer "F.Cu")
		(net 356)
	)
	(segment
		(start 81.7 72.25)
		(end 81.3 72.65)
		(width 0.1)
		(layer "F.Cu")
		(net 356)
	)
	(segment
		(start 187.3 59.78)
		(end 187.25 59.73)
		(width 0.15)
		(layer "F.Cu")
		(net 356)
	)
	(segment
		(start 91.35 75.9)
		(end 86.35 75.9)
		(width 0.1)
		(layer "F.Cu")
		(net 356)
	)
	(segment
		(start 188.952 59.8)
		(end 193.049999 59.8)
		(width 0.1)
		(layer "F.Cu")
		(net 356)
	)
	(segment
		(start 91.730532 76.280532)
		(end 91.35 75.9)
		(width 0.1)
		(layer "F.Cu")
		(net 356)
	)
	(segment
		(start 187.3 60.651)
		(end 187.3 59.78)
		(width 0.15)
		(layer "F.Cu")
		(net 356)
	)
	(segment
		(start 177.15 59.1)
		(end 185.9 59.1)
		(width 0.15)
		(layer "F.Cu")
		(net 356)
	)
	(segment
		(start 176.47 58.91)
		(end 176.96 58.91)
		(width 0.15)
		(layer "F.Cu")
		(net 356)
	)
	(segment
		(start 186.53 59.73)
		(end 187.25 59.73)
		(width 0.15)
		(layer "F.Cu")
		(net 356)
	)
	(segment
		(start 187.32 59.8)
		(end 187.25 59.73)
		(width 0.15)
		(layer "F.Cu")
		(net 356)
	)
	(segment
		(start 151.1 67.15)
		(end 148.8 64.85)
		(width 0.1)
		(layer "F.Cu")
		(net 356)
	)
	(segment
		(start 170.22 59.05)
		(end 169.6 59.05)
		(width 0.1)
		(layer "F.Cu")
		(net 356)
	)
	(segment
		(start 86.35 75.9)
		(end 85.925 75.475)
		(width 0.1)
		(layer "F.Cu")
		(net 356)
	)
	(segment
		(start 169.6 59.05)
		(end 161.5 67.15)
		(width 0.1)
		(layer "F.Cu")
		(net 356)
	)
	(segment
		(start 148.8 64.85)
		(end 148.8 62.1)
		(width 0.1)
		(layer "F.Cu")
		(net 356)
	)
	(segment
		(start 85.925 74.925)
		(end 85.1 74.1)
		(width 0.1)
		(layer "F.Cu")
		(net 356)
	)
	(segment
		(start 185.9 59.1)
		(end 186.53 59.73)
		(width 0.15)
		(layer "F.Cu")
		(net 356)
	)
	(segment
		(start 176.96 58.91)
		(end 177.15 59.1)
		(width 0.15)
		(layer "F.Cu")
		(net 356)
	)
	(segment
		(start 91.730532 76.65)
		(end 91.730532 76.280532)
		(width 0.1)
		(layer "F.Cu")
		(net 356)
	)
	(segment
		(start 85.1 74.1)
		(end 85.1 73.1)
		(width 0.1)
		(layer "F.Cu")
		(net 356)
	)
	(segment
		(start 85.925 75.475)
		(end 85.925 74.925)
		(width 0.1)
		(layer "F.Cu")
		(net 356)
	)
	(segment
		(start 188.952 59.8)
		(end 187.32 59.8)
		(width 0.15)
		(layer "F.Cu")
		(net 356)
	)
	(segment
		(start 85.1 73.1)
		(end 84.25 72.25)
		(width 0.1)
		(layer "F.Cu")
		(net 356)
	)
	(segment
		(start 161.5 67.15)
		(end 151.1 67.15)
		(width 0.1)
		(layer "F.Cu")
		(net 356)
	)
	(via
		(at 81.3 72.65)
		(size 0.45)
		(drill 0.1)
		(layers "F.Cu" "B.Cu")
		(net 356)
	)
	(via
		(at 148.8 62.1)
		(size 0.45)
		(drill 0.1)
		(layers "F.Cu" "B.Cu")
		(net 356)
	)
	(via
		(at 176.47 58.91)
		(size 0.45)
		(drill 0.1)
		(layers "F.Cu" "B.Cu")
		(net 356)
	)
	(via
		(at 74.505532 106.885)
		(size 0.45)
		(drill 0.1)
		(layers "F.Cu" "B.Cu")
		(net 356)
	)
	(via
		(at 170.22 59.05)
		(size 0.45)
		(drill 0.1)
		(layers "F.Cu" "B.Cu")
		(net 356)
	)
	(segment
		(start 170.22 59.05)
		(end 170.62 58.65)
		(width 0.1)
		(layer "B.Cu")
		(net 356)
	)
	(segment
		(start 170.62 58.65)
		(end 176.21 58.65)
		(width 0.1)
		(layer "B.Cu")
		(net 356)
	)
	(segment
		(start 176.21 58.65)
		(end 176.47 58.91)
		(width 0.1)
		(layer "B.Cu")
		(net 356)
	)
	(segment
		(start 74.1 95.9)
		(end 74.475 96.275)
		(width 0.1)
		(layer "In5.Cu")
		(net 356)
	)
	(segment
		(start 74.95 99.375)
		(end 74.95 102.35)
		(width 0.1)
		(layer "In5.Cu")
		(net 356)
	)
	(segment
		(start 74.925 96.275)
		(end 75.175 96.525)
		(width 0.1)
		(layer "In5.Cu")
		(net 356)
	)
	(segment
		(start 73.8 78.95)
		(end 73.8 83.55)
		(width 0.1)
		(layer "In5.Cu")
		(net 356)
	)
	(segment
		(start 75.175 96.525)
		(end 75.175 99.15)
		(width 0.1)
		(layer "In5.Cu")
		(net 356)
	)
	(segment
		(start 74.1 83.85)
		(end 74.1 95.9)
		(width 0.1)
		(layer "In5.Cu")
		(net 356)
	)
	(segment
		(start 74.95 102.35)
		(end 74.7875 102.5125)
		(width 0.1)
		(layer "In5.Cu")
		(net 356)
	)
	(segment
		(start 81.3 77.05)
		(end 79.9 78.45)
		(width 0.1)
		(layer "In5.Cu")
		(net 356)
	)
	(segment
		(start 74.7875 102.5125)
		(end 74.3125 102.5125)
		(width 0.1)
		(layer "In5.Cu")
		(net 356)
	)
	(segment
		(start 79.9 78.45)
		(end 74.3 78.45)
		(width 0.1)
		(layer "In5.Cu")
		(net 356)
	)
	(segment
		(start 73.925 102.9)
		(end 73.925 106.304468)
		(width 0.1)
		(layer "In5.Cu")
		(net 356)
	)
	(segment
		(start 74.3 78.45)
		(end 73.8 78.95)
		(width 0.1)
		(layer "In5.Cu")
		(net 356)
	)
	(segment
		(start 73.925 106.304468)
		(end 74.505532 106.885)
		(width 0.1)
		(layer "In5.Cu")
		(net 356)
	)
	(segment
		(start 81.3 72.65)
		(end 81.3 77.05)
		(width 0.1)
		(layer "In5.Cu")
		(net 356)
	)
	(segment
		(start 74.3125 102.5125)
		(end 73.925 102.9)
		(width 0.1)
		(layer "In5.Cu")
		(net 356)
	)
	(segment
		(start 74.475 96.275)
		(end 74.925 96.275)
		(width 0.1)
		(layer "In5.Cu")
		(net 356)
	)
	(segment
		(start 73.8 83.55)
		(end 74.1 83.85)
		(width 0.1)
		(layer "In5.Cu")
		(net 356)
	)
	(segment
		(start 75.175 99.15)
		(end 74.95 99.375)
		(width 0.1)
		(layer "In5.Cu")
		(net 356)
	)
	(segment
		(start 88.75 71.1)
		(end 90.3 69.55)
		(width 0.1)
		(layer "In7.Cu")
		(net 356)
	)
	(segment
		(start 98.5 67.18)
		(end 109.44 56.24)
		(width 0.1)
		(layer "In7.Cu")
		(net 356)
	)
	(segment
		(start 90.3 69.55)
		(end 92.72 69.55)
		(width 0.1)
		(layer "In7.Cu")
		(net 356)
	)
	(segment
		(start 92.72 69.55)
		(end 93.4 68.87)
		(width 0.1)
		(layer "In7.Cu")
		(net 356)
	)
	(segment
		(start 81.3 72.65)
		(end 82.85 71.1)
		(width 0.1)
		(layer "In7.Cu")
		(net 356)
	)
	(segment
		(start 96.24 68.87)
		(end 97.93 67.18)
		(width 0.1)
		(layer "In7.Cu")
		(net 356)
	)
	(segment
		(start 93.4 68.87)
		(end 96.24 68.87)
		(width 0.1)
		(layer "In7.Cu")
		(net 356)
	)
	(segment
		(start 124.32 55.92)
		(end 141.92 55.92)
		(width 0.1)
		(layer "In7.Cu")
		(net 356)
	)
	(segment
		(start 148.1 62.1)
		(end 148.8 62.1)
		(width 0.1)
		(layer "In7.Cu")
		(net 356)
	)
	(segment
		(start 141.92 55.92)
		(end 148.1 62.1)
		(width 0.1)
		(layer "In7.Cu")
		(net 356)
	)
	(segment
		(start 97.93 67.18)
		(end 98.5 67.18)
		(width 0.1)
		(layer "In7.Cu")
		(net 356)
	)
	(segment
		(start 109.44 56.24)
		(end 124 56.24)
		(width 0.1)
		(layer "In7.Cu")
		(net 356)
	)
	(segment
		(start 82.85 71.1)
		(end 88.75 71.1)
		(width 0.1)
		(layer "In7.Cu")
		(net 356)
	)
	(segment
		(start 124 56.24)
		(end 124.32 55.92)
		(width 0.1)
		(layer "In7.Cu")
		(net 356)
	)
	(via
		(at 72 128.45)
		(size 0.45)
		(drill 0.1)
		(layers "F.Cu" "B.Cu")
		(net 360)
	)
	(segment
		(start 71.975 128.475)
		(end 72 128.45)
		(width 0.1)
		(layer "B.Cu")
		(net 360)
	)
	(segment
		(start 71.965532 128.475)
		(end 71.975 128.475)
		(width 0.1)
		(layer "B.Cu")
		(net 360)
	)
	(segment
		(start 223 90.9)
		(end 223.115 91.015)
		(width 0.19)
		(layer "F.Cu")
		(net 361)
	)
	(segment
		(start 230.930532 87.385)
		(end 230.865532 87.32)
		(width 0.19)
		(layer "F.Cu")
		(net 361)
	)
	(segment
		(start 223.115 91.42337)
		(end 222.81137 91.727)
		(width 0.19)
		(layer "F.Cu")
		(net 361)
	)
	(segment
		(start 221.017132 91.662)
		(end 220.346132 91.662)
		(width 0.19)
		(layer "F.Cu")
		(net 361)
	)
	(segment
		(start 222.201633 91.662)
		(end 221.789132 91.662)
		(width 0.19)
		(layer "F.Cu")
		(net 361)
	)
	(segment
		(start 222.266633 91.727)
		(end 222.201633 91.662)
		(width 0.19)
		(layer "F.Cu")
		(net 361)
	)
	(segment
		(start 230.930532 88.0725)
		(end 230.930532 87.385)
		(width 0.19)
		(layer "F.Cu")
		(net 361)
	)
	(segment
		(start 230.865532 86.865)
		(end 230.980532 86.75)
		(width 0.19)
		(layer "F.Cu")
		(net 361)
	)
	(segment
		(start 230.865532 87.32)
		(end 230.865532 86.865)
		(width 0.19)
		(layer "F.Cu")
		(net 361)
	)
	(segment
		(start 221.789132 91.662)
		(end 221.017132 91.662)
		(width 0.19)
		(layer "F.Cu")
		(net 361)
	)
	(segment
		(start 222.81137 91.727)
		(end 222.266633 91.727)
		(width 0.19)
		(layer "F.Cu")
		(net 361)
	)
	(segment
		(start 223.115 91.015)
		(end 223.115 91.42337)
		(width 0.19)
		(layer "F.Cu")
		(net 361)
	)
	(segment
		(start 220.346132 91.662)
		(end 220.044132 91.36)
		(width 0.19)
		(layer "F.Cu")
		(net 361)
	)
	(via
		(at 230.980532 86.75)
		(size 0.45)
		(drill 0.1)
		(layers "F.Cu" "B.Cu")
		(net 361)
	)
	(via
		(at 223 90.9)
		(size 0.45)
		(drill 0.1)
		(layers "F.Cu" "B.Cu")
		(net 361)
	)
	(segment
		(start 223.143044 84.8625)
		(end 221.6625 86.343044)
		(width 0.15)
		(layer "In7.Cu")
		(net 361)
	)
	(segment
		(start 230.818032 85.553576)
		(end 230.126956 84.8625)
		(width 0.15)
		(layer "In7.Cu")
		(net 361)
	)
	(segment
		(start 221.6625 87.856956)
		(end 223.1625 89.356956)
		(width 0.15)
		(layer "In7.Cu")
		(net 361)
	)
	(segment
		(start 230.126956 84.8625)
		(end 223.143044 84.8625)
		(width 0.15)
		(layer "In7.Cu")
		(net 361)
	)
	(segment
		(start 230.980532 86.75)
		(end 230.818032 86.5875)
		(width 0.15)
		(layer "In7.Cu")
		(net 361)
	)
	(segment
		(start 223.1625 90.7375)
		(end 223 90.9)
		(width 0.15)
		(layer "In7.Cu")
		(net 361)
	)
	(segment
		(start 230.818032 86.5875)
		(end 230.818032 85.553576)
		(width 0.15)
		(layer "In7.Cu")
		(net 361)
	)
	(segment
		(start 223.1625 89.356956)
		(end 223.1625 90.7375)
		(width 0.15)
		(layer "In7.Cu")
		(net 361)
	)
	(segment
		(start 221.6625 86.343044)
		(end 221.6625 87.856956)
		(width 0.15)
		(layer "In7.Cu")
		(net 361)
	)
	(segment
		(start 93.1 74.1)
		(end 93.730532 74.730532)
		(width 0.1)
		(layer "F.Cu")
		(net 362)
	)
	(segment
		(start 93.730532 74.730532)
		(end 93.730532 75.15)
		(width 0.1)
		(layer "F.Cu")
		(net 362)
	)
	(segment
		(start 93.1 72.7)
		(end 93.1 74.1)
		(width 0.1)
		(layer "F.Cu")
		(net 362)
	)
	(via
		(at 75.775532 80.215)
		(size 0.45)
		(drill 0.1)
		(layers "F.Cu" "B.Cu")
		(net 362)
	)
	(via
		(at 93.1 72.7)
		(size 0.45)
		(drill 0.1)
		(layers "F.Cu" "B.Cu")
		(net 362)
	)
	(segment
		(start 76.390532 79.6)
		(end 80.8 79.6)
		(width 0.1)
		(layer "In5.Cu")
		(net 362)
	)
	(segment
		(start 85.9 74.5)
		(end 91.6 74.5)
		(width 0.1)
		(layer "In5.Cu")
		(net 362)
	)
	(segment
		(start 92.2 73.3)
		(end 92.8 72.7)
		(width 0.1)
		(layer "In5.Cu")
		(net 362)
	)
	(segment
		(start 91.6 74.5)
		(end 92.2 73.9)
		(width 0.1)
		(layer "In5.Cu")
		(net 362)
	)
	(segment
		(start 92.2 73.9)
		(end 92.2 73.3)
		(width 0.1)
		(layer "In5.Cu")
		(net 362)
	)
	(segment
		(start 75.775532 80.215)
		(end 76.390532 79.6)
		(width 0.1)
		(layer "In5.Cu")
		(net 362)
	)
	(segment
		(start 92.8 72.7)
		(end 93.1 72.7)
		(width 0.1)
		(layer "In5.Cu")
		(net 362)
	)
	(segment
		(start 80.8 79.6)
		(end 85.9 74.5)
		(width 0.1)
		(layer "In5.Cu")
		(net 362)
	)
	(segment
		(start 129.5 111.6)
		(end 129.9 112)
		(width 0.1)
		(layer "F.Cu")
		(net 364)
	)
	(segment
		(start 133 112)
		(end 133.6 112.6)
		(width 0.1)
		(layer "F.Cu")
		(net 364)
	)
	(segment
		(start 128.3 111.6)
		(end 129.5 111.6)
		(width 0.1)
		(layer "F.Cu")
		(net 364)
	)
	(segment
		(start 129.9 112)
		(end 133 112)
		(width 0.1)
		(layer "F.Cu")
		(net 364)
	)
	(via
		(at 75.8 101.8)
		(size 0.45)
		(drill 0.1)
		(layers "F.Cu" "B.Cu")
		(net 364)
	)
	(via
		(at 128.3 111.6)
		(size 0.45)
		(drill 0.1)
		(layers "F.Cu" "B.Cu")
		(free yes)
		(net 364)
	)
	(via
		(at 138.830532 84.15)
		(size 0.45)
		(drill 0.1)
		(layers "F.Cu" "B.Cu")
		(net 364)
	)
	(via
		(at 133.6 112.6)
		(size 0.45)
		(drill 0.1)
		(layers "F.Cu" "B.Cu")
		(net 364)
	)
	(segment
		(start 126.8 111.2)
		(end 113.565686 111.2)
		(width 0.1)
		(layer "In5.Cu")
		(net 364)
	)
	(segment
		(start 138.830532 84.15)
		(end 138.2 84.780532)
		(width 0.1)
		(layer "In5.Cu")
		(net 364)
	)
	(segment
		(start 86.4 120.35)
		(end 79.3 120.35)
		(width 0.1)
		(layer "In5.Cu")
		(net 364)
	)
	(segment
		(start 113.565686 111.2)
		(end 112.533912 110.168226)
		(width 0.1)
		(layer "In5.Cu")
		(net 364)
	)
	(segment
		(start 133.6 104)
		(end 133.6 112.6)
		(width 0.1)
		(layer "In5.Cu")
		(net 364)
	)
	(segment
		(start 132 93.4)
		(end 132 96.4)
		(width 0.1)
		(layer "In5.Cu")
		(net 364)
	)
	(segment
		(start 131.15 97.25)
		(end 131.15 101.55)
		(width 0.1)
		(layer "In5.Cu")
		(net 364)
	)
	(segment
		(start 110.434315 108.799997)
		(end 106.5 108.799997)
		(width 0.1)
		(layer "In5.Cu")
		(net 364)
	)
	(segment
		(start 104.6 110.699997)
		(end 104.6 115.565682)
		(width 0.1)
		(layer "In5.Cu")
		(net 364)
	)
	(segment
		(start 138.2 84.780532)
		(end 138.2 87.2)
		(width 0.1)
		(layer "In5.Cu")
		(net 364)
	)
	(segment
		(start 111.802544 110.168226)
		(end 110.434315 108.799997)
		(width 0.1)
		(layer "In5.Cu")
		(net 364)
	)
	(segment
		(start 112.533912 110.168226)
		(end 111.802544 110.168226)
		(width 0.1)
		(layer "In5.Cu")
		(net 364)
	)
	(segment
		(start 131.15 101.55)
		(end 133.6 104)
		(width 0.1)
		(layer "In5.Cu")
		(net 364)
	)
	(segment
		(start 100.365685 119.799997)
		(end 86.950003 119.799997)
		(width 0.1)
		(layer "In5.Cu")
		(net 364)
	)
	(segment
		(start 138.2 87.2)
		(end 132 93.4)
		(width 0.1)
		(layer "In5.Cu")
		(net 364)
	)
	(segment
		(start 132 96.4)
		(end 131.15 97.25)
		(width 0.1)
		(layer "In5.Cu")
		(net 364)
	)
	(segment
		(start 86.950003 119.799997)
		(end 86.4 120.35)
		(width 0.1)
		(layer "In5.Cu")
		(net 364)
	)
	(segment
		(start 79.3 120.35)
		(end 78.75 119.8)
		(width 0.1)
		(layer "In5.Cu")
		(net 364)
	)
	(segment
		(start 78.75 119.8)
		(end 78.75 110.5)
		(width 0.1)
		(layer "In5.Cu")
		(net 364)
	)
	(segment
		(start 127.2 111.6)
		(end 126.8 111.2)
		(width 0.1)
		(layer "In5.Cu")
		(net 364)
	)
	(segment
		(start 76.6 108.35)
		(end 76.6 102.6)
		(width 0.1)
		(layer "In5.Cu")
		(net 364)
	)
	(segment
		(start 106.5 108.799997)
		(end 104.6 110.699997)
		(width 0.1)
		(layer "In5.Cu")
		(net 364)
	)
	(segment
		(start 128.3 111.6)
		(end 127.2 111.6)
		(width 0.1)
		(layer "In5.Cu")
		(net 364)
	)
	(segment
		(start 76.6 102.6)
		(end 75.8 101.8)
		(width 0.1)
		(layer "In5.Cu")
		(net 364)
	)
	(segment
		(start 78.75 110.5)
		(end 76.6 108.35)
		(width 0.1)
		(layer "In5.Cu")
		(net 364)
	)
	(segment
		(start 104.6 115.565682)
		(end 100.365685 119.799997)
		(width 0.1)
		(layer "In5.Cu")
		(net 364)
	)
	(segment
		(start 81.55 112.2)
		(end 81.15 112.6)
		(width 0.1)
		(layer "F.Cu")
		(net 368)
	)
	(segment
		(start 75.175 112.225)
		(end 74.7 112.7)
		(width 0.1)
		(layer "F.Cu")
		(net 368)
	)
	(segment
		(start 76.3 111.6)
		(end 76.3 111.9)
		(width 0.1)
		(layer "F.Cu")
		(net 368)
	)
	(segment
		(start 80.85 110.75)
		(end 80.85 111.15)
		(width 0.1)
		(layer "F.Cu")
		(net 368)
	)
	(segment
		(start 74.7 112.7)
		(end 72.75 112.7)
		(width 0.1)
		(layer "F.Cu")
		(net 368)
	)
	(segment
		(start 75.175 112.225)
		(end 75.175 111.675)
		(width 0.1)
		(layer "F.Cu")
		(net 368)
	)
	(segment
		(start 75.175 111.675)
		(end 75.4 111.45)
		(width 0.1)
		(layer "F.Cu")
		(net 368)
	)
	(segment
		(start 76.15 111.45)
		(end 76.3 111.6)
		(width 0.1)
		(layer "F.Cu")
		(net 368)
	)
	(segment
		(start 76.3 111.9)
		(end 77 112.6)
		(width 0.1)
		(layer "F.Cu")
		(net 368)
	)
	(segment
		(start 91.030532 72.15)
		(end 91.025 72.15)
		(width 0.1)
		(layer "F.Cu")
		(net 368)
	)
	(segment
		(start 80.85 111.15)
		(end 81.55 111.85)
		(width 0.1)
		(layer "F.Cu")
		(net 368)
	)
	(segment
		(start 75.4 111.45)
		(end 76.15 111.45)
		(width 0.1)
		(layer "F.Cu")
		(net 368)
	)
	(segment
		(start 81.15 112.6)
		(end 77 112.6)
		(width 0.1)
		(layer "F.Cu")
		(net 368)
	)
	(segment
		(start 81.55 111.85)
		(end 81.55 112.2)
		(width 0.1)
		(layer "F.Cu")
		(net 368)
	)
	(via
		(at 72.75 112.7)
		(size 0.45)
		(drill 0.1)
		(layers "F.Cu" "B.Cu")
		(net 368)
	)
	(via
		(at 80.85 110.75)
		(size 0.45)
		(drill 0.1)
		(layers "F.Cu" "B.Cu")
		(net 368)
	)
	(via
		(at 91.025 72.15)
		(size 0.45)
		(drill 0.1)
		(layers "F.Cu" "B.Cu")
		(net 368)
	)
	(segment
		(start 70.3 112.7)
		(end 68.6 111)
		(width 0.1)
		(layer "In5.Cu")
		(net 368)
	)
	(segment
		(start 68.4 85.4)
		(end 68.4 78.365686)
		(width 0.1)
		(layer "In5.Cu")
		(net 368)
	)
	(segment
		(start 72.75 112.7)
		(end 70.3 112.7)
		(width 0.1)
		(layer "In5.Cu")
		(net 368)
	)
	(segment
		(start 87.55 72.6)
		(end 90.575 72.6)
		(width 0.1)
		(layer "In5.Cu")
		(net 368)
	)
	(segment
		(start 80 76.8)
		(end 80 72.6)
		(width 0.1)
		(layer "In5.Cu")
		(net 368)
	)
	(segment
		(start 80.95 71.65)
		(end 86.6 71.65)
		(width 0.1)
		(layer "In5.Cu")
		(net 368)
	)
	(segment
		(start 80 72.6)
		(end 80.95 71.65)
		(width 0.1)
		(layer "In5.Cu")
		(net 368)
	)
	(segment
		(start 68.945686 77.82)
		(end 78.98 77.82)
		(width 0.1)
		(layer "In5.Cu")
		(net 368)
	)
	(segment
		(start 78.98 77.82)
		(end 80 76.8)
		(width 0.1)
		(layer "In5.Cu")
		(net 368)
	)
	(segment
		(start 90.575 72.6)
		(end 91.025 72.15)
		(width 0.1)
		(layer "In5.Cu")
		(net 368)
	)
	(segment
		(start 68.6 111)
		(end 68.600001 92.200001)
		(width 0.1)
		(layer "In5.Cu")
		(net 368)
	)
	(segment
		(start 68.600001 92.200001)
		(end 68 91.6)
		(width 0.1)
		(layer "In5.Cu")
		(net 368)
	)
	(segment
		(start 86.6 71.65)
		(end 87.55 72.6)
		(width 0.1)
		(layer "In5.Cu")
		(net 368)
	)
	(segment
		(start 68 85.8)
		(end 68.4 85.4)
		(width 0.1)
		(layer "In5.Cu")
		(net 368)
	)
	(segment
		(start 68 91.6)
		(end 68 85.8)
		(width 0.1)
		(layer "In5.Cu")
		(net 368)
	)
	(segment
		(start 68.4 78.365686)
		(end 68.945686 77.82)
		(width 0.1)
		(layer "In5.Cu")
		(net 368)
	)
	(segment
		(start 218.755632 91.6635)
		(end 218.72513 91.6635)
		(width 0.19)
		(layer "F.Cu")
		(net 370)
	)
	(segment
		(start 218.72513 91.6635)
		(end 218.385 91.32337)
		(width 0.19)
		(layer "F.Cu")
		(net 370)
	)
	(segment
		(start 219.084132 91.36)
		(end 219.059132 91.36)
		(width 0.19)
		(layer "F.Cu")
		(net 370)
	)
	(segment
		(start 216.828633 89.986856)
		(end 216.814633 89.972856)
		(width 0.19)
		(layer "F.Cu")
		(net 370)
	)
	(segment
		(start 216.814633 89.972856)
		(end 216.364632 89.972856)
		(width 0.19)
		(layer "F.Cu")
		(net 370)
	)
	(segment
		(start 218.385 91.32337)
		(end 218.385 90.52337)
		(width 0.19)
		(layer "F.Cu")
		(net 370)
	)
	(segment
		(start 218.385 90.52337)
		(end 217.848486 89.986856)
		(width 0.19)
		(layer "F.Cu")
		(net 370)
	)
	(segment
		(start 217.848486 89.986856)
		(end 216.828633 89.986856)
		(width 0.19)
		(layer "F.Cu")
		(net 370)
	)
	(segment
		(start 219.059132 91.36)
		(end 218.755632 91.6635)
		(width 0.19)
		(layer "F.Cu")
		(net 370)
	)
	(segment
		(start 140.15 72.45)
		(end 140.15 71.7)
		(width 0.1)
		(layer "F.Cu")
		(net 371)
	)
	(segment
		(start 142 75.65)
		(end 142 74.4)
		(width 0.1)
		(layer "F.Cu")
		(net 371)
	)
	(segment
		(start 143.575 78.95)
		(end 143.8 78.725)
		(width 0.1)
		(layer "F.Cu")
		(net 371)
	)
	(segment
		(start 143.8 78.725)
		(end 143.8 77.8)
		(width 0.1)
		(layer "F.Cu")
		(net 371)
	)
	(segment
		(start 143.55 81.725)
		(end 143.8 81.475)
		(width 0.1)
		(layer "F.Cu")
		(net 371)
	)
	(segment
		(start 141.8 75.85)
		(end 142 75.65)
		(width 0.1)
		(layer "F.Cu")
		(net 371)
	)
	(segment
		(start 141.8 74.2)
		(end 142 74.4)
		(width 0.1)
		(layer "F.Cu")
		(net 371)
	)
	(segment
		(start 141.8 76.85)
		(end 141.8 75.85)
		(width 0.1)
		(layer "F.Cu")
		(net 371)
	)
	(segment
		(start 141.8 73.05)
		(end 141.4 72.65)
		(width 0.1)
		(layer "F.Cu")
		(net 371)
	)
	(segment
		(start 143.55 82.9)
		(end 144.230532 83.580532)
		(width 0.1)
		(layer "F.Cu")
		(net 371)
	)
	(segment
		(start 139.95 70.4)
		(end 139.35 69.8)
		(width 0.1)
		(layer "F.Cu")
		(net 371)
	)
	(segment
		(start 140.35 72.65)
		(end 140.15 72.45)
		(width 0.1)
		(layer "F.Cu")
		(net 371)
	)
	(segment
		(start 139.95 71.5)
		(end 140.15 71.7)
		(width 0.1)
		(layer "F.Cu")
		(net 371)
	)
	(segment
		(start 143.8 77.8)
		(end 143.1 77.1)
		(width 0.1)
		(layer "F.Cu")
		(net 371)
	)
	(segment
		(start 143.575 80.05)
		(end 143.575 78.95)
		(width 0.1)
		(layer "F.Cu")
		(net 371)
	)
	(segment
		(start 144.230532 84.15)
		(end 144.230532 83.580532)
		(width 0.1)
		(layer "F.Cu")
		(net 371)
	)
	(segment
		(start 143.575 80.05)
		(end 143.8 80.275)
		(width 0.1)
		(layer "F.Cu")
		(net 371)
	)
	(segment
		(start 143.55 82.9)
		(end 143.55 81.725)
		(width 0.1)
		(layer "F.Cu")
		(net 371)
	)
	(segment
		(start 141.8 76.85)
		(end 142.05 77.1)
		(width 0.1)
		(layer "F.Cu")
		(net 371)
	)
	(segment
		(start 140.35 72.65)
		(end 141.4 72.65)
		(width 0.1)
		(layer "F.Cu")
		(net 371)
	)
	(segment
		(start 141.8 74.2)
		(end 141.8 73.05)
		(width 0.1)
		(layer "F.Cu")
		(net 371)
	)
	(segment
		(start 139.35 69.8)
		(end 138.7 69.8)
		(width 0.1)
		(layer "F.Cu")
		(net 371)
	)
	(segment
		(start 143.8 81.475)
		(end 143.8 80.275)
		(width 0.1)
		(layer "F.Cu")
		(net 371)
	)
	(segment
		(start 139.95 71.5)
		(end 139.95 70.4)
		(width 0.1)
		(layer "F.Cu")
		(net 371)
	)
	(segment
		(start 143.1 77.1)
		(end 142.05 77.1)
		(width 0.1)
		(layer "F.Cu")
		(net 371)
	)
	(via
		(at 144.230532 84.15)
		(size 0.45)
		(drill 0.1)
		(layers "F.Cu" "B.Cu")
		(net 371)
	)
	(via
		(at 74.505532 103.075)
		(size 0.45)
		(drill 0.1)
		(layers "F.Cu" "B.Cu")
		(net 371)
	)
	(via
		(at 138.7 69.8)
		(size 0.45)
		(drill 0.1)
		(layers "F.Cu" "B.Cu")
		(net 371)
	)
	(via
		(at 173.8 61.3)
		(size 0.45)
		(drill 0.1)
		(layers "F.Cu" "B.Cu")
		(net 371)
	)
	(segment
		(start 173.8 61.7)
		(end 173.8 61.3)
		(width 0.1)
		(layer "B.Cu")
		(net 371)
	)
	(segment
		(start 174.55 61.885002)
		(end 175.563002 61.885002)
		(width 0.1)
		(layer "B.Cu")
		(net 371)
	)
	(segment
		(start 174.55 61.885002)
		(end 173.985002 61.885002)
		(width 0.1)
		(layer "B.Cu")
		(net 371)
	)
	(segment
		(start 173.985002 61.885002)
		(end 173.8 61.7)
		(width 0.1)
		(layer "B.Cu")
		(net 371)
	)
	(segment
		(start 175.563002 61.885002)
		(end 175.568 61.89)
		(width 0.1)
		(layer "B.Cu")
		(net 371)
	)
	(segment
		(start 142 70.7)
		(end 143.4 69.3)
		(width 0.1)
		(layer "In2.Cu")
		(net 371)
	)
	(segment
		(start 138.7 69.8)
		(end 139.6 70.7)
		(width 0.1)
		(layer "In2.Cu")
		(net 371)
	)
	(segment
		(start 144.35 71.15)
		(end 144.9 71.7)
		(width 0.1)
		(layer "In2.Cu")
		(net 371)
	)
	(segment
		(start 173.8 61.55)
		(end 173.8 61.3)
		(width 0.1)
		(layer "In2.Cu")
		(net 371)
	)
	(segment
		(start 139.6 70.7)
		(end 142 70.7)
		(width 0.1)
		(layer "In2.Cu")
		(net 371)
	)
	(segment
		(start 165.01 70.34)
		(end 165.01 68.59)
		(width 0.1)
		(layer "In2.Cu")
		(net 371)
	)
	(segment
		(start 163.5 71.85)
		(end 165.01 70.34)
		(width 0.1)
		(layer "In2.Cu")
		(net 371)
	)
	(segment
		(start 147.25 71.7)
		(end 147.95 72.4)
		(width 0.1)
		(layer "In2.Cu")
		(net 371)
	)
	(segment
		(start 165.46 68.14)
		(end 167.21 68.14)
		(width 0.1)
		(layer "In2.Cu")
		(net 371)
	)
	(segment
		(start 143.95 69.3)
		(end 144.35 69.7)
		(width 0.1)
		(layer "In2.Cu")
		(net 371)
	)
	(segment
		(start 165.01 68.59)
		(end 165.46 68.14)
		(width 0.1)
		(layer "In2.Cu")
		(net 371)
	)
	(segment
		(start 167.21 68.14)
		(end 173.8 61.55)
		(width 0.1)
		(layer "In2.Cu")
		(net 371)
	)
	(segment
		(start 147.95 72.4)
		(end 149 72.4)
		(width 0.1)
		(layer "In2.Cu")
		(net 371)
	)
	(segment
		(start 144.35 69.7)
		(end 144.35 71.15)
		(width 0.1)
		(layer "In2.Cu")
		(net 371)
	)
	(segment
		(start 143.4 69.3)
		(end 143.95 69.3)
		(width 0.1)
		(layer "In2.Cu")
		(net 371)
	)
	(segment
		(start 149.55 71.85)
		(end 163.5 71.85)
		(width 0.1)
		(layer "In2.Cu")
		(net 371)
	)
	(segment
		(start 144.9 71.7)
		(end 147.25 71.7)
		(width 0.1)
		(layer "In2.Cu")
		(net 371)
	)
	(segment
		(start 149 72.4)
		(end 149.55 71.85)
		(width 0.1)
		(layer "In2.Cu")
		(net 371)
	)
	(segment
		(start 136.100002 94.775736)
		(end 142.462869 88.412869)
		(width 0.1)
		(layer "In5.Cu")
		(net 371)
	)
	(segment
		(start 142.462869 88.412869)
		(end 142.462869 85.387131)
		(width 0.1)
		(layer "In5.Cu")
		(net 371)
	)
	(segment
		(start 135.300002 100.475736)
		(end 136.100002 99.675736)
		(width 0.1)
		(layer "In5.Cu")
		(net 371)
	)
	(segment
		(start 75.6 123.8)
		(end 86.7 123.8)
		(width 0.1)
		(layer "In5.Cu")
		(net 371)
	)
	(segment
		(start 136.100002 99.675736)
		(end 136.100002 94.775736)
		(width 0.1)
		(layer "In5.Cu")
		(net 371)
	)
	(segment
		(start 86.7 123.8)
		(end 89.2 121.3)
		(width 0.1)
		(layer "In5.Cu")
		(net 371)
	)
	(segment
		(start 75.3 123.5)
		(end 75.6 123.8)
		(width 0.1)
		(layer "In5.Cu")
		(net 371)
	)
	(segment
		(start 105.1 117.4)
		(end 130.300002 117.4)
		(width 0.1)
		(layer "In5.Cu")
		(net 371)
	)
	(segment
		(start 143.109734 84.740266)
		(end 143.640266 84.740266)
		(width 0.1)
		(layer "In5.Cu")
		(net 371)
	)
	(segment
		(start 130.300002 117.4)
		(end 135.300002 112.4)
		(width 0.1)
		(layer "In5.Cu")
		(net 371)
	)
	(segment
		(start 143.640266 84.740266)
		(end 144.230532 84.15)
		(width 0.1)
		(layer "In5.Cu")
		(net 371)
	)
	(segment
		(start 142.462869 85.387131)
		(end 143.109734 84.740266)
		(width 0.1)
		(layer "In5.Cu")
		(net 371)
	)
	(segment
		(start 135.300002 112.4)
		(end 135.300002 100.475736)
		(width 0.1)
		(layer "In5.Cu")
		(net 371)
	)
	(segment
		(start 89.2 121.3)
		(end 101.2 121.3)
		(width 0.1)
		(layer "In5.Cu")
		(net 371)
	)
	(segment
		(start 101.2 121.3)
		(end 105.1 117.4)
		(width 0.1)
		(layer "In5.Cu")
		(net 371)
	)
	(segment
		(start 74.505532 103.075)
		(end 75.3 103.869468)
		(width 0.1)
		(layer "In5.Cu")
		(net 371)
	)
	(segment
		(start 75.3 103.869468)
		(end 75.3 123.5)
		(width 0.1)
		(layer "In5.Cu")
		(net 371)
	)
	(segment
		(start 218.385 88.52663)
		(end 217.753774 89.157856)
		(width 0.19)
		(layer "F.Cu")
		(net 372)
	)
	(segment
		(start 218.385 87.67663)
		(end 218.385 88.52663)
		(width 0.19)
		(layer "F.Cu")
		(net 372)
	)
	(segment
		(start 218.744132 87.435)
		(end 218.62663 87.435)
		(width 0.19)
		(layer "F.Cu")
		(net 372)
	)
	(segment
		(start 216.829633 89.157856)
		(end 216.814633 89.172856)
		(width 0.19)
		(layer "F.Cu")
		(net 372)
	)
	(segment
		(start 219.084132 87.75)
		(end 219.059132 87.75)
		(width 0.19)
		(layer "F.Cu")
		(net 372)
	)
	(segment
		(start 219.059132 87.75)
		(end 218.744132 87.435)
		(width 0.19)
		(layer "F.Cu")
		(net 372)
	)
	(segment
		(start 217.753774 89.157856)
		(end 216.829633 89.157856)
		(width 0.19)
		(layer "F.Cu")
		(net 372)
	)
	(segment
		(start 218.62663 87.435)
		(end 218.385 87.67663)
		(width 0.19)
		(layer "F.Cu")
		(net 372)
	)
	(segment
		(start 216.814633 89.172856)
		(end 216.364632 89.172856)
		(width 0.19)
		(layer "F.Cu")
		(net 372)
	)
	(segment
		(start 222.785 87.447)
		(end 222.9 87.562)
		(width 0.19)
		(layer "F.Cu")
		(net 374)
	)
	(segment
		(start 234.430532 90.3475)
		(end 234.430532 91.566251)
		(width 0.19)
		(layer "F.Cu")
		(net 374)
	)
	(segment
		(start 234.495532 91.885)
		(end 234.380532 92)
		(width 0.19)
		(layer "F.Cu")
		(net 374)
	)
	(segment
		(start 222.266633 87.447)
		(end 222.785 87.447)
		(width 0.19)
		(layer "F.Cu")
		(net 374)
	)
	(segment
		(start 234.430532 91.566251)
		(end 234.495532 91.631251)
		(width 0.19)
		(layer "F.Cu")
		(net 374)
	)
	(segment
		(start 221.789132 87.512)
		(end 221.017132 87.512)
		(width 0.19)
		(layer "F.Cu")
		(net 374)
	)
	(segment
		(start 220.282132 87.512)
		(end 220.044132 87.75)
		(width 0.19)
		(layer "F.Cu")
		(net 374)
	)
	(segment
		(start 234.495532 91.631251)
		(end 234.495532 91.885)
		(width 0.19)
		(layer "F.Cu")
		(net 374)
	)
	(segment
		(start 221.017132 87.512)
		(end 220.282132 87.512)
		(width 0.19)
		(layer "F.Cu")
		(net 374)
	)
	(segment
		(start 221.789132 87.512)
		(end 222.201633 87.512)
		(width 0.19)
		(layer "F.Cu")
		(net 374)
	)
	(segment
		(start 222.201633 87.512)
		(end 222.266633 87.447)
		(width 0.19)
		(layer "F.Cu")
		(net 374)
	)
	(via
		(at 234.380532 92)
		(size 0.45)
		(drill 0.1)
		(layers "F.Cu" "B.Cu")
		(net 374)
	)
	(via
		(at 222.9 87.562)
		(size 0.45)
		(drill 0.1)
		(layers "F.Cu" "B.Cu")
		(net 374)
	)
	(segment
		(start 230.781816 88.285521)
		(end 230.851816 88.285521)
		(width 0.15)
		(layer "In7.Cu")
		(net 374)
	)
	(segment
		(start 233.383044 87.9375)
		(end 234.543032 89.097488)
		(width 0.15)
		(layer "In7.Cu")
		(net 374)
	)
	(segment
		(start 224.792102 87.7995)
		(end 225.242102 87.7995)
		(width 0.15)
		(layer "In7.Cu")
		(net 374)
	)
	(segment
		(start 227.843044 87.9375)
		(end 230.501816 87.9375)
		(width 0.15)
		(layer "In7.Cu")
		(net 374)
	)
	(segment
		(start 225.579602 87.462)
		(end 225.579602 87.021286)
		(width 0.15)
		(layer "In7.Cu")
		(net 374)
	)
	(segment
		(start 230.991816 88.145521)
		(end 230.991816 88.0775)
		(width 0.15)
		(layer "In7.Cu")
		(net 374)
	)
	(segment
		(start 230.641816 88.0775)
		(end 230.641816 88.145521)
		(width 0.15)
		(layer "In7.Cu")
		(net 374)
	)
	(segment
		(start 225.682816 86.918072)
		(end 225.951388 86.918072)
		(width 0.15)
		(layer "In7.Cu")
		(net 374)
	)
	(segment
		(start 222.9 87.562)
		(end 223.0625 87.3995)
		(width 0.15)
		(layer "In7.Cu")
		(net 374)
	)
	(segment
		(start 226.432816 87.3995)
		(end 227.305044 87.3995)
		(width 0.15)
		(layer "In7.Cu")
		(net 374)
	)
	(segment
		(start 231.131816 87.9375)
		(end 233.383044 87.9375)
		(width 0.15)
		(layer "In7.Cu")
		(net 374)
	)
	(segment
		(start 234.543032 91.8375)
		(end 234.380532 92)
		(width 0.15)
		(layer "In7.Cu")
		(net 374)
	)
	(segment
		(start 234.543032 89.097488)
		(end 234.543032 91.8375)
		(width 0.15)
		(layer "In7.Cu")
		(net 374)
	)
	(segment
		(start 223.0625 87.3995)
		(end 224.392102 87.3995)
		(width 0.15)
		(layer "In7.Cu")
		(net 374)
	)
	(segment
		(start 227.305044 87.3995)
		(end 227.843044 87.9375)
		(width 0.15)
		(layer "In7.Cu")
		(net 374)
	)
	(arc
		(start 230.851816 88.285521)
		(mid 230.950811 88.244516)
		(end 230.991816 88.145521)
		(width 0.15)
		(layer "In7.Cu")
		(net 374)
	)
	(arc
		(start 230.501816 87.9375)
		(mid 230.600811 87.978505)
		(end 230.641816 88.0775)
		(width 0.15)
		(layer "In7.Cu")
		(net 374)
	)
	(arc
		(start 225.242102 87.7995)
		(mid 225.480751 87.700649)
		(end 225.579602 87.462)
		(width 0.15)
		(layer "In7.Cu")
		(net 374)
	)
	(arc
		(start 225.951388 86.918072)
		(mid 226.024371 86.948303)
		(end 226.054602 87.021286)
		(width 0.15)
		(layer "In7.Cu")
		(net 374)
	)
	(arc
		(start 230.991816 88.0775)
		(mid 231.032821 87.978505)
		(end 231.131816 87.9375)
		(width 0.15)
		(layer "In7.Cu")
		(net 374)
	)
	(arc
		(start 230.641816 88.145521)
		(mid 230.682821 88.244516)
		(end 230.781816 88.285521)
		(width 0.15)
		(layer "In7.Cu")
		(net 374)
	)
	(arc
		(start 226.054602 87.021286)
		(mid 226.165378 87.288724)
		(end 226.432816 87.3995)
		(width 0.15)
		(layer "In7.Cu")
		(net 374)
	)
	(arc
		(start 224.454602 87.462)
		(mid 224.553453 87.700649)
		(end 224.792102 87.7995)
		(width 0.15)
		(layer "In7.Cu")
		(net 374)
	)
	(arc
		(start 224.392102 87.3995)
		(mid 224.436296 87.417806)
		(end 224.454602 87.462)
		(width 0.15)
		(layer "In7.Cu")
		(net 374)
	)
	(arc
		(start 225.579602 87.021286)
		(mid 225.609833 86.948303)
		(end 225.682816 86.918072)
		(width 0.15)
		(layer "In7.Cu")
		(net 374)
	)
	(segment
		(start 231.430532 90.3475)
		(end 231.430532 89.220532)
		(width 0.2)
		(layer "F.Cu")
		(net 376)
	)
	(segment
		(start 232.060532 95.71)
		(end 231.5025 95.71)
		(width 0.15)
		(layer "F.Cu")
		(net 376)
	)
	(segment
		(start 233.930532 90.3475)
		(end 233.930532 91.429468)
		(width 0.2)
		(layer "F.Cu")
		(net 376)
	)
	(segment
		(start 233.930532 90.3475)
		(end 233.930532 89.230532)
		(width 0.2)
		(layer "F.Cu")
		(net 376)
	)
	(segment
		(start 233.930532 91.429468)
		(end 233.91 91.45)
		(width 0.2)
		(layer "F.Cu")
		(net 376)
	)
	(segment
		(start 231.430532 88.0725)
		(end 231.430532 89.219468)
		(width 0.2)
		(layer "F.Cu")
		(net 376)
	)
	(segment
		(start 233.930532 88.0725)
		(end 233.930532 89.209468)
		(width 0.2)
		(layer "F.Cu")
		(net 376)
	)
	(segment
		(start 231.5025 95.71)
		(end 231.25 95.9625)
		(width 0.15)
		(layer "F.Cu")
		(net 376)
	)
	(segment
		(start 231.430532 89.219468)
		(end 231.43 89.22)
		(width 0.2)
		(layer "F.Cu")
		(net 376)
	)
	(segment
		(start 233.930532 89.209468)
		(end 233.92 89.22)
		(width 0.2)
		(layer "F.Cu")
		(net 376)
	)
	(segment
		(start 231.430532 89.220532)
		(end 231.43 89.22)
		(width 0.2)
		(layer "F.Cu")
		(net 376)
	)
	(segment
		(start 231.430532 87.119468)
		(end 231.45 87.1)
		(width 0.2)
		(layer "F.Cu")
		(net 376)
	)
	(segment
		(start 231.430532 91.499468)
		(end 231.41 91.52)
		(width 0.2)
		(layer "F.Cu")
		(net 376)
	)
	(segment
		(start 231.430532 88.0725)
		(end 231.430532 87.119468)
		(width 0.2)
		(layer "F.Cu")
		(net 376)
	)
	(segment
		(start 233.930532 86.920532)
		(end 233.93 86.92)
		(width 0.2)
		(layer "F.Cu")
		(net 376)
	)
	(segment
		(start 233.930532 89.230532)
		(end 233.92 89.22)
		(width 0.2)
		(layer "F.Cu")
		(net 376)
	)
	(segment
		(start 233.930532 88.0725)
		(end 233.930532 86.920532)
		(width 0.2)
		(layer "F.Cu")
		(net 376)
	)
	(segment
		(start 231.430532 90.3475)
		(end 231.430532 91.499468)
		(width 0.2)
		(layer "F.Cu")
		(net 376)
	)
	(via
		(at 205.3 79.9)
		(size 0.45)
		(drill 0.1)
		(layers "F.Cu" "B.Cu")
		(free yes)
		(net 376)
	)
	(via
		(at 231.43 89.22)
		(size 0.45)
		(drill 0.1)
		(layers "F.Cu" "B.Cu")
		(net 376)
	)
	(via
		(at 205.9 81.05)
		(size 0.45)
		(drill 0.1)
		(layers "F.Cu" "B.Cu")
		(free yes)
		(net 376)
	)
	(via
		(at 206.5 80.5)
		(size 0.45)
		(drill 0.1)
		(layers "F.Cu" "B.Cu")
		(free yes)
		(net 376)
	)
	(via
		(at 231.25 95.9625)
		(size 0.45)
		(drill 0.1)
		(layers "F.Cu" "B.Cu")
		(net 376)
	)
	(via
		(at 233.93 86.92)
		(size 0.45)
		(drill 0.1)
		(layers "F.Cu" "B.Cu")
		(net 376)
	)
	(via
		(at 205.3 80.5)
		(size 0.45)
		(drill 0.1)
		(layers "F.Cu" "B.Cu")
		(free yes)
		(net 376)
	)
	(via
		(at 205.9 79.9)
		(size 0.45)
		(drill 0.1)
		(layers "F.Cu" "B.Cu")
		(free yes)
		(net 376)
	)
	(via
		(at 206.5 81.05)
		(size 0.45)
		(drill 0.1)
		(layers "F.Cu" "B.Cu")
		(free yes)
		(net 376)
	)
	(via
		(at 233.92 89.22)
		(size 0.45)
		(drill 0.1)
		(layers "F.Cu" "B.Cu")
		(net 376)
	)
	(via
		(at 206.5 79.9)
		(size 0.45)
		(drill 0.1)
		(layers "F.Cu" "B.Cu")
		(free yes)
		(net 376)
	)
	(via
		(at 205.9 80.5)
		(size 0.45)
		(drill 0.1)
		(layers "F.Cu" "B.Cu")
		(free yes)
		(net 376)
	)
	(via
		(at 231.45 87.1)
		(size 0.45)
		(drill 0.1)
		(layers "F.Cu" "B.Cu")
		(net 376)
	)
	(via
		(at 231.41 91.52)
		(size 0.45)
		(drill 0.1)
		(layers "F.Cu" "B.Cu")
		(net 376)
	)
	(via
		(at 233.91 91.45)
		(size 0.45)
		(drill 0.1)
		(layers "F.Cu" "B.Cu")
		(net 376)
	)
	(segment
		(start 231.45 87.92)
		(end 231.45 87.1)
		(width 0.2)
		(layer "B.Cu")
		(net 376)
	)
	(segment
		(start 231.43 89.22)
		(end 231.43 90.06)
		(width 0.2)
		(layer "B.Cu")
		(net 376)
	)
	(segment
		(start 231.37 88)
		(end 231.45 87.92)
		(width 0.2)
		(layer "B.Cu")
		(net 376)
	)
	(segment
		(start 230.65 88)
		(end 231.37 88)
		(width 0.2)
		(layer "B.Cu")
		(net 376)
	)
	(segment
		(start 231.37 90.2)
		(end 231.43 90.14)
		(width 0.1)
		(layer "B.Cu")
		(net 376)
	)
	(segment
		(start 231.43 90.06)
		(end 231.57 90.2)
		(width 0.2)
		(layer "B.Cu")
		(net 376)
	)
	(via
		(at 215.346 145.4)
		(size 0.45)
		(drill 0.1)
		(layers "F.Cu" "B.Cu")
		(net 379)
	)
	(segment
		(start 227.641 137.86)
		(end 227.726 137.775)
		(width 0.2)
		(layer "B.Cu")
		(net 379)
	)
	(segment
		(start 204.151 150.6)
		(end 202.726 152.025)
		(width 0.2)
		(layer "B.Cu")
		(net 379)
	)
	(segment
		(start 198.106 139.8)
		(end 198.106 138.155)
		(width 0.2)
		(layer "B.Cu")
		(net 379)
	)
	(segment
		(start 212.726 152.025)
		(end 214.371 152.025)
		(width 0.2)
		(layer "B.Cu")
		(net 379)
	)
	(segment
		(start 217.726 137.775)
		(end 215.931 137.775)
		(width 0.2)
		(layer "B.Cu")
		(net 379)
	)
	(segment
		(start 195.476532 138.32)
		(end 197.181 138.32)
		(width 0.2)
		(layer "B.Cu")
		(net 379)
	)
	(segment
		(start 220.906 152.2)
		(end 222.551 152.2)
		(width 0.2)
		(layer "B.Cu")
		(net 379)
	)
	(segment
		(start 225.906 137.86)
		(end 227.641 137.86)
		(width 0.2)
		(layer "B.Cu")
		(net 379)
	)
	(segment
		(start 198.106 138.155)
		(end 197.726 137.775)
		(width 0.2)
		(layer "B.Cu")
		(net 379)
	)
	(segment
		(start 230.906 152.025)
		(end 232.726 152.025)
		(width 0.2)
		(layer "B.Cu")
		(net 379)
	)
	(segment
		(start 207.706 139.6)
		(end 207.706 137.795)
		(width 0.2)
		(layer "B.Cu")
		(net 379)
	)
	(segment
		(start 215.931 137.775)
		(end 215.906 137.8)
		(width 0.2)
		(layer "B.Cu")
		(net 379)
	)
	(segment
		(start 197.181 138.32)
		(end 197.726 137.775)
		(width 0.2)
		(layer "B.Cu")
		(net 379)
	)
	(segment
		(start 207.706 137.795)
		(end 207.726 137.775)
		(width 0.2)
		(layer "B.Cu")
		(net 379)
	)
	(segment
		(start 222.551 152.2)
		(end 222.726 152.025)
		(width 0.2)
		(layer "B.Cu")
		(net 379)
	)
	(segment
		(start 214.371 152.025)
		(end 214.546 152.2)
		(width 0.2)
		(layer "B.Cu")
		(net 379)
	)
	(segment
		(start 204.746 150.6)
		(end 204.151 150.6)
		(width 0.2)
		(layer "B.Cu")
		(net 379)
	)
	(segment
		(start 108.695532 75.885)
		(end 108.580532 76)
		(width 0.19)
		(layer "F.Cu")
		(net 382)
	)
	(segment
		(start 108.430532 75.15)
		(end 108.695532 75.415)
		(width 0.19)
		(layer "F.Cu")
		(net 382)
	)
	(segment
		(start 108.695532 75.415)
		(end 108.695532 75.885)
		(width 0.19)
		(layer "F.Cu")
		(net 382)
	)
	(via
		(at 108.580532 76)
		(size 0.45)
		(drill 0.1)
		(layers "F.Cu" "B.Cu")
		(net 382)
	)
	(segment
		(start 109.77 107.5)
		(end 109.745 107.5)
		(width 0.19)
		(layer "B.Cu")
		(net 382)
	)
	(segment
		(start 99.330001 101.038541)
		(end 99.330001 87.208369)
		(width 0.19)
		(layer "B.Cu")
		(net 382)
	)
	(segment
		(start 100.715 84.52337)
		(end 102.715 82.52337)
		(width 0.19)
		(layer "B.Cu")
		(net 382)
	)
	(segment
		(start 108.32337 77.215)
		(end 108.695532 76.842838)
		(width 0.19)
		(layer "B.Cu")
		(net 382)
	)
	(segment
		(start 109.745 107.5)
		(end 109.43 107.185)
		(width 0.19)
		(layer "B.Cu")
		(net 382)
	)
	(segment
		(start 102.715 79.42337)
		(end 103.52337 78.615)
		(width 0.19)
		(layer "B.Cu")
		(net 382)
	)
	(segment
		(start 108.695532 76.115)
		(end 108.580532 76)
		(width 0.19)
		(layer "B.Cu")
		(net 382)
	)
	(segment
		(start 100.715 85.82337)
		(end 100.715 84.52337)
		(width 0.19)
		(layer "B.Cu")
		(net 382)
	)
	(segment
		(start 104.52337 78.615)
		(end 105.92337 77.215)
		(width 0.19)
		(layer "B.Cu")
		(net 382)
	)
	(segment
		(start 105.92337 77.215)
		(end 108.32337 77.215)
		(width 0.19)
		(layer "B.Cu")
		(net 382)
	)
	(segment
		(start 105.47646 107.185)
		(end 99.330001 101.038541)
		(width 0.19)
		(layer "B.Cu")
		(net 382)
	)
	(segment
		(start 102.715 82.52337)
		(end 102.715 79.42337)
		(width 0.19)
		(layer "B.Cu")
		(net 382)
	)
	(segment
		(start 109.43 107.185)
		(end 105.47646 107.185)
		(width 0.19)
		(layer "B.Cu")
		(net 382)
	)
	(segment
		(start 103.52337 78.615)
		(end 104.52337 78.615)
		(width 0.19)
		(layer "B.Cu")
		(net 382)
	)
	(segment
		(start 99.330001 87.208369)
		(end 100.715 85.82337)
		(width 0.19)
		(layer "B.Cu")
		(net 382)
	)
	(segment
		(start 108.695532 76.842838)
		(end 108.695532 76.115)
		(width 0.19)
		(layer "B.Cu")
		(net 382)
	)
	(segment
		(start 112.995 107.185)
		(end 113.06 107.25)
		(width 0.19)
		(layer "B.Cu")
		(net 386)
	)
	(segment
		(start 110.755 107.5)
		(end 111.07 107.185)
		(width 0.19)
		(layer "B.Cu")
		(net 386)
	)
	(segment
		(start 113.06 107.25)
		(end 113.685 107.25)
		(width 0.19)
		(layer "B.Cu")
		(net 386)
	)
	(segment
		(start 111.07 107.185)
		(end 112.995 107.185)
		(width 0.19)
		(layer "B.Cu")
		(net 386)
	)
	(segment
		(start 110.73 107.5)
		(end 110.755 107.5)
		(width 0.19)
		(layer "B.Cu")
		(net 386)
	)
	(segment
		(start 111.07 103.815)
		(end 110.755 103.5)
		(width 0.19)
		(layer "B.Cu")
		(net 391)
	)
	(segment
		(start 113.685 103.75)
		(end 113.06 103.75)
		(width 0.19)
		(layer "B.Cu")
		(net 391)
	)
	(segment
		(start 110.755 103.5)
		(end 110.73 103.5)
		(width 0.19)
		(layer "B.Cu")
		(net 391)
	)
	(segment
		(start 113.06 103.75)
		(end 112.995 103.815)
		(width 0.19)
		(layer "B.Cu")
		(net 391)
	)
	(segment
		(start 112.995 103.815)
		(end 111.07 103.815)
		(width 0.19)
		(layer "B.Cu")
		(net 391)
	)
	(segment
		(start 109.330532 72.15)
		(end 109.065532 72.415)
		(width 0.19)
		(layer "F.Cu")
		(net 392)
	)
	(segment
		(start 109.065532 72.415)
		(end 109.065532 72.685)
		(width 0.19)
		(layer "F.Cu")
		(net 392)
	)
	(segment
		(start 109.065532 72.685)
		(end 109.180532 72.8)
		(width 0.19)
		(layer "F.Cu")
		(net 392)
	)
	(via
		(at 109.180532 72.8)
		(size 0.45)
		(drill 0.1)
		(layers "F.Cu" "B.Cu")
		(net 392)
	)
	(segment
		(start 107.085 84.87663)
		(end 107.085 83.17663)
		(width 0.19)
		(layer "B.Cu")
		(net 392)
	)
	(segment
		(start 109.43 103.815)
		(end 106.87236 103.815)
		(width 0.19)
		(layer "B.Cu")
		(net 392)
	)
	(segment
		(start 110.385 79.12337)
		(end 109.685 78.42337)
		(width 0.19)
		(layer "B.Cu")
		(net 392)
	)
	(segment
		(start 109.065532 73.13894)
		(end 109.065532 72.915)
		(width 0.19)
		(layer "B.Cu")
		(net 392)
	)
	(segment
		(start 109.785 81.27663)
		(end 109.785 80.67663)
		(width 0.19)
		(layer "B.Cu")
		(net 392)
	)
	(segment
		(start 110.385 76.97663)
		(end 110.385 76.02337)
		(width 0.19)
		(layer "B.Cu")
		(net 392)
	)
	(segment
		(start 102.940001 93.911635)
		(end 102.972478 93.911635)
		(width 0.19)
		(layer "B.Cu")
		(net 392)
	)
	(segment
		(start 102.700001 93.071635)
		(end 102.700001 89.261629)
		(width 0.19)
		(layer "B.Cu")
		(net 392)
	)
	(segment
		(start 109.085 73.158408)
		(end 109.065532 73.13894)
		(width 0.19)
		(layer "B.Cu")
		(net 392)
	)
	(segment
		(start 103.212478 93.671635)
		(end 103.212478 93.551635)
		(width 0.19)
		(layer "B.Cu")
		(net 392)
	)
	(segment
		(start 109.685 78.42337)
		(end 109.685 77.67663)
		(width 0.19)
		(layer "B.Cu")
		(net 392)
	)
	(segment
		(start 107.085 83.17663)
		(end 108.47663 81.785)
		(width 0.19)
		(layer "B.Cu")
		(net 392)
	)
	(segment
		(start 106.87236 103.815)
		(end 102.700001 99.642641)
		(width 0.19)
		(layer "B.Cu")
		(net 392)
	)
	(segment
		(start 102.972478 93.311635)
		(end 102.940001 93.311635)
		(width 0.19)
		(layer "B.Cu")
		(net 392)
	)
	(segment
		(start 109.685 77.67663)
		(end 110.385 76.97663)
		(width 0.19)
		(layer "B.Cu")
		(net 392)
	)
	(segment
		(start 102.700001 89.261629)
		(end 107.085 84.87663)
		(width 0.19)
		(layer "B.Cu")
		(net 392)
	)
	(segment
		(start 108.47663 81.785)
		(end 109.27663 81.785)
		(width 0.19)
		(layer "B.Cu")
		(net 392)
	)
	(segment
		(start 109.27663 81.785)
		(end 109.785 81.27663)
		(width 0.19)
		(layer "B.Cu")
		(net 392)
	)
	(segment
		(start 109.065532 72.915)
		(end 109.180532 72.8)
		(width 0.19)
		(layer "B.Cu")
		(net 392)
	)
	(segment
		(start 109.085 74.72337)
		(end 109.085 73.158408)
		(width 0.19)
		(layer "B.Cu")
		(net 392)
	)
	(segment
		(start 110.385 80.07663)
		(end 110.385 79.12337)
		(width 0.19)
		(layer "B.Cu")
		(net 392)
	)
	(segment
		(start 102.700001 99.642641)
		(end 102.700001 94.151635)
		(width 0.19)
		(layer "B.Cu")
		(net 392)
	)
	(segment
		(start 109.77 103.5)
		(end 109.745 103.5)
		(width 0.19)
		(layer "B.Cu")
		(net 392)
	)
	(segment
		(start 110.385 76.02337)
		(end 109.085 74.72337)
		(width 0.19)
		(layer "B.Cu")
		(net 392)
	)
	(segment
		(start 109.785 80.67663)
		(end 110.385 80.07663)
		(width 0.19)
		(layer "B.Cu")
		(net 392)
	)
	(segment
		(start 109.745 103.5)
		(end 109.43 103.815)
		(width 0.19)
		(layer "B.Cu")
		(net 392)
	)
	(arc
		(start 103.212478 93.551635)
		(mid 103.142184 93.381929)
		(end 102.972478 93.311635)
		(width 0.19)
		(layer "B.Cu")
		(net 392)
	)
	(arc
		(start 102.972478 93.911635)
		(mid 103.142184 93.841341)
		(end 103.212478 93.671635)
		(width 0.19)
		(layer "B.Cu")
		(net 392)
	)
	(arc
		(start 102.940001 93.311635)
		(mid 102.770295 93.241341)
		(end 102.700001 93.071635)
		(width 0.19)
		(layer "B.Cu")
		(net 392)
	)
	(arc
		(start 102.700001 94.151635)
		(mid 102.770295 93.981929)
		(end 102.940001 93.911635)
		(width 0.19)
		(layer "B.Cu")
		(net 392)
	)
	(via
		(at 82.8 135)
		(size 0.45)
		(drill 0.1)
		(layers "F.Cu" "B.Cu")
		(net 393)
	)
	(via
		(at 144.2 93.4)
		(size 0.45)
		(drill 0.1)
		(layers "F.Cu" "B.Cu")
		(net 393)
	)
	(via
		(at 143.130532 79.65)
		(size 0.45)
		(drill 0.1)
		(layers "F.Cu" "B.Cu")
		(net 393)
	)
	(via
		(at 75.775 111.875)
		(size 0.45)
		(drill 0.1)
		(layers "F.Cu" "B.Cu")
		(net 393)
	)
	(segment
		(start 143.6 86.15)
		(end 143.6 91.4)
		(width 0.1)
		(layer "B.Cu")
		(net 393)
	)
	(segment
		(start 144.2 92)
		(end 144.2 93.4)
		(width 0.1)
		(layer "B.Cu")
		(net 393)
	)
	(segment
		(start 143.8 80.319468)
		(end 143.8 81.5)
		(width 0.1)
		(layer "B.Cu")
		(net 393)
	)
	(segment
		(start 143.130532 79.65)
		(end 143.8 80.319468)
		(width 0.1)
		(layer "B.Cu")
		(net 393)
	)
	(segment
		(start 142.5 83.15)
		(end 142.85 83.5)
		(width 0.1)
		(layer "B.Cu")
		(net 393)
	)
	(segment
		(start 143.8 81.5)
		(end 143.4 81.9)
		(width 0.1)
		(layer "B.Cu")
		(net 393)
	)
	(segment
		(start 142.85 85.4)
		(end 143.6 86.15)
		(width 0.1)
		(layer "B.Cu")
		(net 393)
	)
	(segment
		(start 143.4 81.9)
		(end 143.05 81.9)
		(width 0.1)
		(layer "B.Cu")
		(net 393)
	)
	(segment
		(start 142.85 83.5)
		(end 142.85 85.4)
		(width 0.1)
		(layer "B.Cu")
		(net 393)
	)
	(segment
		(start 143.05 81.9)
		(end 142.5 82.45)
		(width 0.1)
		(layer "B.Cu")
		(net 393)
	)
	(segment
		(start 142.5 82.45)
		(end 142.5 83.15)
		(width 0.1)
		(layer "B.Cu")
		(net 393)
	)
	(segment
		(start 143.6 91.4)
		(end 144.2 92)
		(width 0.1)
		(layer "B.Cu")
		(net 393)
	)
	(segment
		(start 82.8 131.4)
		(end 84.4 129.8)
		(width 0.1)
		(layer "In5.Cu")
		(net 393)
	)
	(segment
		(start 143.6 102.899999)
		(end 144.199999 102.3)
		(width 0.1)
		(layer "In5.Cu")
		(net 393)
	)
	(segment
		(start 138.031371 123.299999)
		(end 144.199999 117.131371)
		(width 0.1)
		(layer "In5.Cu")
		(net 393)
	)
	(segment
		(start 84.4 129.8)
		(end 105.93137 129.8)
		(width 0.1)
		(layer "In5.Cu")
		(net 393)
	)
	(segment
		(start 144.199999 102.3)
		(end 144.2 93.4)
		(width 0.1)
		(layer "In5.Cu")
		(net 393)
	)
	(segment
		(start 144.199999 117.131371)
		(end 144.199999 108.199999)
		(width 0.1)
		(layer "In5.Cu")
		(net 393)
	)
	(segment
		(start 82.8 135)
		(end 82.8 131.4)
		(width 0.1)
		(layer "In5.Cu")
		(net 393)
	)
	(segment
		(start 105.93137 129.8)
		(end 112.431371 123.299999)
		(width 0.1)
		(layer "In5.Cu")
		(net 393)
	)
	(segment
		(start 112.431371 123.299999)
		(end 138.031371 123.299999)
		(width 0.1)
		(layer "In5.Cu")
		(net 393)
	)
	(segment
		(start 143.6 107.6)
		(end 143.6 102.899999)
		(width 0.1)
		(layer "In5.Cu")
		(net 393)
	)
	(segment
		(start 144.199999 108.199999)
		(end 143.6 107.6)
		(width 0.1)
		(layer "In5.Cu")
		(net 393)
	)
	(segment
		(start 75.2 114.6)
		(end 75.2 112.45)
		(width 0.1)
		(layer "In7.Cu")
		(net 393)
	)
	(segment
		(start 82.8 135)
		(end 82.8 133.4)
		(width 0.1)
		(layer "In7.Cu")
		(net 393)
	)
	(segment
		(start 78.8 129.4)
		(end 78.8 116.7)
		(width 0.1)
		(layer "In7.Cu")
		(net 393)
	)
	(segment
		(start 75.6 115)
		(end 75.2 114.6)
		(width 0.1)
		(layer "In7.Cu")
		(net 393)
	)
	(segment
		(start 75.2 112.45)
		(end 75.775 111.875)
		(width 0.1)
		(layer "In7.Cu")
		(net 393)
	)
	(segment
		(start 77.1 115)
		(end 75.6 115)
		(width 0.1)
		(layer "In7.Cu")
		(net 393)
	)
	(segment
		(start 82.8 133.4)
		(end 78.8 129.4)
		(width 0.1)
		(layer "In7.Cu")
		(net 393)
	)
	(segment
		(start 78.8 116.7)
		(end 77.1 115)
		(width 0.1)
		(layer "In7.Cu")
		(net 393)
	)
	(segment
		(start 110.805 100.5)
		(end 110.78 100.5)
		(width 0.19)
		(layer "B.Cu")
		(net 399)
	)
	(segment
		(start 112.995 100.815)
		(end 111.12 100.815)
		(width 0.19)
		(layer "B.Cu")
		(net 399)
	)
	(segment
		(start 113.685 100.75)
		(end 113.06 100.75)
		(width 0.19)
		(layer "B.Cu")
		(net 399)
	)
	(segment
		(start 113.06 100.75)
		(end 112.995 100.815)
		(width 0.19)
		(layer "B.Cu")
		(net 399)
	)
	(segment
		(start 111.12 100.815)
		(end 110.805 100.5)
		(width 0.19)
		(layer "B.Cu")
		(net 399)
	)
	(segment
		(start 111.065532 77.385)
		(end 111.180532 77.5)
		(width 0.19)
		(layer "F.Cu")
		(net 400)
	)
	(segment
		(start 111.065532 76.915)
		(end 111.065532 77.385)
		(width 0.19)
		(layer "F.Cu")
		(net 400)
	)
	(segment
		(start 111.330532 76.65)
		(end 111.065532 76.915)
		(width 0.19)
		(layer "F.Cu")
		(net 400)
	)
	(via
		(at 111.180532 77.5)
		(size 0.45)
		(drill 0.1)
		(layers "F.Cu" "B.Cu")
		(net 400)
	)
	(segment
		(start 105.957583 94.38727)
		(end 105.925 94.38727)
		(width 0.19)
		(layer "B.Cu")
		(net 400)
	)
	(segment
		(start 110.585 82.77663)
		(end 110.585 81.97663)
		(width 0.19)
		(layer "B.Cu")
		(net 400)
	)
	(segment
		(start 105.685 94.14727)
		(end 105.685 90.27663)
		(width 0.19)
		(layer "B.Cu")
		(net 400)
	)
	(segment
		(start 109.785 84.52337)
		(end 109.785 83.57663)
		(width 0.19)
		(layer "B.Cu")
		(net 400)
	)
	(segment
		(start 106.197583 94.74727)
		(end 106.197583 94.62727)
		(width 0.19)
		(layer "B.Cu")
		(net 400)
	)
	(segment
		(start 105.685 90.27663)
		(end 107.87663 88.085)
		(width 0.19)
		(layer "B.Cu")
		(net 400)
	)
	(segment
		(start 110.585 81.97663)
		(end 111.065532 81.496098)
		(width 0.19)
		(layer "B.Cu")
		(net 400)
	)
	(segment
		(start 109.48 100.815)
		(end 108.115 100.815)
		(width 0.19)
		(layer "B.Cu")
		(net 400)
	)
	(segment
		(start 111.065532 78.403902)
		(end 111.065532 77.615)
		(width 0.19)
		(layer "B.Cu")
		(net 400)
	)
	(segment
		(start 105.685 98.385)
		(end 105.685 95.22727)
		(width 0.19)
		(layer "B.Cu")
		(net 400)
	)
	(segment
		(start 108.87663 88.085)
		(end 110.385 86.57663)
		(width 0.19)
		(layer "B.Cu")
		(net 400)
	)
	(segment
		(start 110.385 86.57663)
		(end 110.385 85.12337)
		(width 0.19)
		(layer "B.Cu")
		(net 400)
	)
	(segment
		(start 111.065532 77.615)
		(end 111.180532 77.5)
		(width 0.19)
		(layer "B.Cu")
		(net 400)
	)
	(segment
		(start 110.385 85.12337)
		(end 109.785 84.52337)
		(width 0.19)
		(layer "B.Cu")
		(net 400)
	)
	(segment
		(start 111.685 79.02337)
		(end 111.065532 78.403902)
		(width 0.19)
		(layer "B.Cu")
		(net 400)
	)
	(segment
		(start 109.785 83.57663)
		(end 110.585 82.77663)
		(width 0.19)
		(layer "B.Cu")
		(net 400)
	)
	(segment
		(start 111.065532 81.496098)
		(end 111.065532 80.796098)
		(width 0.19)
		(layer "B.Cu")
		(net 400)
	)
	(segment
		(start 111.065532 80.796098)
		(end 111.685 80.17663)
		(width 0.19)
		(layer "B.Cu")
		(net 400)
	)
	(segment
		(start 109.795 100.5)
		(end 109.48 100.815)
		(width 0.19)
		(layer "B.Cu")
		(net 400)
	)
	(segment
		(start 107.87663 88.085)
		(end 108.87663 88.085)
		(width 0.19)
		(layer "B.Cu")
		(net 400)
	)
	(segment
		(start 105.925 94.98727)
		(end 105.957583 94.98727)
		(width 0.19)
		(layer "B.Cu")
		(net 400)
	)
	(segment
		(start 111.685 80.17663)
		(end 111.685 79.02337)
		(width 0.19)
		(layer "B.Cu")
		(net 400)
	)
	(segment
		(start 108.115 100.815)
		(end 105.685 98.385)
		(width 0.19)
		(layer "B.Cu")
		(net 400)
	)
	(arc
		(start 105.957583 94.98727)
		(mid 106.127289 94.916976)
		(end 106.197583 94.74727)
		(width 0.19)
		(layer "B.Cu")
		(net 400)
	)
	(arc
		(start 105.925 94.38727)
		(mid 105.755294 94.316976)
		(end 105.685 94.14727)
		(width 0.19)
		(layer "B.Cu")
		(net 400)
	)
	(arc
		(start 106.197583 94.62727)
		(mid 106.127289 94.457564)
		(end 105.957583 94.38727)
		(width 0.19)
		(layer "B.Cu")
		(net 400)
	)
	(arc
		(start 105.685 95.22727)
		(mid 105.755294 95.057564)
		(end 105.925 94.98727)
		(width 0.19)
		(layer "B.Cu")
		(net 400)
	)
	(segment
		(start 79 128.9)
		(end 79.3 129.2)
		(width 0.1)
		(layer "F.Cu")
		(net 405)
	)
	(segment
		(start 75.1 120.3)
		(end 77.7 122.9)
		(width 0.1)
		(layer "F.Cu")
		(net 405)
	)
	(segment
		(start 86.2 134)
		(end 86.2 136.6)
		(width 0.1)
		(layer "F.Cu")
		(net 405)
	)
	(segment
		(start 86.9 137.3)
		(end 87.3 137.3)
		(width 0.1)
		(layer "F.Cu")
		(net 405)
	)
	(segment
		(start 77.7 122.9)
		(end 77.7 126)
		(width 0.1)
		(layer "F.Cu")
		(net 405)
	)
	(segment
		(start 85.4 133.2)
		(end 86.2 134)
		(width 0.1)
		(layer "F.Cu")
		(net 405)
	)
	(segment
		(start 79.3 129.2)
		(end 79.834314 129.2)
		(width 0.1)
		(layer "F.Cu")
		(net 405)
	)
	(segment
		(start 77.7 126)
		(end 79 127.3)
		(width 0.1)
		(layer "F.Cu")
		(net 405)
	)
	(segment
		(start 74.5 117.05)
		(end 73.9 117.65)
		(width 0.1)
		(layer "F.Cu")
		(net 405)
	)
	(segment
		(start 79 127.3)
		(end 79 128.9)
		(width 0.1)
		(layer "F.Cu")
		(net 405)
	)
	(segment
		(start 73.9 117.65)
		(end 73.9 119.7)
		(width 0.1)
		(layer "F.Cu")
		(net 405)
	)
	(segment
		(start 79.834314 129.2)
		(end 83.834314 133.2)
		(width 0.1)
		(layer "F.Cu")
		(net 405)
	)
	(segment
		(start 86.2 136.6)
		(end 86.9 137.3)
		(width 0.1)
		(layer "F.Cu")
		(net 405)
	)
	(segment
		(start 83.834314 133.2)
		(end 85.4 133.2)
		(width 0.1)
		(layer "F.Cu")
		(net 405)
	)
	(segment
		(start 74.5 120.3)
		(end 75.1 120.3)
		(width 0.1)
		(layer "F.Cu")
		(net 405)
	)
	(segment
		(start 73.9 119.7)
		(end 74.5 120.3)
		(width 0.1)
		(layer "F.Cu")
		(net 405)
	)
	(via
		(at 146.2 92.6)
		(size 0.45)
		(drill 0.1)
		(layers "F.Cu" "B.Cu")
		(net 405)
	)
	(via
		(at 138.630532 79.65)
		(size 0.45)
		(drill 0.1)
		(layers "F.Cu" "B.Cu")
		(net 405)
	)
	(via
		(at 87.3 137.3)
		(size 0.45)
		(drill 0.1)
		(layers "F.Cu" "B.Cu")
		(net 405)
	)
	(via
		(at 74.5 117.05)
		(size 0.45)
		(drill 0.1)
		(layers "F.Cu" "B.Cu")
		(net 405)
	)
	(segment
		(start 138.4 81.6)
		(end 138.4 79.880532)
		(width 0.1)
		(layer "B.Cu")
		(net 405)
	)
	(segment
		(start 146.2 93.95)
		(end 145.55 94.6)
		(width 0.1)
		(layer "B.Cu")
		(net 405)
	)
	(segment
		(start 142 93.55)
		(end 142 87.85)
		(width 0.1)
		(layer "B.Cu")
		(net 405)
	)
	(segment
		(start 146.2 92.6)
		(end 146.2 93.95)
		(width 0.1)
		(layer "B.Cu")
		(net 405)
	)
	(segment
		(start 145.55 94.6)
		(end 143.05 94.6)
		(width 0.1)
		(layer "B.Cu")
		(net 405)
	)
	(segment
		(start 138.4 79.880532)
		(end 138.630532 79.65)
		(width 0.1)
		(layer "B.Cu")
		(net 405)
	)
	(segment
		(start 139.95 82.5)
		(end 139.7 82.25)
		(width 0.1)
		(layer "B.Cu")
		(net 405)
	)
	(segment
		(start 139.7 82.25)
		(end 139.05 82.25)
		(width 0.1)
		(layer "B.Cu")
		(net 405)
	)
	(segment
		(start 140.55 83.5)
		(end 139.95 82.9)
		(width 0.1)
		(layer "B.Cu")
		(net 405)
	)
	(segment
		(start 139.05 82.25)
		(end 138.4 81.6)
		(width 0.1)
		(layer "B.Cu")
		(net 405)
	)
	(segment
		(start 140.55 86.4)
		(end 140.55 83.5)
		(width 0.1)
		(layer "B.Cu")
		(net 405)
	)
	(segment
		(start 143.05 94.6)
		(end 142 93.55)
		(width 0.1)
		(layer "B.Cu")
		(net 405)
	)
	(segment
		(start 139.95 82.9)
		(end 139.95 82.5)
		(width 0.1)
		(layer "B.Cu")
		(net 405)
	)
	(segment
		(start 142 87.85)
		(end 140.55 86.4)
		(width 0.1)
		(layer "B.Cu")
		(net 405)
	)
	(segment
		(start 96.25 133.05)
		(end 92 137.3)
		(width 0.1)
		(layer "In5.Cu")
		(net 405)
	)
	(segment
		(start 146.2 92.6)
		(end 146.199998 92.600002)
		(width 0.1)
		(layer "In5.Cu")
		(net 405)
	)
	(segment
		(start 113.259799 125.299999)
		(end 106.359798 132.2)
		(width 0.1)
		(layer "In5.Cu")
		(net 405)
	)
	(segment
		(start 145.7 104)
		(end 145.7 106.900002)
		(width 0.1)
		(layer "In5.Cu")
		(net 405)
	)
	(segment
		(start 145.7 106.900002)
		(end 146.199998 107.4)
		(width 0.1)
		(layer "In5.Cu")
		(net 405)
	)
	(segment
		(start 146.199998 92.600002)
		(end 146.199998 103.500002)
		(width 0.1)
		(layer "In5.Cu")
		(net 405)
	)
	(segment
		(start 146.199998 117.959798)
		(end 138.859797 125.299999)
		(width 0.1)
		(layer "In5.Cu")
		(net 405)
	)
	(segment
		(start 100.8 132.2)
		(end 99.95 133.05)
		(width 0.1)
		(layer "In5.Cu")
		(net 405)
	)
	(segment
		(start 92 137.3)
		(end 87.3 137.3)
		(width 0.1)
		(layer "In5.Cu")
		(net 405)
	)
	(segment
		(start 106.359798 132.2)
		(end 100.8 132.2)
		(width 0.1)
		(layer "In5.Cu")
		(net 405)
	)
	(segment
		(start 138.859797 125.299999)
		(end 113.259799 125.299999)
		(width 0.1)
		(layer "In5.Cu")
		(net 405)
	)
	(segment
		(start 146.199998 103.500002)
		(end 145.7 104)
		(width 0.1)
		(layer "In5.Cu")
		(net 405)
	)
	(segment
		(start 99.95 133.05)
		(end 96.25 133.05)
		(width 0.1)
		(layer "In5.Cu")
		(net 405)
	)
	(segment
		(start 146.199998 107.4)
		(end 146.199998 117.959798)
		(width 0.1)
		(layer "In5.Cu")
		(net 405)
	)
	(segment
		(start 131.635 135.29)
		(end 131.635 133.365)
		(width 0.1)
		(layer "F.Cu")
		(net 407)
	)
	(segment
		(start 149.53 120.2)
		(end 148.28 120.2)
		(width 0.1)
		(layer "F.Cu")
		(net 407)
	)
	(segment
		(start 149.98 119.75)
		(end 151.231 119.75)
		(width 0.1)
		(layer "F.Cu")
		(net 407)
	)
	(segment
		(start 131.635 133.365)
		(end 132.2 132.8)
		(width 0.1)
		(layer "F.Cu")
		(net 407)
	)
	(segment
		(start 132.2 132.8)
		(end 132.8 132.8)
		(width 0.1)
		(layer "F.Cu")
		(net 407)
	)
	(segment
		(start 149.96 119.77)
		(end 149.98 119.75)
		(width 0.1)
		(layer "F.Cu")
		(net 407)
	)
	(segment
		(start 149.96 119.77)
		(end 149.53 120.2)
		(width 0.1)
		(layer "F.Cu")
		(net 407)
	)
	(via
		(at 80.855532 115.775)
		(size 0.45)
		(drill 0.1)
		(layers "F.Cu" "B.Cu")
		(net 407)
	)
	(via
		(at 149.96 119.77)
		(size 0.45)
		(drill 0.1)
		(layers "F.Cu" "B.Cu")
		(net 407)
	)
	(via
		(at 131.6 133.8)
		(size 0.45)
		(drill 0.1)
		(layers "F.Cu" "B.Cu")
		(net 407)
	)
	(via
		(at 132.8 132.8)
		(size 0.45)
		(drill 0.1)
		(layers "F.Cu" "B.Cu")
		(net 407)
	)
	(segment
		(start 87.699998 124.330011)
		(end 101.269987 137.9)
		(width 0.1)
		(layer "In7.Cu")
		(net 407)
	)
	(segment
		(start 149.96 119.77)
		(end 149.93 119.8)
		(width 0.1)
		(layer "In7.Cu")
		(net 407)
	)
	(segment
		(start 82.924265 120.100001)
		(end 85.424263 120.100001)
		(width 0.1)
		(layer "In7.Cu")
		(net 407)
	)
	(segment
		(start 142.6 123.8)
		(end 134.8 123.8)
		(width 0.1)
		(layer "In7.Cu")
		(net 407)
	)
	(segment
		(start 119.6 135.8)
		(end 130.5 135.8)
		(width 0.1)
		(layer "In7.Cu")
		(net 407)
	)
	(segment
		(start 134.8 123.8)
		(end 132.8 125.8)
		(width 0.1)
		(layer "In7.Cu")
		(net 407)
	)
	(segment
		(start 131.6 134.7)
		(end 131.6 133.8)
		(width 0.1)
		(layer "In7.Cu")
		(net 407)
	)
	(segment
		(start 117.5 137.9)
		(end 119.6 135.8)
		(width 0.1)
		(layer "In7.Cu")
		(net 407)
	)
	(segment
		(start 132.8 125.8)
		(end 132.8 132.8)
		(width 0.1)
		(layer "In7.Cu")
		(net 407)
	)
	(segment
		(start 146.8 119.6)
		(end 142.6 123.8)
		(width 0.1)
		(layer "In7.Cu")
		(net 407)
	)
	(segment
		(start 101.269987 137.9)
		(end 117.5 137.9)
		(width 0.1)
		(layer "In7.Cu")
		(net 407)
	)
	(segment
		(start 149.93 119.8)
		(end 149.6 119.8)
		(width 0.1)
		(layer "In7.Cu")
		(net 407)
	)
	(segment
		(start 81.6 116.519468)
		(end 81.6 118.775736)
		(width 0.1)
		(layer "In7.Cu")
		(net 407)
	)
	(segment
		(start 85.424263 120.100001)
		(end 87.699998 122.375736)
		(width 0.1)
		(layer "In7.Cu")
		(net 407)
	)
	(segment
		(start 149.4 119.6)
		(end 146.8 119.6)
		(width 0.1)
		(layer "In7.Cu")
		(net 407)
	)
	(segment
		(start 80.855532 115.775)
		(end 81.6 116.519468)
		(width 0.1)
		(layer "In7.Cu")
		(net 407)
	)
	(segment
		(start 87.699998 122.375736)
		(end 87.699998 124.330011)
		(width 0.1)
		(layer "In7.Cu")
		(net 407)
	)
	(segment
		(start 149.6 119.8)
		(end 149.4 119.6)
		(width 0.1)
		(layer "In7.Cu")
		(net 407)
	)
	(segment
		(start 130.5 135.8)
		(end 131.6 134.7)
		(width 0.1)
		(layer "In7.Cu")
		(net 407)
	)
	(segment
		(start 81.6 118.775736)
		(end 82.924265 120.100001)
		(width 0.1)
		(layer "In7.Cu")
		(net 407)
	)
	(segment
		(start 110.78 98.5)
		(end 110.805 98.5)
		(width 0.19)
		(layer "B.Cu")
		(net 408)
	)
	(segment
		(start 110.805 98.5)
		(end 111.12 98.185)
		(width 0.19)
		(layer "B.Cu")
		(net 408)
	)
	(segment
		(start 111.799 98.185)
		(end 111.8 98.184)
		(width 0.19)
		(layer "B.Cu")
		(net 408)
	)
	(segment
		(start 111.8 98.184)
		(end 112.995 98.184)
		(width 0.19)
		(layer "B.Cu")
		(net 408)
	)
	(segment
		(start 112.995 98.184)
		(end 113.06 98.249)
		(width 0.19)
		(layer "B.Cu")
		(net 408)
	)
	(segment
		(start 113.06 98.249)
		(end 113.685 98.249)
		(width 0.19)
		(layer "B.Cu")
		(net 408)
	)
	(segment
		(start 111.12 98.185)
		(end 111.799 98.185)
		(width 0.19)
		(layer "B.Cu")
		(net 408)
	)
	(via
		(at 143.4 93.4)
		(size 0.45)
		(drill 0.1)
		(layers "F.Cu" "B.Cu")
		(net 409)
	)
	(via
		(at 142.430532 81.15)
		(size 0.45)
		(drill 0.1)
		(layers "F.Cu" "B.Cu")
		(net 409)
	)
	(via
		(at 82 135)
		(size 0.45)
		(drill 0.1)
		(layers "F.Cu" "B.Cu")
		(net 409)
	)
	(via
		(at 75.775532 109.425)
		(size 0.45)
		(drill 0.1)
		(layers "F.Cu" "B.Cu")
		(net 409)
	)
	(segment
		(start 143 87)
		(end 141.6 85.6)
		(width 0.1)
		(layer "B.Cu")
		(net 409)
	)
	(segment
		(start 141.6 85.6)
		(end 141.6 81.980532)
		(width 0.1)
		(layer "B.Cu")
		(net 409)
	)
	(segment
		(start 141.6 81.980532)
		(end 142.430532 81.15)
		(width 0.1)
		(layer "B.Cu")
		(net 409)
	)
	(segment
		(start 143 93)
		(end 143 87)
		(width 0.1)
		(layer "B.Cu")
		(net 409)
	)
	(segment
		(start 143.4 93.4)
		(end 143 93)
		(width 0.1)
		(layer "B.Cu")
		(net 409)
	)
	(segment
		(start 82 130.6)
		(end 83.6 129)
		(width 0.1)
		(layer "In5.Cu")
		(net 409)
	)
	(segment
		(start 105.6 129)
		(end 112.1 122.5)
		(width 0.1)
		(layer "In5.Cu")
		(net 409)
	)
	(segment
		(start 83.6 129)
		(end 105.6 129)
		(width 0.1)
		(layer "In5.Cu")
		(net 409)
	)
	(segment
		(start 112.1 122.5)
		(end 137.7 122.5)
		(width 0.1)
		(layer "In5.Cu")
		(net 409)
	)
	(segment
		(start 142.8 94)
		(end 143.4 93.4)
		(width 0.1)
		(layer "In5.Cu")
		(net 409)
	)
	(segment
		(start 137.7 122.5)
		(end 142.8 117.4)
		(width 0.1)
		(layer "In5.Cu")
		(net 409)
	)
	(segment
		(start 142.8 117.4)
		(end 142.8 94)
		(width 0.1)
		(layer "In5.Cu")
		(net 409)
	)
	(segment
		(start 82 135)
		(end 82 130.6)
		(width 0.1)
		(layer "In5.Cu")
		(net 409)
	)
	(segment
		(start 75.2 110.000532)
		(end 75.775532 109.425)
		(width 0.1)
		(layer "In7.Cu")
		(net 409)
	)
	(segment
		(start 82 134.1)
		(end 77.5 129.6)
		(width 0.1)
		(layer "In7.Cu")
		(net 409)
	)
	(segment
		(start 77.5 129.6)
		(end 77.5 118.2)
		(width 0.1)
		(layer "In7.Cu")
		(net 409)
	)
	(segment
		(start 74.9 112.1)
		(end 75.2 111.8)
		(width 0.1)
		(layer "In7.Cu")
		(net 409)
	)
	(segment
		(start 77.5 118.2)
		(end 74.9 115.6)
		(width 0.1)
		(layer "In7.Cu")
		(net 409)
	)
	(segment
		(start 82 135)
		(end 82 134.1)
		(width 0.1)
		(layer "In7.Cu")
		(net 409)
	)
	(segment
		(start 74.9 115.6)
		(end 74.9 112.1)
		(width 0.1)
		(layer "In7.Cu")
		(net 409)
	)
	(segment
		(start 75.2 111.8)
		(end 75.2 110.000532)
		(width 0.1)
		(layer "In7.Cu")
		(net 409)
	)
	(segment
		(start 110.695532 73.915)
		(end 110.695532 74.185)
		(width 0.19)
		(layer "F.Cu")
		(net 410)
	)
	(segment
		(start 110.695532 74.185)
		(end 110.580532 74.3)
		(width 0.19)
		(layer "F.Cu")
		(net 410)
	)
	(segment
		(start 110.430532 73.65)
		(end 110.695532 73.915)
		(width 0.19)
		(layer "F.Cu")
		(net 410)
	)
	(via
		(at 110.580532 74.3)
		(size 0.45)
		(drill 0.1)
		(layers "F.Cu" "B.Cu")
		(net 410)
	)
	(segment
		(start 108.33 91.50837)
		(end 110.32337 89.515)
		(width 0.19)
		(layer "B.Cu")
		(net 410)
	)
	(segment
		(start 112.115 80.52337)
		(end 112.715 79.92337)
		(width 0.19)
		(layer "B.Cu")
		(net 410)
	)
	(segment
		(start 111.32337 76.085)
		(end 110.715 75.47663)
		(width 0.19)
		(layer "B.Cu")
		(net 410)
	)
	(segment
		(start 110.580532 74.3)
		(end 110.695532 74.415)
		(width 0.19)
		(layer "B.Cu")
		(net 410)
	)
	(segment
		(start 112.52337 76.085)
		(end 111.32337 76.085)
		(width 0.19)
		(layer "B.Cu")
		(net 410)
	)
	(segment
		(start 109.48 98.185)
		(end 109.204382 98.185)
		(width 0.19)
		(layer "B.Cu")
		(net 410)
	)
	(segment
		(start 110.695532 74.780532)
		(end 110.715 74.8)
		(width 0.19)
		(layer "B.Cu")
		(net 410)
	)
	(segment
		(start 110.715 75.47663)
		(end 110.715 74.8)
		(width 0.19)
		(layer "B.Cu")
		(net 410)
	)
	(segment
		(start 111.415 83.07663)
		(end 111.415 81.92337)
		(width 0.19)
		(layer "B.Cu")
		(net 410)
	)
	(segment
		(start 110.32337 89.515)
		(end 111.72337 89.515)
		(width 0.19)
		(layer "B.Cu")
		(net 410)
	)
	(segment
		(start 112.115 81.22337)
		(end 112.115 80.52337)
		(width 0.19)
		(layer "B.Cu")
		(net 410)
	)
	(segment
		(start 111.72337 89.515)
		(end 112.715 88.52337)
		(width 0.19)
		(layer "B.Cu")
		(net 410)
	)
	(segment
		(start 112.715 84.37663)
		(end 111.415 83.07663)
		(width 0.19)
		(layer "B.Cu")
		(net 410)
	)
	(segment
		(start 109.204382 98.185)
		(end 108.33 97.310618)
		(width 0.19)
		(layer "B.Cu")
		(net 410)
	)
	(segment
		(start 108.33 97.310618)
		(end 108.33 91.50837)
		(width 0.19)
		(layer "B.Cu")
		(net 410)
	)
	(segment
		(start 111.415 81.92337)
		(end 112.115 81.22337)
		(width 0.19)
		(layer "B.Cu")
		(net 410)
	)
	(segment
		(start 110.695532 74.415)
		(end 110.695532 74.780532)
		(width 0.19)
		(layer "B.Cu")
		(net 410)
	)
	(segment
		(start 112.715 88.52337)
		(end 112.715 84.37663)
		(width 0.19)
		(layer "B.Cu")
		(net 410)
	)
	(segment
		(start 112.715 76.27663)
		(end 112.52337 76.085)
		(width 0.19)
		(layer "B.Cu")
		(net 410)
	)
	(segment
		(start 109.795 98.5)
		(end 109.48 98.185)
		(width 0.19)
		(layer "B.Cu")
		(net 410)
	)
	(segment
		(start 112.715 79.92337)
		(end 112.715 76.27663)
		(width 0.19)
		(layer "B.Cu")
		(net 410)
	)
	(segment
		(start 109.065532 75.885)
		(end 109.180532 76)
		(width 0.19)
		(layer "F.Cu")
		(net 411)
	)
	(segment
		(start 109.065532 75.415)
		(end 109.065532 75.885)
		(width 0.19)
		(layer "F.Cu")
		(net 411)
	)
	(segment
		(start 109.330532 75.15)
		(end 109.065532 75.415)
		(width 0.19)
		(layer "F.Cu")
		(net 411)
	)
	(via
		(at 109.180532 76)
		(size 0.45)
		(drill 0.1)
		(layers "F.Cu" "B.Cu")
		(net 411)
	)
	(segment
		(start 99.7 87.36163)
		(end 99.7 93.914362)
		(width 0.19)
		(layer "B.Cu")
		(net 411)
	)
	(segment
		(start 109.065532 76.115)
		(end 109.065532 76.996098)
		(width 0.19)
		(layer "B.Cu")
		(net 411)
	)
	(segment
		(start 108.47663 77.585)
		(end 106.07663 77.585)
		(width 0.19)
		(layer "B.Cu")
		(net 411)
	)
	(segment
		(start 99.7 94.994362)
		(end 99.7 100.885282)
		(width 0.19)
		(layer "B.Cu")
		(net 411)
	)
	(segment
		(start 99.972477 94.754362)
		(end 99.94 94.754362)
		(width 0.19)
		(layer "B.Cu")
		(net 411)
	)
	(segment
		(start 104.67663 78.985)
		(end 103.67663 78.985)
		(width 0.19)
		(layer "B.Cu")
		(net 411)
	)
	(segment
		(start 99.94 94.154362)
		(end 99.972477 94.154362)
		(width 0.19)
		(layer "B.Cu")
		(net 411)
	)
	(segment
		(start 109.745 106.5)
		(end 109.77 106.5)
		(width 0.19)
		(layer "B.Cu")
		(net 411)
	)
	(segment
		(start 103.085 82.67663)
		(end 101.085 84.67663)
		(width 0.19)
		(layer "B.Cu")
		(net 411)
	)
	(segment
		(start 103.67663 78.985)
		(end 103.085 79.57663)
		(width 0.19)
		(layer "B.Cu")
		(net 411)
	)
	(segment
		(start 101.085 84.67663)
		(end 101.085 85.97663)
		(width 0.19)
		(layer "B.Cu")
		(net 411)
	)
	(segment
		(start 99.7 100.885282)
		(end 105.629718 106.815)
		(width 0.19)
		(layer "B.Cu")
		(net 411)
	)
	(segment
		(start 109.065532 76.996098)
		(end 108.47663 77.585)
		(width 0.19)
		(layer "B.Cu")
		(net 411)
	)
	(segment
		(start 103.085 79.57663)
		(end 103.085 82.67663)
		(width 0.19)
		(layer "B.Cu")
		(net 411)
	)
	(segment
		(start 109.180532 76)
		(end 109.065532 76.115)
		(width 0.19)
		(layer "B.Cu")
		(net 411)
	)
	(segment
		(start 105.629718 106.815)
		(end 109.43 106.815)
		(width 0.19)
		(layer "B.Cu")
		(net 411)
	)
	(segment
		(start 100.212477 94.394362)
		(end 100.212477 94.514362)
		(width 0.19)
		(layer "B.Cu")
		(net 411)
	)
	(segment
		(start 106.07663 77.585)
		(end 104.67663 78.985)
		(width 0.19)
		(layer "B.Cu")
		(net 411)
	)
	(segment
		(start 109.43 106.815)
		(end 109.745 106.5)
		(width 0.19)
		(layer "B.Cu")
		(net 411)
	)
	(segment
		(start 101.085 85.97663)
		(end 99.7 87.36163)
		(width 0.19)
		(layer "B.Cu")
		(net 411)
	)
	(arc
		(start 99.972477 94.154362)
		(mid 100.142183 94.224656)
		(end 100.212477 94.394362)
		(width 0.19)
		(layer "B.Cu")
		(net 411)
	)
	(arc
		(start 100.212477 94.514362)
		(mid 100.142183 94.684068)
		(end 99.972477 94.754362)
		(width 0.19)
		(layer "B.Cu")
		(net 411)
	)
	(arc
		(start 99.94 94.754362)
		(mid 99.770294 94.824656)
		(end 99.7 94.994362)
		(width 0.19)
		(layer "B.Cu")
		(net 411)
	)
	(arc
		(start 99.7 93.914362)
		(mid 99.770294 94.084068)
		(end 99.94 94.154362)
		(width 0.19)
		(layer "B.Cu")
		(net 411)
	)
	(segment
		(start 111.07 106.815)
		(end 112.995 106.815)
		(width 0.19)
		(layer "B.Cu")
		(net 415)
	)
	(segment
		(start 110.73 106.5)
		(end 110.755 106.5)
		(width 0.19)
		(layer "B.Cu")
		(net 415)
	)
	(segment
		(start 112.995 106.815)
		(end 113.06 106.75)
		(width 0.19)
		(layer "B.Cu")
		(net 415)
	)
	(segment
		(start 110.755 106.5)
		(end 111.07 106.815)
		(width 0.19)
		(layer "B.Cu")
		(net 415)
	)
	(segment
		(start 113.06 106.75)
		(end 113.685 106.75)
		(width 0.19)
		(layer "B.Cu")
		(net 415)
	)
	(via
		(at 136.830532 73.65)
		(size 0.45)
		(drill 0.1)
		(layers "F.Cu" "B.Cu")
		(net 416)
	)
	(via
		(at 75.775532 81.485)
		(size 0.45)
		(drill 0.1)
		(layers "F.Cu" "B.Cu")
		(net 416)
	)
	(segment
		(start 85.2 75.55)
		(end 90.5 75.55)
		(width 0.1)
		(layer "In5.Cu")
		(net 416)
	)
	(segment
		(start 98.05 74.3)
		(end 99.2 73.15)
		(width 0.1)
		(layer "In5.Cu")
		(net 416)
	)
	(segment
		(start 81.65 79.1)
		(end 85.2 75.55)
		(width 0.1)
		(layer "In5.Cu")
		(net 416)
	)
	(segment
		(start 81 80.8)
		(end 81.65 80.15)
		(width 0.1)
		(layer "In5.Cu")
		(net 416)
	)
	(segment
		(start 81.65 80.15)
		(end 81.65 79.1)
		(width 0.1)
		(layer "In5.Cu")
		(net 416)
	)
	(segment
		(start 126.9 69.7)
		(end 133.5 69.7)
		(width 0.1)
		(layer "In5.Cu")
		(net 416)
	)
	(segment
		(start 100.9 73.45)
		(end 100.9 73.9)
		(width 0.1)
		(layer "In5.Cu")
		(net 416)
	)
	(segment
		(start 103 69.6)
		(end 103.5 69.1)
		(width 0.1)
		(layer "In5.Cu")
		(net 416)
	)
	(segment
		(start 136.830532 71.1)
		(end 136.830532 73.65)
		(width 0.1)
		(layer "In5.Cu")
		(net 416)
	)
	(segment
		(start 94.45 74.3)
		(end 98.05 74.3)
		(width 0.1)
		(layer "In5.Cu")
		(net 416)
	)
	(segment
		(start 99.2 73.15)
		(end 100.6 73.15)
		(width 0.1)
		(layer "In5.Cu")
		(net 416)
	)
	(segment
		(start 94 74.75)
		(end 94.45 74.3)
		(width 0.1)
		(layer "In5.Cu")
		(net 416)
	)
	(segment
		(start 126.3 69.1)
		(end 126.9 69.7)
		(width 0.1)
		(layer "In5.Cu")
		(net 416)
	)
	(segment
		(start 75.775532 81.485)
		(end 76.460532 80.8)
		(width 0.1)
		(layer "In5.Cu")
		(net 416)
	)
	(segment
		(start 91.3 74.75)
		(end 94 74.75)
		(width 0.1)
		(layer "In5.Cu")
		(net 416)
	)
	(segment
		(start 101.7 74.7)
		(end 102.4 74.7)
		(width 0.1)
		(layer "In5.Cu")
		(net 416)
	)
	(segment
		(start 103 74.1)
		(end 103 69.6)
		(width 0.1)
		(layer "In5.Cu")
		(net 416)
	)
	(segment
		(start 133.5 69.7)
		(end 134.3 70.5)
		(width 0.1)
		(layer "In5.Cu")
		(net 416)
	)
	(segment
		(start 102.4 74.7)
		(end 103 74.1)
		(width 0.1)
		(layer "In5.Cu")
		(net 416)
	)
	(segment
		(start 103.5 69.1)
		(end 126.3 69.1)
		(width 0.1)
		(layer "In5.Cu")
		(net 416)
	)
	(segment
		(start 90.5 75.55)
		(end 91.3 74.75)
		(width 0.1)
		(layer "In5.Cu")
		(net 416)
	)
	(segment
		(start 136.230532 70.5)
		(end 136.830532 71.1)
		(width 0.1)
		(layer "In5.Cu")
		(net 416)
	)
	(segment
		(start 76.460532 80.8)
		(end 81 80.8)
		(width 0.1)
		(layer "In5.Cu")
		(net 416)
	)
	(segment
		(start 100.6 73.15)
		(end 100.9 73.45)
		(width 0.1)
		(layer "In5.Cu")
		(net 416)
	)
	(segment
		(start 100.9 73.9)
		(end 101.7 74.7)
		(width 0.1)
		(layer "In5.Cu")
		(net 416)
	)
	(segment
		(start 134.3 70.5)
		(end 136.230532 70.5)
		(width 0.1)
		(layer "In5.Cu")
		(net 416)
	)
	(segment
		(start 111.07 104.185)
		(end 110.755 104.5)
		(width 0.19)
		(layer "B.Cu")
		(net 417)
	)
	(segment
		(start 110.755 104.5)
		(end 110.73 104.5)
		(width 0.19)
		(layer "B.Cu")
		(net 417)
	)
	(segment
		(start 113.06 104.25)
		(end 112.995 104.185)
		(width 0.19)
		(layer "B.Cu")
		(net 417)
	)
	(segment
		(start 113.685 104.25)
		(end 113.06 104.25)
		(width 0.19)
		(layer "B.Cu")
		(net 417)
	)
	(segment
		(start 112.995 104.185)
		(end 111.07 104.185)
		(width 0.19)
		(layer "B.Cu")
		(net 417)
	)
	(segment
		(start 108.695532 72.685)
		(end 108.580532 72.8)
		(width 0.19)
		(layer "F.Cu")
		(net 418)
	)
	(segment
		(start 108.430532 72.15)
		(end 108.695532 72.415)
		(width 0.19)
		(layer "F.Cu")
		(net 418)
	)
	(segment
		(start 108.695532 72.415)
		(end 108.695532 72.685)
		(width 0.19)
		(layer "F.Cu")
		(net 418)
	)
	(via
		(at 108.580532 72.8)
		(size 0.45)
		(drill 0.1)
		(layers "F.Cu" "B.Cu")
		(net 418)
	)
	(segment
		(start 106.715 84.72337)
		(end 106.715 83.02337)
		(width 0.19)
		(layer "B.Cu")
		(net 418)
	)
	(segment
		(start 109.415 80.52337)
		(end 110.015 79.92337)
		(width 0.19)
		(layer "B.Cu")
		(net 418)
	)
	(segment
		(start 109.315 77.52337)
		(end 110.015 76.82337)
		(width 0.19)
		(layer "B.Cu")
		(net 418)
	)
	(segment
		(start 109.415 81.12337)
		(end 109.415 80.52337)
		(width 0.19)
		(layer "B.Cu")
		(net 418)
	)
	(segment
		(start 109.315 78.57663)
		(end 109.315 77.52337)
		(width 0.19)
		(layer "B.Cu")
		(net 418)
	)
	(segment
		(start 109.745 104.5)
		(end 109.43 104.185)
		(width 0.19)
		(layer "B.Cu")
		(net 418)
	)
	(segment
		(start 110.015 79.27663)
		(end 109.315 78.57663)
		(width 0.19)
		(layer "B.Cu")
		(net 418)
	)
	(segment
		(start 108.715 74.87663)
		(end 108.715 73.3)
		(width 0.19)
		(layer "B.Cu")
		(net 418)
	)
	(segment
		(start 108.695532 72.915)
		(end 108.695532 73.280532)
		(width 0.19)
		(layer "B.Cu")
		(net 418)
	)
	(segment
		(start 110.015 79.92337)
		(end 110.015 79.27663)
		(width 0.19)
		(layer "B.Cu")
		(net 418)
	)
	(segment
		(start 106.7191 104.185)
		(end 102.33 99.7959)
		(width 0.19)
		(layer "B.Cu")
		(net 418)
	)
	(segment
		(start 108.580532 72.8)
		(end 108.695532 72.915)
		(width 0.19)
		(layer "B.Cu")
		(net 418)
	)
	(segment
		(start 109.12337 81.415)
		(end 109.415 81.12337)
		(width 0.19)
		(layer "B.Cu")
		(net 418)
	)
	(segment
		(start 108.32337 81.415)
		(end 109.12337 81.415)
		(width 0.19)
		(layer "B.Cu")
		(net 418)
	)
	(segment
		(start 102.33 99.7959)
		(end 102.33 89.10837)
		(width 0.19)
		(layer "B.Cu")
		(net 418)
	)
	(segment
		(start 110.015 76.17663)
		(end 108.715 74.87663)
		(width 0.19)
		(layer "B.Cu")
		(net 418)
	)
	(segment
		(start 102.33 89.10837)
		(end 106.715 84.72337)
		(width 0.19)
		(layer "B.Cu")
		(net 418)
	)
	(segment
		(start 110.015 76.82337)
		(end 110.015 76.17663)
		(width 0.19)
		(layer "B.Cu")
		(net 418)
	)
	(segment
		(start 108.695532 73.280532)
		(end 108.715 73.3)
		(width 0.19)
		(layer "B.Cu")
		(net 418)
	)
	(segment
		(start 106.715 83.02337)
		(end 108.32337 81.415)
		(width 0.19)
		(layer "B.Cu")
		(net 418)
	)
	(segment
		(start 109.77 104.5)
		(end 109.745 104.5)
		(width 0.19)
		(layer "B.Cu")
		(net 418)
	)
	(segment
		(start 109.43 104.185)
		(end 106.7191 104.185)
		(width 0.19)
		(layer "B.Cu")
		(net 418)
	)
	(segment
		(start 131.7 111.2)
		(end 130.2 111.2)
		(width 0.1)
		(layer "F.Cu")
		(net 421)
	)
	(segment
		(start 130.2 111.2)
		(end 129.8 110.8)
		(width 0.1)
		(layer "F.Cu")
		(net 421)
	)
	(segment
		(start 129.8 110.8)
		(end 128.3 110.8)
		(width 0.1)
		(layer "F.Cu")
		(net 421)
	)
	(via
		(at 139.530532 73.65)
		(size 0.45)
		(drill 0.1)
		(layers "F.Cu" "B.Cu")
		(net 421)
	)
	(via
		(at 77.9 107.5)
		(size 0.45)
		(drill 0.1)
		(layers "F.Cu" "B.Cu")
		(net 421)
	)
	(via
		(at 128.3 110.8)
		(size 0.45)
		(drill 0.1)
		(layers "F.Cu" "B.Cu")
		(free yes)
		(net 421)
	)
	(via
		(at 131.7 111.2)
		(size 0.45)
		(drill 0.1)
		(layers "F.Cu" "B.Cu")
		(net 421)
	)
	(segment
		(start 75.775532 108.175532)
		(end 76.3 108.7)
		(width 0.1)
		(layer "B.Cu")
		(net 421)
	)
	(segment
		(start 77.5 108.7)
		(end 77.6 108.6)
		(width 0.1)
		(layer "B.Cu")
		(net 421)
	)
	(segment
		(start 75.775532 108.155)
		(end 75.775532 108.175532)
		(width 0.1)
		(layer "B.Cu")
		(net 421)
	)
	(segment
		(start 77.6 108.6)
		(end 77.6 107.8)
		(width 0.1)
		(layer "B.Cu")
		(net 421)
	)
	(segment
		(start 77.6 107.8)
		(end 77.9 107.5)
		(width 0.1)
		(layer "B.Cu")
		(net 421)
	)
	(segment
		(start 76.3 108.7)
		(end 77.5 108.7)
		(width 0.1)
		(layer "B.Cu")
		(net 421)
	)
	(segment
		(start 110.634314 107.8)
		(end 105.257843 107.8)
		(width 0.1)
		(layer "In5.Cu")
		(net 421)
	)
	(segment
		(start 130.1 110.8)
		(end 130.1 95.9)
		(width 0.1)
		(layer "In5.Cu")
		(net 421)
	)
	(segment
		(start 113.897056 110.4)
		(end 113 109.502944)
		(width 0.1)
		(layer "In5.Cu")
		(net 421)
	)
	(segment
		(start 128.3 110.8)
		(end 127.4 110.8)
		(width 0.1)
		(layer "In5.Cu")
		(net 421)
	)
	(segment
		(start 130.4 92.6)
		(end 135.6 87.4)
		(width 0.1)
		(layer "In5.Cu")
		(net 421)
	)
	(segment
		(start 131.7 111.2)
		(end 130.5 111.2)
		(width 0.1)
		(layer "In5.Cu")
		(net 421)
	)
	(segment
		(start 81 119)
		(end 80 118)
		(width 0.1)
		(layer "In5.Cu")
		(net 421)
	)
	(segment
		(start 136.55 85.85)
		(end 136.55 81.45)
		(width 0.1)
		(layer "In5.Cu")
		(net 421)
	)
	(segment
		(start 89.65 118.4)
		(end 89.4 118.15)
		(width 0.1)
		(layer "In5.Cu")
		(net 421)
	)
	(segment
		(start 136.55 81.45)
		(end 137.3 80.7)
		(width 0.1)
		(layer "In5.Cu")
		(net 421)
	)
	(segment
		(start 127.4 110.8)
		(end 127 110.4)
		(width 0.1)
		(layer "In5.Cu")
		(net 421)
	)
	(segment
		(start 111.434314 108.6)
		(end 110.634314 107.8)
		(width 0.1)
		(layer "In5.Cu")
		(net 421)
	)
	(segment
		(start 78.875 108.475)
		(end 77.9 107.5)
		(width 0.1)
		(layer "In5.Cu")
		(net 421)
	)
	(segment
		(start 113 108.965686)
		(end 112.634314 108.6)
		(width 0.1)
		(layer "In5.Cu")
		(net 421)
	)
	(segment
		(start 89.4 118.15)
		(end 87.15 118.15)
		(width 0.1)
		(layer "In5.Cu")
		(net 421)
	)
	(segment
		(start 137.3 79.5)
		(end 138.4 78.4)
		(width 0.1)
		(layer "In5.Cu")
		(net 421)
	)
	(segment
		(start 135.6 87.4)
		(end 135.6 86.8)
		(width 0.1)
		(layer "In5.Cu")
		(net 421)
	)
	(segment
		(start 95.182843 118.4)
		(end 89.65 118.4)
		(width 0.1)
		(layer "In5.Cu")
		(net 421)
	)
	(segment
		(start 130.5 111.2)
		(end 130.1 110.8)
		(width 0.1)
		(layer "In5.Cu")
		(net 421)
	)
	(segment
		(start 138.4 78.4)
		(end 138.4 77.8)
		(width 0.1)
		(layer "In5.Cu")
		(net 421)
	)
	(segment
		(start 135.6 86.8)
		(end 136.55 85.85)
		(width 0.1)
		(layer "In5.Cu")
		(net 421)
	)
	(segment
		(start 138.190266 77.590266)
		(end 138.190266 74.990266)
		(width 0.1)
		(layer "In5.Cu")
		(net 421)
	)
	(segment
		(start 86.3 119)
		(end 81 119)
		(width 0.1)
		(layer "In5.Cu")
		(net 421)
	)
	(segment
		(start 80 118)
		(end 80 109.25)
		(width 0.1)
		(layer "In5.Cu")
		(net 421)
	)
	(segment
		(start 112.634314 108.6)
		(end 111.434314 108.6)
		(width 0.1)
		(layer "In5.Cu")
		(net 421)
	)
	(segment
		(start 127 110.4)
		(end 113.897056 110.4)
		(width 0.1)
		(layer "In5.Cu")
		(net 421)
	)
	(segment
		(start 101.2 112.382843)
		(end 95.182843 118.4)
		(width 0.1)
		(layer "In5.Cu")
		(net 421)
	)
	(segment
		(start 130.4 95.6)
		(end 130.4 92.6)
		(width 0.1)
		(layer "In5.Cu")
		(net 421)
	)
	(segment
		(start 137.3 80.7)
		(end 137.3 79.5)
		(width 0.1)
		(layer "In5.Cu")
		(net 421)
	)
	(segment
		(start 87.15 118.15)
		(end 86.3 119)
		(width 0.1)
		(layer "In5.Cu")
		(net 421)
	)
	(segment
		(start 104.45 108.607843)
		(end 104.157843 108.607843)
		(width 0.1)
		(layer "In5.Cu")
		(net 421)
	)
	(segment
		(start 130.1 95.9)
		(end 130.4 95.6)
		(width 0.1)
		(layer "In5.Cu")
		(net 421)
	)
	(segment
		(start 138.4 77.8)
		(end 138.190266 77.590266)
		(width 0.1)
		(layer "In5.Cu")
		(net 421)
	)
	(segment
		(start 113 109.502944)
		(end 113 108.965686)
		(width 0.1)
		(layer "In5.Cu")
		(net 421)
	)
	(segment
		(start 79.225 108.475)
		(end 78.875 108.475)
		(width 0.1)
		(layer "In5.Cu")
		(net 421)
	)
	(segment
		(start 104.157843 108.607843)
		(end 101.2 111.565686)
		(width 0.1)
		(layer "In5.Cu")
		(net 421)
	)
	(segment
		(start 105.257843 107.8)
		(end 104.45 108.607843)
		(width 0.1)
		(layer "In5.Cu")
		(net 421)
	)
	(segment
		(start 101.2 111.565686)
		(end 101.2 112.382843)
		(width 0.1)
		(layer "In5.Cu")
		(net 421)
	)
	(segment
		(start 138.190266 74.990266)
		(end 139.530532 73.65)
		(width 0.1)
		(layer "In5.Cu")
		(net 421)
	)
	(segment
		(start 80 109.25)
		(end 79.225 108.475)
		(width 0.1)
		(layer "In5.Cu")
		(net 421)
	)
	(segment
		(start 113.685 101.25)
		(end 113.06 101.25)
		(width 0.19)
		(layer "B.Cu")
		(net 423)
	)
	(segment
		(start 112.995 101.185)
		(end 111.12 101.185)
		(width 0.19)
		(layer "B.Cu")
		(net 423)
	)
	(segment
		(start 111.12 101.185)
		(end 110.805 101.5)
		(width 0.19)
		(layer "B.Cu")
		(net 423)
	)
	(segment
		(start 110.805 101.5)
		(end 110.78 101.5)
		(width 0.19)
		(layer "B.Cu")
		(net 423)
	)
	(segment
		(start 113.06 101.25)
		(end 112.995 101.185)
		(width 0.19)
		(layer "B.Cu")
		(net 423)
	)
	(segment
		(start 70.4 73.1)
		(end 74.505532 77.205532)
		(width 0.1)
		(layer "B.Cu")
		(net 431)
	)
	(segment
		(start 74.505532 77.205532)
		(end 74.505532 78.945)
		(width 0.1)
		(layer "B.Cu")
		(net 431)
	)
	(segment
		(start 63 73.1)
		(end 70.4 73.1)
		(width 0.1)
		(layer "B.Cu")
		(net 431)
	)
	(segment
		(start 110.430532 76.65)
		(end 110.695532 76.915)
		(width 0.19)
		(layer "F.Cu")
		(net 435)
	)
	(segment
		(start 110.695532 76.915)
		(end 110.695532 77.385)
		(width 0.19)
		(layer "F.Cu")
		(net 435)
	)
	(segment
		(start 110.695532 77.385)
		(end 110.580532 77.5)
		(width 0.19)
		(layer "F.Cu")
		(net 435)
	)
	(via
		(at 110.580532 77.5)
		(size 0.45)
		(drill 0.1)
		(layers "F.Cu" "B.Cu")
		(net 435)
	)
	(segment
		(start 109.415 83.42337)
		(end 109.415 84.67663)
		(width 0.19)
		(layer "B.Cu")
		(net 435)
	)
	(segment
		(start 107.72337 87.715)
		(end 105.315 90.12337)
		(width 0.19)
		(layer "B.Cu")
		(net 435)
	)
	(segment
		(start 110.015 85.27663)
		(end 110.015 86.42337)
		(width 0.19)
		(layer "B.Cu")
		(net 435)
	)
	(segment
		(start 110.695532 81.342838)
		(end 110.215 81.82337)
		(width 0.19)
		(layer "B.Cu")
		(net 435)
	)
	(segment
		(start 110.215 82.62337)
		(end 109.415 83.42337)
		(width 0.19)
		(layer "B.Cu")
		(net 435)
	)
	(segment
		(start 105.315 90.12337)
		(end 105.315 98.53826)
		(width 0.19)
		(layer "B.Cu")
		(net 435)
	)
	(segment
		(start 110.215 81.82337)
		(end 110.215 82.62337)
		(width 0.19)
		(layer "B.Cu")
		(net 435)
	)
	(segment
		(start 111.315 80.02337)
		(end 110.695532 80.642838)
		(width 0.19)
		(layer "B.Cu")
		(net 435)
	)
	(segment
		(start 110.695532 80.642838)
		(end 110.695532 81.342838)
		(width 0.19)
		(layer "B.Cu")
		(net 435)
	)
	(segment
		(start 110.695532 78.557162)
		(end 111.315 79.17663)
		(width 0.19)
		(layer "B.Cu")
		(net 435)
	)
	(segment
		(start 110.015 86.42337)
		(end 108.72337 87.715)
		(width 0.19)
		(layer "B.Cu")
		(net 435)
	)
	(segment
		(start 108.72337 87.715)
		(end 107.72337 87.715)
		(width 0.19)
		(layer "B.Cu")
		(net 435)
	)
	(segment
		(start 111.315 79.17663)
		(end 111.315 80.02337)
		(width 0.19)
		(layer "B.Cu")
		(net 435)
	)
	(segment
		(start 110.695532 77.615)
		(end 110.695532 78.557162)
		(width 0.19)
		(layer "B.Cu")
		(net 435)
	)
	(segment
		(start 105.315 98.53826)
		(end 107.96174 101.185)
		(width 0.19)
		(layer "B.Cu")
		(net 435)
	)
	(segment
		(start 109.48 101.185)
		(end 109.795 101.5)
		(width 0.19)
		(layer "B.Cu")
		(net 435)
	)
	(segment
		(start 110.580532 77.5)
		(end 110.695532 77.615)
		(width 0.19)
		(layer "B.Cu")
		(net 435)
	)
	(segment
		(start 109.415 84.67663)
		(end 110.015 85.27663)
		(width 0.19)
		(layer "B.Cu")
		(net 435)
	)
	(segment
		(start 107.96174 101.185)
		(end 109.48 101.185)
		(width 0.19)
		(layer "B.Cu")
		(net 435)
	)
	(segment
		(start 112.995 97.814)
		(end 113.06 97.749)
		(width 0.19)
		(layer "B.Cu")
		(net 436)
	)
	(segment
		(start 111.12 97.815)
		(end 111.657408 97.815)
		(width 0.19)
		(layer "B.Cu")
		(net 436)
	)
	(segment
		(start 111.657408 97.815)
		(end 111.658408 97.814)
		(width 0.19)
		(layer "B.Cu")
		(net 436)
	)
	(segment
		(start 110.805 97.5)
		(end 111.12 97.815)
		(width 0.19)
		(layer "B.Cu")
		(net 436)
	)
	(segment
		(start 110.78 97.5)
		(end 110.805 97.5)
		(width 0.19)
		(layer "B.Cu")
		(net 436)
	)
	(segment
		(start 113.06 97.749)
		(end 113.685 97.749)
		(width 0.19)
		(layer "B.Cu")
		(net 436)
	)
	(segment
		(start 111.658408 97.814)
		(end 112.995 97.814)
		(width 0.19)
		(layer "B.Cu")
		(net 436)
	)
	(segment
		(start 85.4 133.6)
		(end 85.8 134)
		(width 0.1)
		(layer "F.Cu")
		(net 438)
	)
	(segment
		(start 76.5 122.1)
		(end 76.5 125.2)
		(width 0.1)
		(layer "F.Cu")
		(net 438)
	)
	(segment
		(start 75.775 117.05)
		(end 75.35 117.05)
		(width 0.1)
		(layer "F.Cu")
		(net 438)
	)
	(segment
		(start 75.4 121)
		(end 76.5 122.1)
		(width 0.1)
		(layer "F.Cu")
		(net 438)
	)
	(segment
		(start 72.8 117.3)
		(end 72.8 119.6)
		(width 0.1)
		(layer "F.Cu")
		(net 438)
	)
	(segment
		(start 83.66863 133.6)
		(end 85.4 133.6)
		(width 0.1)
		(layer "F.Cu")
		(net 438)
	)
	(segment
		(start 86.8 138)
		(end 87.7 138)
		(width 0.1)
		(layer "F.Cu")
		(net 438)
	)
	(segment
		(start 78.5 129.8)
		(end 79.86863 129.8)
		(width 0.1)
		(layer "F.Cu")
		(net 438)
	)
	(segment
		(start 77.9 129.2)
		(end 78.5 129.8)
		(width 0.1)
		(layer "F.Cu")
		(net 438)
	)
	(segment
		(start 77.9 126.6)
		(end 77.9 129.2)
		(width 0.1)
		(layer "F.Cu")
		(net 438)
	)
	(segment
		(start 79.86863 129.8)
		(end 83.66863 133.6)
		(width 0.1)
		(layer "F.Cu")
		(net 438)
	)
	(segment
		(start 76.5 125.2)
		(end 77.9 126.6)
		(width 0.1)
		(layer "F.Cu")
		(net 438)
	)
	(segment
		(start 74.2 121)
		(end 75.4 121)
		(width 0.1)
		(layer "F.Cu")
		(net 438)
	)
	(segment
		(start 85.8 134)
		(end 85.8 137)
		(width 0.1)
		(layer "F.Cu")
		(net 438)
	)
	(segment
		(start 75.35 117.05)
		(end 74.975 116.675)
		(width 0.1)
		(layer "F.Cu")
		(net 438)
	)
	(segment
		(start 85.8 137)
		(end 86.8 138)
		(width 0.1)
		(layer "F.Cu")
		(net 438)
	)
	(segment
		(start 73.425 116.675)
		(end 72.8 117.3)
		(width 0.1)
		(layer "F.Cu")
		(net 438)
	)
	(segment
		(start 72.8 119.6)
		(end 74.2 121)
		(width 0.1)
		(layer "F.Cu")
		(net 438)
	)
	(segment
		(start 74.975 116.675)
		(end 73.425 116.675)
		(width 0.1)
		(layer "F.Cu")
		(net 438)
	)
	(via
		(at 75.775 117.05)
		(size 0.45)
		(drill 0.1)
		(layers "F.Cu" "B.Cu")
		(net 438)
	)
	(via
		(at 146.6 93.4)
		(size 0.45)
		(drill 0.1)
		(layers "F.Cu" "B.Cu")
		(net 438)
	)
	(via
		(at 139.530532 82.65)
		(size 0.45)
		(drill 0.1)
		(layers "F.Cu" "B.Cu")
		(net 438)
	)
	(via
		(at 87.7 138)
		(size 0.45)
		(drill 0.1)
		(layers "F.Cu" "B.Cu")
		(net 438)
	)
	(segment
		(start 140.15 86.5)
		(end 140.15 83.75)
		(width 0.1)
		(layer "B.Cu")
		(net 438)
	)
	(segment
		(start 145.8 95)
		(end 142.8 95)
		(width 0.1)
		(layer "B.Cu")
		(net 438)
	)
	(segment
		(start 140.15 83.75)
		(end 139.530532 83.130532)
		(width 0.1)
		(layer "B.Cu")
		(net 438)
	)
	(segment
		(start 146.6 94.2)
		(end 145.8 95)
		(width 0.1)
		(layer "B.Cu")
		(net 438)
	)
	(segment
		(start 142.8 95)
		(end 141.6 93.8)
		(width 0.1)
		(layer "B.Cu")
		(net 438)
	)
	(segment
		(start 139.530532 83.130532)
		(end 139.530532 82.65)
		(width 0.1)
		(layer "B.Cu")
		(net 438)
	)
	(segment
		(start 141.6 87.95)
		(end 140.15 86.5)
		(width 0.1)
		(layer "B.Cu")
		(net 438)
	)
	(segment
		(start 146.6 93.4)
		(end 146.6 94.2)
		(width 0.1)
		(layer "B.Cu")
		(net 438)
	)
	(segment
		(start 141.6 93.8)
		(end 141.6 87.95)
		(width 0.1)
		(layer "B.Cu")
		(net 438)
	)
	(segment
		(start 146.6 118.125484)
		(end 146.6 107.4)
		(width 0.1)
		(layer "In5.Cu")
		(net 438)
	)
	(segment
		(start 96.5125 133.5125)
		(end 100.7875 133.5125)
		(width 0.1)
		(layer "In5.Cu")
		(net 438)
	)
	(segment
		(start 87.7 138)
		(end 92.025 138)
		(width 0.1)
		(layer "In5.Cu")
		(net 438)
	)
	(segment
		(start 139.025484 125.7)
		(end 146.6 118.125484)
		(width 0.1)
		(layer "In5.Cu")
		(net 438)
	)
	(segment
		(start 146.1 104.2)
		(end 146.6 103.7)
		(width 0.1)
		(layer "In5.Cu")
		(net 438)
	)
	(segment
		(start 101.7 132.6)
		(end 106.525484 132.6)
		(width 0.1)
		(layer "In5.Cu")
		(net 438)
	)
	(segment
		(start 146.1 106.9)
		(end 146.1 104.2)
		(width 0.1)
		(layer "In5.Cu")
		(net 438)
	)
	(segment
		(start 146.6 103.7)
		(end 146.6 93.4)
		(width 0.1)
		(layer "In5.Cu")
		(net 438)
	)
	(segment
		(start 146.6 107.4)
		(end 146.1 106.9)
		(width 0.1)
		(layer "In5.Cu")
		(net 438)
	)
	(segment
		(start 113.425484 125.7)
		(end 139.025484 125.7)
		(width 0.1)
		(layer "In5.Cu")
		(net 438)
	)
	(segment
		(start 92.025 138)
		(end 96.5125 133.5125)
		(width 0.1)
		(layer "In5.Cu")
		(net 438)
	)
	(segment
		(start 100.7875 133.5125)
		(end 101.7 132.6)
		(width 0.1)
		(layer "In5.Cu")
		(net 438)
	)
	(segment
		(start 106.525484 132.6)
		(end 113.425484 125.7)
		(width 0.1)
		(layer "In5.Cu")
		(net 438)
	)
	(segment
		(start 111.065532 74.185)
		(end 111.180532 74.3)
		(width 0.19)
		(layer "F.Cu")
		(net 439)
	)
	(segment
		(start 111.330532 73.65)
		(end 111.065532 73.915)
		(width 0.19)
		(layer "F.Cu")
		(net 439)
	)
	(segment
		(start 111.065532 73.915)
		(end 111.065532 74.185)
		(width 0.19)
		(layer "F.Cu")
		(net 439)
	)
	(via
		(at 111.180532 74.3)
		(size 0.45)
		(drill 0.1)
		(layers "F.Cu" "B.Cu")
		(net 439)
	)
	(segment
		(start 112.67663 75.715)
		(end 113.085 76.12337)
		(width 0.19)
		(layer "B.Cu")
		(net 439)
	)
	(segment
		(start 109.48 97.815)
		(end 109.795 97.5)
		(width 0.19)
		(layer "B.Cu")
		(net 439)
	)
	(segment
		(start 111.085 75.32337)
		(end 111.47663 75.715)
		(width 0.19)
		(layer "B.Cu")
		(net 439)
	)
	(segment
		(start 111.085 74.658408)
		(end 111.085 75.32337)
		(width 0.19)
		(layer "B.Cu")
		(net 439)
	)
	(segment
		(start 111.065532 74.63894)
		(end 111.085 74.658408)
		(width 0.19)
		(layer "B.Cu")
		(net 439)
	)
	(segment
		(start 108.699999 94.735272)
		(end 108.699999 97.157359)
		(width 0.19)
		(layer "B.Cu")
		(net 439)
	)
	(segment
		(start 108.899999 94.035272)
		(end 108.978154 94.035272)
		(width 0.19)
		(layer "B.Cu")
		(net 439)
	)
	(segment
		(start 109.35764 97.815)
		(end 109.48 97.815)
		(width 0.19)
		(layer "B.Cu")
		(net 439)
	)
	(segment
		(start 108.699999 97.157359)
		(end 109.35764 97.815)
		(width 0.19)
		(layer "B.Cu")
		(net 439)
	)
	(segment
		(start 111.065532 74.415)
		(end 111.065532 74.63894)
		(width 0.19)
		(layer "B.Cu")
		(net 439)
	)
	(segment
		(start 110.47663 89.885)
		(end 108.699999 91.661631)
		(width 0.19)
		(layer "B.Cu")
		(net 439)
	)
	(segment
		(start 112.485 81.37663)
		(end 111.785 82.07663)
		(width 0.19)
		(layer "B.Cu")
		(net 439)
	)
	(segment
		(start 113.085 88.67663)
		(end 111.87663 89.885)
		(width 0.19)
		(layer "B.Cu")
		(net 439)
	)
	(segment
		(start 111.180532 74.3)
		(end 111.065532 74.415)
		(width 0.19)
		(layer "B.Cu")
		(net 439)
	)
	(segment
		(start 109.178154 94.235272)
		(end 109.178154 94.335272)
		(width 0.19)
		(layer "B.Cu")
		(net 439)
	)
	(segment
		(start 113.085 84.22337)
		(end 113.085 88.67663)
		(width 0.19)
		(layer "B.Cu")
		(net 439)
	)
	(segment
		(start 111.785 82.07663)
		(end 111.785 82.92337)
		(width 0.19)
		(layer "B.Cu")
		(net 439)
	)
	(segment
		(start 111.47663 75.715)
		(end 112.67663 75.715)
		(width 0.19)
		(layer "B.Cu")
		(net 439)
	)
	(segment
		(start 113.085 80.07663)
		(end 112.485 80.67663)
		(width 0.19)
		(layer "B.Cu")
		(net 439)
	)
	(segment
		(start 111.785 82.92337)
		(end 113.085 84.22337)
		(width 0.19)
		(layer "B.Cu")
		(net 439)
	)
	(segment
		(start 113.085 76.12337)
		(end 113.085 80.07663)
		(width 0.19)
		(layer "B.Cu")
		(net 439)
	)
	(segment
		(start 111.87663 89.885)
		(end 110.47663 89.885)
		(width 0.19)
		(layer "B.Cu")
		(net 439)
	)
	(segment
		(start 108.699999 91.661631)
		(end 108.699999 93.835272)
		(width 0.19)
		(layer "B.Cu")
		(net 439)
	)
	(segment
		(start 108.978154 94.535272)
		(end 108.899999 94.535272)
		(width 0.19)
		(layer "B.Cu")
		(net 439)
	)
	(segment
		(start 112.485 80.67663)
		(end 112.485 81.37663)
		(width 0.19)
		(layer "B.Cu")
		(net 439)
	)
	(arc
		(start 108.978154 94.035272)
		(mid 109.119575 94.093851)
		(end 109.178154 94.235272)
		(width 0.19)
		(layer "B.Cu")
		(net 439)
	)
	(arc
		(start 108.899999 94.535272)
		(mid 108.758578 94.593851)
		(end 108.699999 94.735272)
		(width 0.19)
		(layer "B.Cu")
		(net 439)
	)
	(arc
		(start 109.178154 94.335272)
		(mid 109.119575 94.476693)
		(end 108.978154 94.535272)
		(width 0.19)
		(layer "B.Cu")
		(net 439)
	)
	(arc
		(start 108.699999 93.835272)
		(mid 108.758578 93.976693)
		(end 108.899999 94.035272)
		(width 0.19)
		(layer "B.Cu")
		(net 439)
	)
	(segment
		(start 110.305 129.5)
		(end 110.62 129.185)
		(width 0.19)
		(layer "F.Cu")
		(net 440)
	)
	(segment
		(start 111.01 129.195)
		(end 111.985 129.195)
		(width 0.19)
		(layer "F.Cu")
		(net 440)
	)
	(segment
		(start 111.985 129.195)
		(end 112.1 129.31)
		(width 0.19)
		(layer "F.Cu")
		(net 440)
	)
	(segment
		(start 110.28 129.5)
		(end 110.305 129.5)
		(width 0.19)
		(layer "F.Cu")
		(net 440)
	)
	(segment
		(start 110.62 129.185)
		(end 111 129.185)
		(width 0.19)
		(layer "F.Cu")
		(net 440)
	)
	(segment
		(start 111 129.185)
		(end 111.01 129.195)
		(width 0.19)
		(layer "F.Cu")
		(net 440)
	)
	(via
		(at 112.1 129.31)
		(size 0.45)
		(drill 0.1)
		(layers "F.Cu" "B.Cu")
		(net 440)
	)
	(segment
		(start 112.215 129.195)
		(end 112.1 129.31)
		(width 0.19)
		(layer "B.Cu")
		(net 440)
	)
	(segment
		(start 113.711 129.26)
		(end 113.086 129.26)
		(width 0.19)
		(layer "B.Cu")
		(net 440)
	)
	(segment
		(start 113.021 129.195)
		(end 112.215 129.195)
		(width 0.19)
		(layer "B.Cu")
		(net 440)
	)
	(segment
		(start 113.086 129.26)
		(end 113.021 129.195)
		(width 0.19)
		(layer "B.Cu")
		(net 440)
	)
	(segment
		(start 110.305 128.5)
		(end 110.62 128.815)
		(width 0.19)
		(layer "F.Cu")
		(net 444)
	)
	(segment
		(start 111.141592 128.815)
		(end 111.151592 128.825)
		(width 0.19)
		(layer "F.Cu")
		(net 444)
	)
	(segment
		(start 110.62 128.815)
		(end 111.141592 128.815)
		(width 0.19)
		(layer "F.Cu")
		(net 444)
	)
	(segment
		(start 111.151592 128.825)
		(end 111.985 128.825)
		(width 0.19)
		(layer "F.Cu")
		(net 444)
	)
	(segment
		(start 111.985 128.825)
		(end 112.1 128.71)
		(width 0.19)
		(layer "F.Cu")
		(net 444)
	)
	(segment
		(start 110.28 128.5)
		(end 110.305 128.5)
		(width 0.19)
		(layer "F.Cu")
		(net 444)
	)
	(via
		(at 112.1 128.71)
		(size 0.45)
		(drill 0.1)
		(layers "F.Cu" "B.Cu")
		(net 444)
	)
	(segment
		(start 112.215 128.825)
		(end 112.1 128.71)
		(width 0.19)
		(layer "B.Cu")
		(net 444)
	)
	(segment
		(start 113.021 128.825)
		(end 112.215 128.825)
		(width 0.19)
		(layer "B.Cu")
		(net 444)
	)
	(segment
		(start 113.711 128.76)
		(end 113.086 128.76)
		(width 0.19)
		(layer "B.Cu")
		(net 444)
	)
	(segment
		(start 113.086 128.76)
		(end 113.021 128.825)
		(width 0.19)
		(layer "B.Cu")
		(net 444)
	)
	(segment
		(start 189.248 56.497999)
		(end 192.750001 56.497999)
		(width 0.2)
		(layer "F.Cu")
		(net 448)
	)
	(segment
		(start 144.45 85.35)
		(end 144.45 85.8)
		(width 0.1)
		(layer "F.Cu")
		(net 448)
	)
	(segment
		(start 187.248 56.768)
		(end 187.25 56.77)
		(width 0.2)
		(layer "F.Cu")
		(net 448)
	)
	(segment
		(start 146.599 87.849)
		(end 146.780745 87.849)
		(width 0.1)
		(layer "F.Cu")
		(net 448)
	)
	(segment
		(start 143.8 83.7)
		(end 143.8 84.7)
		(width 0.1)
		(layer "F.Cu")
		(net 448)
	)
	(segment
		(start 187.248 55.846999)
		(end 188.597 55.846999)
		(width 0.2)
		(layer "F.Cu")
		(net 448)
	)
	(segment
		(start 192.750001 56.497999)
		(end 193.048 56.2)
		(width 0.2)
		(layer "F.Cu")
		(net 448)
	)
	(segment
		(start 143.130532 82.65)
		(end 143.130532 83.030532)
		(width 0.1)
		(layer "F.Cu")
		(net 448)
	)
	(segment
		(start 143.130532 83.030532)
		(end 143.8 83.7)
		(width 0.1)
		(layer "F.Cu")
		(net 448)
	)
	(segment
		(start 148.55 89.4)
		(end 148.55 89.75)
		(width 0.1)
		(layer "F.Cu")
		(net 448)
	)
	(segment
		(start 147.05 87.9)
		(end 148.55 89.4)
		(width 0.1)
		(layer "F.Cu")
		(net 448)
	)
	(segment
		(start 144.75 86.1)
		(end 144.85 86.1)
		(width 0.1)
		(layer "F.Cu")
		(net 448)
	)
	(segment
		(start 188.95 56.199999)
		(end 189.248 56.497999)
		(width 0.2)
		(layer "F.Cu")
		(net 448)
	)
	(segment
		(start 144.45 85.8)
		(end 144.75 86.1)
		(width 0.1)
		(layer "F.Cu")
		(net 448)
	)
	(segment
		(start 144.85 86.1)
		(end 146.599 87.849)
		(width 0.1)
		(layer "F.Cu")
		(net 448)
	)
	(segment
		(start 146.780745 87.849)
		(end 146.831745 87.9)
		(width 0.1)
		(layer "F.Cu")
		(net 448)
	)
	(segment
		(start 187.248 55.846999)
		(end 187.248 56.768)
		(width 0.2)
		(layer "F.Cu")
		(net 448)
	)
	(segment
		(start 143.8 84.7)
		(end 144.45 85.35)
		(width 0.1)
		(layer "F.Cu")
		(net 448)
	)
	(segment
		(start 188.597 55.846999)
		(end 188.95 56.199999)
		(width 0.2)
		(layer "F.Cu")
		(net 448)
	)
	(segment
		(start 146.831745 87.9)
		(end 147.05 87.9)
		(width 0.1)
		(layer "F.Cu")
		(net 448)
	)
	(via
		(at 188 55.9)
		(size 0.45)
		(drill 0.1)
		(layers "F.Cu" "B.Cu")
		(net 448)
	)
	(via
		(at 148.25 78.25)
		(size 0.45)
		(drill 0.1)
		(layers "F.Cu" "B.Cu")
		(net 448)
	)
	(via
		(at 148.55 89.75)
		(size 0.45)
		(drill 0.1)
		(layers "F.Cu" "B.Cu")
		(net 448)
	)
	(via
		(at 74.505532 105.615)
		(size 0.45)
		(drill 0.1)
		(layers "F.Cu" "B.Cu")
		(net 448)
	)
	(via
		(at 143.130532 82.65)
		(size 0.45)
		(drill 0.1)
		(layers "F.Cu" "B.Cu")
		(net 448)
	)
	(via
		(at 193.35 64.45)
		(size 0.45)
		(drill 0.1)
		(layers "F.Cu" "B.Cu")
		(net 448)
	)
	(segment
		(start 152.45 83.2)
		(end 152.45 81.6)
		(width 0.1)
		(layer "B.Cu")
		(net 448)
	)
	(segment
		(start 152.3 83.35)
		(end 152.45 83.2)
		(width 0.1)
		(layer "B.Cu")
		(net 448)
	)
	(segment
		(start 148.55 89.75)
		(end 152.3 86)
		(width 0.1)
		(layer "B.Cu")
		(net 448)
	)
	(segment
		(start 149.1 78.25)
		(end 152.45 81.6)
		(width 0.1)
		(layer "B.Cu")
		(net 448)
	)
	(segment
		(start 149.1 78.25)
		(end 148.25 78.25)
		(width 0.1)
		(layer "B.Cu")
		(net 448)
	)
	(segment
		(start 152.3 86)
		(end 152.3 83.35)
		(width 0.1)
		(layer "B.Cu")
		(net 448)
	)
	(segment
		(start 171.08 72.6)
		(end 171.51 72.6)
		(width 0.1)
		(layer "In2.Cu")
		(net 448)
	)
	(segment
		(start 193 64.1)
		(end 193.35 64.45)
		(width 0.1)
		(layer "In2.Cu")
		(net 448)
	)
	(segment
		(start 191.9 64.1)
		(end 193 64.1)
		(width 0.1)
		(layer "In2.Cu")
		(net 448)
	)
	(segment
		(start 148.25 78.25)
		(end 148.5 78.5)
		(width 0.1)
		(layer "In2.Cu")
		(net 448)
	)
	(segment
		(start 179.57 64.4)
		(end 191.6 64.4)
		(width 0.1)
		(layer "In2.Cu")
		(net 448)
	)
	(segment
		(start 148.5 78.5)
		(end 165.18 78.5)
		(width 0.1)
		(layer "In2.Cu")
		(net 448)
	)
	(segment
		(start 165.18 78.5)
		(end 171.08 72.6)
		(width 0.1)
		(layer "In2.Cu")
		(net 448)
	)
	(segment
		(start 176.25 67.86)
		(end 176.25 67.2)
		(width 0.1)
		(layer "In2.Cu")
		(net 448)
	)
	(segment
		(start 176.25 67.2)
		(end 176.865 66.585)
		(width 0.1)
		(layer "In2.Cu")
		(net 448)
	)
	(segment
		(start 177.385 66.585)
		(end 179.57 64.4)
		(width 0.1)
		(layer "In2.Cu")
		(net 448)
	)
	(segment
		(start 171.51 72.6)
		(end 176.25 67.86)
		(width 0.1)
		(layer "In2.Cu")
		(net 448)
	)
	(segment
		(start 176.865 66.585)
		(end 177.385 66.585)
		(width 0.1)
		(layer "In2.Cu")
		(net 448)
	)
	(segment
		(start 191.6 64.4)
		(end 191.9 64.1)
		(width 0.1)
		(layer "In2.Cu")
		(net 448)
	)
	(segment
		(start 130.424262 117.7)
		(end 105.3 117.7)
		(width 0.1)
		(layer "In5.Cu")
		(net 448)
	)
	(segment
		(start 133.124262 115)
		(end 130.424262 117.7)
		(width 0.1)
		(layer "In5.Cu")
		(net 448)
	)
	(segment
		(start 143.225 85.125)
		(end 143.542157 85.125)
		(width 0.1)
		(layer "In5.Cu")
		(net 448)
	)
	(segment
		(start 144.3 83.3)
		(end 143.780532 83.3)
		(width 0.1)
		(layer "In5.Cu")
		(net 448)
	)
	(segment
		(start 75.475736 124.099998)
		(end 75 123.624262)
		(width 0.1)
		(layer "In5.Cu")
		(net 448)
	)
	(segment
		(start 144.386272 84.526)
		(end 144.7 84.212272)
		(width 0.1)
		(layer "In5.Cu")
		(net 448)
	)
	(segment
		(start 75 106.109468)
		(end 74.505532 105.615)
		(width 0.1)
		(layer "In5.Cu")
		(net 448)
	)
	(segment
		(start 135.6 112.524262)
		(end 135.6 100.6)
		(width 0.1)
		(layer "In5.Cu")
		(net 448)
	)
	(segment
		(start 136.4 99.8)
		(end 136.4 94.9)
		(width 0.1)
		(layer "In5.Cu")
		(net 448)
	)
	(segment
		(start 136.4 94.9)
		(end 142.725 88.575)
		(width 0.1)
		(layer "In5.Cu")
		(net 448)
	)
	(segment
		(start 101.400001 121.599999)
		(end 89.324263 121.599999)
		(width 0.1)
		(layer "In5.Cu")
		(net 448)
	)
	(segment
		(start 105.3 117.7)
		(end 101.400001 121.599999)
		(width 0.1)
		(layer "In5.Cu")
		(net 448)
	)
	(segment
		(start 143.780532 83.3)
		(end 143.130532 82.65)
		(width 0.1)
		(layer "In5.Cu")
		(net 448)
	)
	(segment
		(start 135.6 100.6)
		(end 136.4 99.8)
		(width 0.1)
		(layer "In5.Cu")
		(net 448)
	)
	(segment
		(start 143.542157 85.125)
		(end 144.141157 84.526)
		(width 0.1)
		(layer "In5.Cu")
		(net 448)
	)
	(segment
		(start 142.725 85.625)
		(end 143.225 85.125)
		(width 0.1)
		(layer "In5.Cu")
		(net 448)
	)
	(segment
		(start 142.725 88.575)
		(end 142.725 85.625)
		(width 0.1)
		(layer "In5.Cu")
		(net 448)
	)
	(segment
		(start 144.7 83.7)
		(end 144.3 83.3)
		(width 0.1)
		(layer "In5.Cu")
		(net 448)
	)
	(segment
		(start 86.824264 124.099998)
		(end 75.475736 124.099998)
		(width 0.1)
		(layer "In5.Cu")
		(net 448)
	)
	(segment
		(start 144.7 84.212272)
		(end 144.7 83.7)
		(width 0.1)
		(layer "In5.Cu")
		(net 448)
	)
	(segment
		(start 144.141157 84.526)
		(end 144.386272 84.526)
		(width 0.1)
		(layer "In5.Cu")
		(net 448)
	)
	(segment
		(start 89.324263 121.599999)
		(end 86.824264 124.099998)
		(width 0.1)
		(layer "In5.Cu")
		(net 448)
	)
	(segment
		(start 133.124262 115)
		(end 135.6 112.524262)
		(width 0.1)
		(layer "In5.Cu")
		(net 448)
	)
	(segment
		(start 75 123.624262)
		(end 75 106.109468)
		(width 0.1)
		(layer "In5.Cu")
		(net 448)
	)
	(segment
		(start 190.5 57.55)
		(end 188.2 57.55)
		(width 0.1)
		(layer "In7.Cu")
		(net 448)
	)
	(segment
		(start 190.5 57.55)
		(end 193.9 60.95)
		(width 0.1)
		(layer "In7.Cu")
		(net 448)
	)
	(segment
		(start 193.35 64.45)
		(end 193.9 63.9)
		(width 0.1)
		(layer "In7.Cu")
		(net 448)
	)
	(segment
		(start 193.9 63.9)
		(end 193.9 60.95)
		(width 0.1)
		(layer "In7.Cu")
		(net 448)
	)
	(segment
		(start 188 57.35)
		(end 188 55.9)
		(width 0.1)
		(layer "In7.Cu")
		(net 448)
	)
	(segment
		(start 188.2 57.55)
		(end 188 57.35)
		(width 0.1)
		(layer "In7.Cu")
		(net 448)
	)
	(via
		(at 73.2 127.2)
		(size 0.45)
		(drill 0.1)
		(layers "F.Cu" "B.Cu")
		(net 450)
	)
	(segment
		(start 73.235532 127.205)
		(end 73.205 127.205)
		(width 0.1)
		(layer "B.Cu")
		(net 450)
	)
	(segment
		(start 73.205 127.205)
		(end 73.2 127.2)
		(width 0.1)
		(layer "B.Cu")
		(net 450)
	)
	(segment
		(start 87.28663 121.675)
		(end 86.385532 121.675)
		(width 0.19)
		(layer "B.Cu")
		(net 452)
	)
	(segment
		(start 93.495 118.77)
		(end 93.195 118.47)
		(width 0.19)
		(layer "B.Cu")
		(net 452)
	)
	(segment
		(start 90.49163 118.47)
		(end 87.28663 121.675)
		(width 0.19)
		(layer "B.Cu")
		(net 452)
	)
	(segment
		(start 86.385532 121.675)
		(end 85.935532 122.125)
		(width 0.19)
		(layer "B.Cu")
		(net 452)
	)
	(segment
		(start 93.195 118.47)
		(end 90.49163 118.47)
		(width 0.19)
		(layer "B.Cu")
		(net 452)
	)
	(segment
		(start 93.52 118.77)
		(end 93.495 118.77)
		(width 0.19)
		(layer "B.Cu")
		(net 452)
	)
	(segment
		(start 98.77663 119.415)
		(end 100.42337 119.415)
		(width 0.19)
		(layer "F.Cu")
		(net 459)
	)
	(segment
		(start 101.015 117.53)
		(end 100.885 117.4)
		(width 0.19)
		(layer "F.Cu")
		(net 459)
	)
	(segment
		(start 97.327681 117.966051)
		(end 98.77663 119.415)
		(width 0.19)
		(layer "F.Cu")
		(net 459)
	)
	(segment
		(start 97.065532 72.415)
		(end 97.065532 72.685)
		(width 0.19)
		(layer "F.Cu")
		(net 459)
	)
	(segment
		(start 97.216718 116.865139)
		(end 97.287428 116.935849)
		(width 0.19)
		(layer "F.Cu")
		(net 459)
	)
	(segment
		(start 93.4 89.46)
		(end 93.67837 89.46)
		(width 0.19)
		(layer "F.Cu")
		(net 459)
	)
	(segment
		(start 96.36 97.42337)
		(end 98.635 99.69837)
		(width 0.19)
		(layer "F.Cu")
		(net 459)
	)
	(segment
		(start 97.065532 72.685)
		(end 97.180532 72.8)
		(width 0.19)
		(layer "F.Cu")
		(net 459)
	)
	(segment
		(start 98.635 99.69837)
		(end 98.635 102.10163)
		(width 0.19)
		(layer "F.Cu")
		(net 459)
	)
	(segment
		(start 96.721743 117.077271)
		(end 96.933876 116.865139)
		(width 0.19)
		(layer "F.Cu")
		(net 459)
	)
	(segment
		(start 96.36 90.12337)
		(end 96.36 97.42337)
		(width 0.19)
		(layer "F.Cu")
		(net 459)
	)
	(segment
		(start 97.146007 117.784377)
		(end 97.327681 117.966051)
		(width 0.19)
		(layer "F.Cu")
		(net 459)
	)
	(segment
		(start 97.075295 117.713666)
		(end 97.146007 117.784377)
		(width 0.19)
		(layer "F.Cu")
		(net 459)
	)
	(segment
		(start 97.287427 117.218691)
		(end 97.075295 117.430824)
		(width 0.19)
		(layer "F.Cu")
		(net 459)
	)
	(segment
		(start 98.635 102.10163)
		(end 95.285 105.45163)
		(width 0.19)
		(layer "F.Cu")
		(net 459)
	)
	(segment
		(start 101.015 118.82337)
		(end 101.015 117.53)
		(width 0.19)
		(layer "F.Cu")
		(net 459)
	)
	(segment
		(start 95.285 115.92337)
		(end 96.438901 117.077271)
		(width 0.19)
		(layer "F.Cu")
		(net 459)
	)
	(segment
		(start 94.02337 89.115)
		(end 95.35163 89.115)
		(width 0.19)
		(layer "F.Cu")
		(net 459)
	)
	(segment
		(start 93.67837 89.46)
		(end 94.02337 89.115)
		(width 0.19)
		(layer "F.Cu")
		(net 459)
	)
	(segment
		(start 95.35163 89.115)
		(end 96.36 90.12337)
		(width 0.19)
		(layer "F.Cu")
		(net 459)
	)
	(segment
		(start 95.285 105.45163)
		(end 95.285 115.92337)
		(width 0.19)
		(layer "F.Cu")
		(net 459)
	)
	(segment
		(start 100.42337 119.415)
		(end 101.015 118.82337)
		(width 0.19)
		(layer "F.Cu")
		(net 459)
	)
	(segment
		(start 97.330532 72.15)
		(end 97.065532 72.415)
		(width 0.19)
		(layer "F.Cu")
		(net 459)
	)
	(via
		(at 100.885 117.4)
		(size 0.45)
		(drill 0.1)
		(layers "F.Cu" "B.Cu")
		(net 459)
	)
	(via
		(at 97.180532 72.8)
		(size 0.45)
		(drill 0.1)
		(layers "F.Cu" "B.Cu")
		(net 459)
	)
	(via
		(at 93.4 89.46)
		(size 0.45)
		(drill 0.1)
		(layers "F.Cu" "B.Cu")
		(net 459)
	)
	(arc
		(start 96.438901 117.077271)
		(mid 96.580323 117.13585)
		(end 96.721743 117.077271)
		(width 0.19)
		(layer "F.Cu")
		(net 459)
	)
	(arc
		(start 97.287428 116.935849)
		(mid 97.346006 117.077271)
		(end 97.287427 117.218691)
		(width 0.19)
		(layer "F.Cu")
		(net 459)
	)
	(arc
		(start 96.933876 116.865139)
		(mid 97.075296 116.80656)
		(end 97.216718 116.865139)
		(width 0.19)
		(layer "F.Cu")
		(net 459)
	)
	(arc
		(start 97.075295 117.430824)
		(mid 97.016716 117.572244)
		(end 97.075295 117.713666)
		(width 0.19)
		(layer "F.Cu")
		(net 459)
	)
	(segment
		(start 101.015 115.77663)
		(end 99.82337 114.585)
		(width 0.19)
		(layer "B.Cu")
		(net 459)
	)
	(segment
		(start 95.79163 118.47)
		(end 94.805 118.47)
		(width 0.19)
		(layer "B.Cu")
		(net 459)
	)
	(segment
		(start 97.765743 116.02873)
		(end 97.919039 116.182026)
		(width 0.19)
		(layer "B.Cu")
		(net 459)
	)
	(segment
		(start 101.015 117.27)
		(end 101.015 115.77663)
		(width 0.19)
		(layer "B.Cu")
		(net 459)
	)
	(segment
		(start 91.735 87.27663)
		(end 91.735 88.97337)
		(width 0.19)
		(layer "B.Cu")
		(net 459)
	)
	(segment
		(start 94.47663 74.585)
		(end 92.835 76.22663)
		(width 0.19)
		(layer "B.Cu")
		(net 459)
	)
	(segment
		(start 96.52663 74.585)
		(end 94.47663 74.585)
		(width 0.19)
		(layer "B.Cu")
		(net 459)
	)
	(segment
		(start 94.805 118.47)
		(end 94.505 118.77)
		(width 0.19)
		(layer "B.Cu")
		(net 459)
	)
	(segment
		(start 96.646091 117.615538)
		(end 96.579375 117.682255)
		(width 0.19)
		(layer "B.Cu")
		(net 459)
	)
	(segment
		(start 92.35163 89.59)
		(end 93.27 89.59)
		(width 0.19)
		(layer "B.Cu")
		(net 459)
	)
	(segment
		(start 97.919039 116.464868)
		(end 97.848329 116.535579)
		(width 0.19)
		(layer "B.Cu")
		(net 459)
	)
	(segment
		(start 92.835 86.17663)
		(end 91.735 87.27663)
		(width 0.19)
		(layer "B.Cu")
		(net 459)
	)
	(segment
		(start 97.129348 116.382285)
		(end 97.058637 116.452994)
		(width 0.19)
		(layer "B.Cu")
		(net 459)
	)
	(segment
		(start 97.065532 72.915)
		(end 97.065532 74.046098)
		(width 0.19)
		(layer "B.Cu")
		(net 459)
	)
	(segment
		(start 93.27 89.59)
		(end 93.4 89.46)
		(width 0.19)
		(layer "B.Cu")
		(net 459)
	)
	(segment
		(start 100.885 117.4)
		(end 101.015 117.27)
		(width 0.19)
		(layer "B.Cu")
		(net 459)
	)
	(segment
		(start 91.735 88.97337)
		(end 92.35163 89.59)
		(width 0.19)
		(layer "B.Cu")
		(net 459)
	)
	(segment
		(start 92.835 76.22663)
		(end 92.835 86.17663)
		(width 0.19)
		(layer "B.Cu")
		(net 459)
	)
	(segment
		(start 98.92663 114.585)
		(end 97.765744 115.745886)
		(width 0.19)
		(layer "B.Cu")
		(net 459)
	)
	(segment
		(start 97.035 116.47663)
		(end 97.035 117.22663)
		(width 0.19)
		(layer "B.Cu")
		(net 459)
	)
	(segment
		(start 97.180532 72.8)
		(end 97.065532 72.915)
		(width 0.19)
		(layer "B.Cu")
		(net 459)
	)
	(segment
		(start 99.82337 114.585)
		(end 98.92663 114.585)
		(width 0.19)
		(layer "B.Cu")
		(net 459)
	)
	(segment
		(start 94.505 118.77)
		(end 94.48 118.77)
		(width 0.19)
		(layer "B.Cu")
		(net 459)
	)
	(segment
		(start 97.058637 116.452994)
		(end 97.035 116.47663)
		(width 0.19)
		(layer "B.Cu")
		(net 459)
	)
	(segment
		(start 96.579375 117.682255)
		(end 95.79163 118.47)
		(width 0.19)
		(layer "B.Cu")
		(net 459)
	)
	(segment
		(start 97.035 117.22663)
		(end 96.646091 117.615538)
		(width 0.19)
		(layer "B.Cu")
		(net 459)
	)
	(segment
		(start 97.565485 116.53558)
		(end 97.41219 116.382285)
		(width 0.19)
		(layer "B.Cu")
		(net 459)
	)
	(segment
		(start 97.065532 74.046098)
		(end 96.52663 74.585)
		(width 0.19)
		(layer "B.Cu")
		(net 459)
	)
	(arc
		(start 97.848329 116.535579)
		(mid 97.706907 116.594158)
		(end 97.565485 116.53558)
		(width 0.19)
		(layer "B.Cu")
		(net 459)
	)
	(arc
		(start 97.41219 116.382285)
		(mid 97.27077 116.323706)
		(end 97.129348 116.382285)
		(width 0.19)
		(layer "B.Cu")
		(net 459)
	)
	(arc
		(start 97.765744 115.745886)
		(mid 97.707164 115.887309)
		(end 97.765743 116.02873)
		(width 0.19)
		(layer "B.Cu")
		(net 459)
	)
	(arc
		(start 97.919039 116.182026)
		(mid 97.977618 116.323446)
		(end 97.919039 116.464868)
		(width 0.19)
		(layer "B.Cu")
		(net 459)
	)
	(segment
		(start 85.8 74.4)
		(end 89.380532 74.4)
		(width 0.1)
		(layer "F.Cu")
		(net 464)
	)
	(segment
		(start 85.4 74)
		(end 85.8 74.4)
		(width 0.1)
		(layer "F.Cu")
		(net 464)
	)
	(segment
		(start 85.4 71.4)
		(end 85.4 74)
		(width 0.1)
		(layer "F.Cu")
		(net 464)
	)
	(segment
		(start 86 70.8)
		(end 85.4 71.4)
		(width 0.1)
		(layer "F.Cu")
		(net 464)
	)
	(segment
		(start 89.380532 74.4)
		(end 90.130532 75.15)
		(width 0.1)
		(layer "F.Cu")
		(net 464)
	)
	(segment
		(start 86.9 70.8)
		(end 86 70.8)
		(width 0.1)
		(layer "F.Cu")
		(net 464)
	)
	(segment
		(start 87.2 70.5)
		(end 86.9 70.8)
		(width 0.1)
		(layer "F.Cu")
		(net 464)
	)
	(via
		(at 73.9 110.3)
		(size 0.45)
		(drill 0.1)
		(layers "F.Cu" "B.Cu")
		(net 464)
	)
	(via
		(at 87.2 70.5)
		(size 0.45)
		(drill 0.1)
		(layers "F.Cu" "B.Cu")
		(net 464)
	)
	(segment
		(start 74.110532 110.3)
		(end 73.9 110.3)
		(width 0.15)
		(layer "B.Cu")
		(net 464)
	)
	(segment
		(start 74.505532 110.695)
		(end 74.110532 110.3)
		(width 0.15)
		(layer "B.Cu")
		(net 464)
	)
	(segment
		(start 67.8 109.45)
		(end 67.2 110.05)
		(width 0.1)
		(layer "In5.Cu")
		(net 464)
	)
	(segment
		(start 73.3 112.85)
		(end 73.3 111.6)
		(width 0.1)
		(layer "In5.Cu")
		(net 464)
	)
	(segment
		(start 70.5 113.4)
		(end 72.75 113.4)
		(width 0.1)
		(layer "In5.Cu")
		(net 464)
	)
	(segment
		(start 69.75 112.65)
		(end 70.5 113.4)
		(width 0.1)
		(layer "In5.Cu")
		(net 464)
	)
	(segment
		(start 77.4 75.6)
		(end 70.034316 75.6)
		(width 0.1)
		(layer "In5.Cu")
		(net 464)
	)
	(segment
		(start 67.2 110.05)
		(end 67.2 110.9)
		(width 0.1)
		(layer "In5.Cu")
		(net 464)
	)
	(segment
		(start 72.7 110.3)
		(end 72.9 110.1)
		(width 0.1)
		(layer "In5.Cu")
		(net 464)
	)
	(segment
		(start 73.3 111.6)
		(end 72.7 111)
		(width 0.1)
		(layer "In5.Cu")
		(net 464)
	)
	(segment
		(start 79.2 73.8)
		(end 77.4 75.6)
		(width 0.1)
		(layer "In5.Cu")
		(net 464)
	)
	(segment
		(start 67.600001 78.034315)
		(end 67.600001 81.9)
		(width 0.1)
		(layer "In5.Cu")
		(net 464)
	)
	(segment
		(start 86.9 70.8)
		(end 80.7 70.8)
		(width 0.1)
		(layer "In5.Cu")
		(net 464)
	)
	(segment
		(start 70.034316 75.6)
		(end 67.600001 78.034315)
		(width 0.1)
		(layer "In5.Cu")
		(net 464)
	)
	(segment
		(start 72.75 113.4)
		(end 73.3 112.85)
		(width 0.1)
		(layer "In5.Cu")
		(net 464)
	)
	(segment
		(start 79.2 72.3)
		(end 79.2 73.8)
		(width 0.1)
		(layer "In5.Cu")
		(net 464)
	)
	(segment
		(start 67.2 85.75)
		(end 67.2 92.8)
		(width 0.1)
		(layer "In5.Cu")
		(net 464)
	)
	(segment
		(start 72.7 111)
		(end 72.7 110.3)
		(width 0.1)
		(layer "In5.Cu")
		(net 464)
	)
	(segment
		(start 68.95 112.65)
		(end 69.75 112.65)
		(width 0.1)
		(layer "In5.Cu")
		(net 464)
	)
	(segment
		(start 66.7 82.800001)
		(end 66.7 85.25)
		(width 0.1)
		(layer "In5.Cu")
		(net 464)
	)
	(segment
		(start 87.2 70.5)
		(end 86.9 70.8)
		(width 0.1)
		(layer "In5.Cu")
		(net 464)
	)
	(segment
		(start 67.2 92.8)
		(end 67.8 93.400001)
		(width 0.1)
		(layer "In5.Cu")
		(net 464)
	)
	(segment
		(start 66.7 85.25)
		(end 67.2 85.75)
		(width 0.1)
		(layer "In5.Cu")
		(net 464)
	)
	(segment
		(start 80.7 70.8)
		(end 79.2 72.3)
		(width 0.1)
		(layer "In5.Cu")
		(net 464)
	)
	(segment
		(start 67.2 110.9)
		(end 68.95 112.65)
		(width 0.1)
		(layer "In5.Cu")
		(net 464)
	)
	(segment
		(start 72.9 110.1)
		(end 73.7 110.1)
		(width 0.1)
		(layer "In5.Cu")
		(net 464)
	)
	(segment
		(start 67.8 93.400001)
		(end 67.8 109.45)
		(width 0.1)
		(layer "In5.Cu")
		(net 464)
	)
	(segment
		(start 67.600001 81.9)
		(end 66.7 82.800001)
		(width 0.1)
		(layer "In5.Cu")
		(net 464)
	)
	(segment
		(start 73.7 110.1)
		(end 73.9 110.3)
		(width 0.1)
		(layer "In5.Cu")
		(net 464)
	)
	(segment
		(start 94.76 88.675)
		(end 94.89 88.545)
		(width 0.19)
		(layer "F.Cu")
		(net 467)
	)
	(segment
		(start 94.89 88.545)
		(end 94.89 88.17337)
		(width 0.19)
		(layer "F.Cu")
		(net 467)
	)
	(segment
		(start 96.430532 75.15)
		(end 96.695532 75.415)
		(width 0.19)
		(layer "F.Cu")
		(net 467)
	)
	(segment
		(start 96.695532 75.415)
		(end 96.695532 75.685)
		(width 0.19)
		(layer "F.Cu")
		(net 467)
	)
	(segment
		(start 100.21 102.40163)
		(end 96.535 106.07663)
		(width 0.19)
		(layer "F.Cu")
		(net 467)
	)
	(segment
		(start 96.535 106.07663)
		(end 96.535 114.47337)
		(width 0.19)
		(layer "F.Cu")
		(net 467)
	)
	(segment
		(start 96.695532 75.685)
		(end 96.580532 75.8)
		(width 0.19)
		(layer "F.Cu")
		(net 467)
	)
	(segment
		(start 97.985 96.52337)
		(end 100.21 98.74837)
		(width 0.19)
		(layer "F.Cu")
		(net 467)
	)
	(segment
		(start 100.21 98.74837)
		(end 100.21 102.40163)
		(width 0.19)
		(layer "F.Cu")
		(net 467)
	)
	(segment
		(start 99.985 118.57)
		(end 99.985 117.92337)
		(width 0.19)
		(layer "F.Cu")
		(net 467)
	)
	(segment
		(start 100.115 118.7)
		(end 99.985 118.57)
		(width 0.19)
		(layer "F.Cu")
		(net 467)
	)
	(segment
		(start 96.535 114.47337)
		(end 99.985 117.92337)
		(width 0.19)
		(layer "F.Cu")
		(net 467)
	)
	(segment
		(start 97.985 89.37337)
		(end 97.985 96.52337)
		(width 0.19)
		(layer "F.Cu")
		(net 467)
	)
	(segment
		(start 95.34837 87.715)
		(end 96.32663 87.715)
		(width 0.19)
		(layer "F.Cu")
		(net 467)
	)
	(segment
		(start 94.89 88.17337)
		(end 95.34837 87.715)
		(width 0.19)
		(layer "F.Cu")
		(net 467)
	)
	(segment
		(start 96.32663 87.715)
		(end 97.985 89.37337)
		(width 0.19)
		(layer "F.Cu")
		(net 467)
	)
	(via
		(at 94.76 88.675)
		(size 0.45)
		(drill 0.1)
		(layers "F.Cu" "B.Cu")
		(net 467)
	)
	(via
		(at 96.580532 75.8)
		(size 0.45)
		(drill 0.1)
		(layers "F.Cu" "B.Cu")
		(net 467)
	)
	(via
		(at 100.115 118.7)
		(size 0.45)
		(drill 0.1)
		(layers "F.Cu" "B.Cu")
		(net 467)
	)
	(segment
		(start 93.615 83.17337)
		(end 94.065 82.72337)
		(width 0.19)
		(layer "B.Cu")
		(net 467)
	)
	(segment
		(start 93.715 82.02663)
		(end 93.715 80.82337)
		(width 0.19)
		(layer "B.Cu")
		(net 467)
	)
	(segment
		(start 94.779999 122.47)
		(end 97.94163 122.47)
		(width 0.19)
		(layer "B.Cu")
		(net 467)
	)
	(segment
		(start 94.065 82.72337)
		(end 94.065 82.37663)
		(width 0.19)
		(layer "B.Cu")
		(net 467)
	)
	(segment
		(start 93.615 85.12663)
		(end 93.615 83.17337)
		(width 0.19)
		(layer "B.Cu")
		(net 467)
	)
	(segment
		(start 94.065 82.37663)
		(end 93.715 82.02663)
		(width 0.19)
		(layer "B.Cu")
		(net 467)
	)
	(segment
		(start 94.76 88.675)
		(end 94.89 88.545)
		(width 0.19)
		(layer "B.Cu")
		(net 467)
	)
	(segment
		(start 94.515 77.17337)
		(end 96.28837 75.4)
		(width 0.19)
		(layer "B.Cu")
		(net 467)
	)
	(segment
		(start 94.065 87.42663)
		(end 94.065 85.57663)
		(width 0.19)
		(layer "B.Cu")
		(net 467)
	)
	(segment
		(start 96.28837 75.4)
		(end 96.45 75.4)
		(width 0.19)
		(layer "B.Cu")
		(net 467)
	)
	(segment
		(start 99.985 120.42663)
		(end 99.985 118.83)
		(width 0.19)
		(layer "B.Cu")
		(net 467)
	)
	(segment
		(start 96.580532 75.530532)
		(end 96.580532 75.8)
		(width 0.19)
		(layer "B.Cu")
		(net 467)
	)
	(segment
		(start 96.45 75.4)
		(end 96.580532 75.530532)
		(width 0.19)
		(layer "B.Cu")
		(net 467)
	)
	(segment
		(start 94.48 122.769999)
		(end 94.779999 122.47)
		(width 0.19)
		(layer "B.Cu")
		(net 467)
	)
	(segment
		(start 94.89 88.545)
		(end 94.89 88.25163)
		(width 0.19)
		(layer "B.Cu")
		(net 467)
	)
	(segment
		(start 94.065 85.57663)
		(end 93.615 85.12663)
		(width 0.19)
		(layer "B.Cu")
		(net 467)
	)
	(segment
		(start 94.89 88.25163)
		(end 94.065 87.42663)
		(width 0.19)
		(layer "B.Cu")
		(net 467)
	)
	(segment
		(start 93.715 80.82337)
		(end 94.515 80.02337)
		(width 0.19)
		(layer "B.Cu")
		(net 467)
	)
	(segment
		(start 99.985 118.83)
		(end 100.115 118.7)
		(width 0.19)
		(layer "B.Cu")
		(net 467)
	)
	(segment
		(start 94.515 80.02337)
		(end 94.515 77.17337)
		(width 0.19)
		(layer "B.Cu")
		(net 467)
	)
	(segment
		(start 97.94163 122.47)
		(end 99.985 120.42663)
		(width 0.19)
		(layer "B.Cu")
		(net 467)
	)
	(segment
		(start 89.515 117.67663)
		(end 89.515 115.37663)
		(width 0.19)
		(layer "F.Cu")
		(net 471)
	)
	(segment
		(start 92.22 119.1)
		(end 92.195 119.1)
		(width 0.19)
		(layer "F.Cu")
		(net 471)
	)
	(segment
		(start 91.88 118.785)
		(end 90.62337 118.785)
		(width 0.19)
		(layer "F.Cu")
		(net 471)
	)
	(segment
		(start 90.62337 118.785)
		(end 89.515 117.67663)
		(width 0.19)
		(layer "F.Cu")
		(net 471)
	)
	(segment
		(start 92.195 119.1)
		(end 91.88 118.785)
		(width 0.19)
		(layer "F.Cu")
		(net 471)
	)
	(segment
		(start 85.115532 114.055)
		(end 84.665532 114.505)
		(width 0.19)
		(layer "F.Cu")
		(net 471)
	)
	(segment
		(start 89.515 115.37663)
		(end 88.19337 114.055)
		(width 0.19)
		(layer "F.Cu")
		(net 471)
	)
	(segment
		(start 88.19337 114.055)
		(end 85.115532 114.055)
		(width 0.19)
		(layer "F.Cu")
		(net 471)
	)
	(via
		(at 84.665532 114.505)
		(size 0.45)
		(drill 0.1)
		(layers "F.Cu" "B.Cu")
		(net 471)
	)
	(segment
		(start 130.7 141.9)
		(end 130.365 141.565)
		(width 0.1)
		(layer "F.Cu")
		(net 472)
	)
	(segment
		(start 130.8 142)
		(end 130.7 141.9)
		(width 0.1)
		(layer "F.Cu")
		(net 472)
	)
	(segment
		(start 130.365 141.565)
		(end 130.365 140.715)
		(width 0.1)
		(layer "F.Cu")
		(net 472)
	)
	(segment
		(start 130.8 142.72)
		(end 130.8 142)
		(width 0.1)
		(layer "F.Cu")
		(net 472)
	)
	(via
		(at 87.1 140.5)
		(size 0.45)
		(drill 0.1)
		(layers "F.Cu" "B.Cu")
		(net 472)
	)
	(via
		(at 130.7 141.9)
		(size 0.45)
		(drill 0.1)
		(layers "F.Cu" "B.Cu")
		(net 472)
	)
	(segment
		(start 82.7 129.25)
		(end 82.7 121.8)
		(width 0.1)
		(layer "B.Cu")
		(net 472)
	)
	(segment
		(start 87.1 140.5)
		(end 88.6 139)
		(width 0.1)
		(layer "B.Cu")
		(net 472)
	)
	(segment
		(start 87.4 130.4)
		(end 83.85 130.4)
		(width 0.1)
		(layer "B.Cu")
		(net 472)
	)
	(segment
		(start 88.6 139)
		(end 88.6 131.6)
		(width 0.1)
		(layer "B.Cu")
		(net 472)
	)
	(segment
		(start 83.85 130.4)
		(end 82.7 129.25)
		(width 0.1)
		(layer "B.Cu")
		(net 472)
	)
	(segment
		(start 82.7 121.8)
		(end 82.4 121.5)
		(width 0.1)
		(layer "B.Cu")
		(net 472)
	)
	(segment
		(start 80.210532 121.5)
		(end 79.585532 122.125)
		(width 0.1)
		(layer "B.Cu")
		(net 472)
	)
	(segment
		(start 82.4 121.5)
		(end 80.210532 121.5)
		(width 0.1)
		(layer "B.Cu")
		(net 472)
	)
	(segment
		(start 88.6 131.6)
		(end 87.4 130.4)
		(width 0.1)
		(layer "B.Cu")
		(net 472)
	)
	(segment
		(start 87.3 140.7)
		(end 87.1 140.5)
		(width 0.1)
		(layer "In7.Cu")
		(net 472)
	)
	(segment
		(start 87.3 140.7)
		(end 99.8 140.7)
		(width 0.1)
		(layer "In7.Cu")
		(net 472)
	)
	(segment
		(start 129.1 140.3)
		(end 121.6 140.3)
		(width 0.1)
		(layer "In7.Cu")
		(net 472)
	)
	(segment
		(start 101 141.9)
		(end 99.8 140.7)
		(width 0.1)
		(layer "In7.Cu")
		(net 472)
	)
	(segment
		(start 120 141.9)
		(end 101 141.9)
		(width 0.1)
		(layer "In7.Cu")
		(net 472)
	)
	(segment
		(start 130.7 141.9)
		(end 129.1 140.3)
		(width 0.1)
		(layer "In7.Cu")
		(net 472)
	)
	(segment
		(start 121.6 140.3)
		(end 120 141.9)
		(width 0.1)
		(layer "In7.Cu")
		(net 472)
	)
	(segment
		(start 86.385532 126.385)
		(end 87.35337 126.385)
		(width 0.19)
		(layer "B.Cu")
		(net 475)
	)
	(segment
		(start 93.52 121.8)
		(end 93.52 121.775)
		(width 0.19)
		(layer "B.Cu")
		(net 475)
	)
	(segment
		(start 93.22 122.1)
		(end 93.52 121.8)
		(width 0.19)
		(layer "B.Cu")
		(net 475)
	)
	(segment
		(start 87.35337 126.385)
		(end 91.63837 122.1)
		(width 0.19)
		(layer "B.Cu")
		(net 475)
	)
	(segment
		(start 85.935532 125.935)
		(end 86.385532 126.385)
		(width 0.19)
		(layer "B.Cu")
		(net 475)
	)
	(segment
		(start 91.63837 122.1)
		(end 93.22 122.1)
		(width 0.19)
		(layer "B.Cu")
		(net 475)
	)
	(segment
		(start 93.17 120.475)
		(end 90.78663 120.475)
		(width 0.19)
		(layer "B.Cu")
		(net 476)
	)
	(segment
		(start 87.02663 124.235)
		(end 86.325 124.235)
		(width 0.19)
		(layer "B.Cu")
		(net 476)
	)
	(segment
		(start 93.495 120.8)
		(end 93.17 120.475)
		(width 0.19)
		(layer "B.Cu")
		(net 476)
	)
	(segment
		(start 90.78663 120.475)
		(end 87.02663 124.235)
		(width 0.19)
		(layer "B.Cu")
		(net 476)
	)
	(segment
		(start 93.52 120.8)
		(end 93.495 120.8)
		(width 0.19)
		(layer "B.Cu")
		(net 476)
	)
	(segment
		(start 85.135532 124.195)
		(end 86.285 124.195)
		(width 0.1)
		(layer "B.Cu")
		(net 476)
	)
	(segment
		(start 86.325 124.235)
		(end 86.285 124.195)
		(width 0.19)
		(layer "B.Cu")
		(net 476)
	)
	(segment
		(start 84.665532 124.665)
		(end 85.135532 124.195)
		(width 0.1)
		(layer "B.Cu")
		(net 476)
	)
	(segment
		(start 105.330532 72.15)
		(end 105.065532 72.415)
		(width 0.19)
		(layer "F.Cu")
		(net 478)
	)
	(segment
		(start 99.985 104.25163)
		(end 99.985 115.47663)
		(width 0.19)
		(layer "F.Cu")
		(net 478)
	)
	(segment
		(start 105.065532 72.685)
		(end 105.180532 72.8)
		(width 0.19)
		(layer "F.Cu")
		(net 478)
	)
	(segment
		(start 99.712132 115.749498)
		(end 99.712132 115.912132)
		(width 0.19)
		(layer "F.Cu")
		(net 478)
	)
	(segment
		(start 102.512132 87.950502)
		(end 103.285 88.72337)
		(width 0.19)
		(layer "F.Cu")
		(net 478)
	)
	(segment
		(start 102.512132 87.787868)
		(end 102.512132 87.950502)
		(width 0.19)
		(layer "F.Cu")
		(net 478)
	)
	(segment
		(start 103.285 100.95163)
		(end 99.985 104.25163)
		(width 0.19)
		(layer "F.Cu")
		(net 478)
	)
	(segment
		(start 99.985 115.47663)
		(end 99.712132 115.749498)
		(width 0.19)
		(layer "F.Cu")
		(net 478)
	)
	(segment
		(start 105.065532 72.415)
		(end 105.065532 72.685)
		(width 0.19)
		(layer "F.Cu")
		(net 478)
	)
	(segment
		(start 103.285 88.72337)
		(end 103.285 100.95163)
		(width 0.19)
		(layer "F.Cu")
		(net 478)
	)
	(via
		(at 99.712132 115.912132)
		(size 0.45)
		(drill 0.1)
		(layers "F.Cu" "B.Cu")
		(net 478)
	)
	(via
		(at 102.512132 87.787868)
		(size 0.45)
		(drill 0.1)
		(layers "F.Cu" "B.Cu")
		(net 478)
	)
	(via
		(at 105.180532 72.8)
		(size 0.45)
		(drill 0.1)
		(layers "F.Cu" "B.Cu")
		(net 478)
	)
	(segment
		(start 98.285 117.17663)
		(end 99.549498 115.912132)
		(width 0.19)
		(layer "B.Cu")
		(net 478)
	)
	(segment
		(start 94.505 120.8)
		(end 94.83 120.475)
		(width 0.19)
		(layer "B.Cu")
		(net 478)
	)
	(segment
		(start 98.285 117.97663)
		(end 98.285 117.17663)
		(width 0.19)
		(layer "B.Cu")
		(net 478)
	)
	(segment
		(start 94.83 120.475)
		(end 95.78663 120.475)
		(width 0.19)
		(layer "B.Cu")
		(net 478)
	)
	(segment
		(start 95.78663 120.475)
		(end 98.285 117.97663)
		(width 0.19)
		(layer "B.Cu")
		(net 478)
	)
	(segment
		(start 94.48 120.8)
		(end 94.505 120.8)
		(width 0.19)
		(layer "B.Cu")
		(net 478)
	)
	(segment
		(start 99.549498 115.912132)
		(end 99.712132 115.912132)
		(width 0.19)
		(layer "B.Cu")
		(net 478)
	)
	(segment
		(start 102.282323 87.787868)
		(end 101.0375 86.543045)
		(width 0.15)
		(layer "In7.Cu")
		(net 478)
	)
	(segment
		(start 103.456956 74.5375)
		(end 104.456956 74.5375)
		(width 0.15)
		(layer "In7.Cu")
		(net 478)
	)
	(segment
		(start 103.1375 74.856956)
		(end 103.456956 74.5375)
		(width 0.15)
		(layer "In7.Cu")
		(net 478)
	)
	(segment
		(start 101.456956 75.9375)
		(end 102.456956 75.9375)
		(width 0.15)
		(layer "In7.Cu")
		(net 478)
	)
	(segment
		(start 104.456956 74.5375)
		(end 105.018032 73.976424)
		(width 0.15)
		(layer "In7.Cu")
		(net 478)
	)
	(segment
		(start 103.1375 75.256956)
		(end 103.1375 74.856956)
		(width 0.15)
		(layer "In7.Cu")
		(net 478)
	)
	(segment
		(start 100.1375 80.743044)
		(end 100.1375 80.143044)
		(width 0.15)
		(layer "In7.Cu")
		(net 478)
	)
	(segment
		(start 101.1375 76.256956)
		(end 101.456956 75.9375)
		(width 0.15)
		(layer "In7.Cu")
		(net 478)
	)
	(segment
		(start 102.512132 87.787868)
		(end 102.282323 87.787868)
		(width 0.15)
		(layer "In7.Cu")
		(net 478)
	)
	(segment
		(start 101.0375 86.543045)
		(end 101.0375 81.643044)
		(width 0.15)
		(layer "In7.Cu")
		(net 478)
	)
	(segment
		(start 105.018032 73.976424)
		(end 105.018032 72.9625)
		(width 0.15)
		(layer "In7.Cu")
		(net 478)
	)
	(segment
		(start 102.456956 75.9375)
		(end 103.1375 75.256956)
		(width 0.15)
		(layer "In7.Cu")
		(net 478)
	)
	(segment
		(start 101.1375 77.856956)
		(end 101.1375 76.256956)
		(width 0.15)
		(layer "In7.Cu")
		(net 478)
	)
	(segment
		(start 100.1375 80.143044)
		(end 99.7875 79.793044)
		(width 0.15)
		(layer "In7.Cu")
		(net 478)
	)
	(segment
		(start 99.7875 79.206956)
		(end 101.1375 77.856956)
		(width 0.15)
		(layer "In7.Cu")
		(net 478)
	)
	(segment
		(start 101.0375 81.643044)
		(end 100.1375 80.743044)
		(width 0.15)
		(layer "In7.Cu")
		(net 478)
	)
	(segment
		(start 99.7875 79.793044)
		(end 99.7875 79.206956)
		(width 0.15)
		(layer "In7.Cu")
		(net 478)
	)
	(segment
		(start 105.018032 72.9625)
		(end 105.180532 72.8)
		(width 0.15)
		(layer "In7.Cu")
		(net 478)
	)
	(segment
		(start 85.135532 123.865)
		(end 86.275 123.865)
		(width 0.1)
		(layer "B.Cu")
		(net 479)
	)
	(segment
		(start 90.63337 120.105)
		(end 86.87337 123.865)
		(width 0.19)
		(layer "B.Cu")
		(net 479)
	)
	(segment
		(start 93.17 120.105)
		(end 90.63337 120.105)
		(width 0.19)
		(layer "B.Cu")
		(net 479)
	)
	(segment
		(start 86.87337 123.865)
		(end 86.275 123.865)
		(width 0.19)
		(layer "B.Cu")
		(net 479)
	)
	(segment
		(start 84.665532 123.395)
		(end 85.135532 123.865)
		(width 0.1)
		(layer "B.Cu")
		(net 479)
	)
	(segment
		(start 93.495 119.78)
		(end 93.17 120.105)
		(width 0.19)
		(layer "B.Cu")
		(net 479)
	)
	(segment
		(start 93.52 119.78)
		(end 93.495 119.78)
		(width 0.19)
		(layer "B.Cu")
		(net 479)
	)
	(segment
		(start 141.8 87)
		(end 141.8 86.119468)
		(width 0.1)
		(layer "F.Cu")
		(net 487)
	)
	(segment
		(start 147.2 89.1)
		(end 146.9 88.8)
		(width 0.1)
		(layer "F.Cu")
		(net 487)
	)
	(segment
		(start 151.75 82.45)
		(end 151.75 70.475)
		(width 0.1)
		(layer "F.Cu")
		(net 487)
	)
	(segment
		(start 146.1 88.3)
		(end 146.1 88.1)
		(width 0.1)
		(layer "F.Cu")
		(net 487)
	)
	(segment
		(start 153.2 67.5)
		(end 162 67.5)
		(width 0.1)
		(layer "F.Cu")
		(net 487)
	)
	(segment
		(start 151.75 70.475)
		(end 152.85 69.375)
		(width 0.1)
		(layer "F.Cu")
		(net 487)
	)
	(segment
		(start 167.7 66.7)
		(end 167.9 66.9)
		(width 0.1)
		(layer "F.Cu")
		(net 487)
	)
	(segment
		(start 142.2 87.4)
		(end 141.8 87)
		(width 0.1)
		(layer "F.Cu")
		(net 487)
	)
	(segment
		(start 152.85 69.375)
		(end 152.85 67.85)
		(width 0.1)
		(layer "F.Cu")
		(net 487)
	)
	(segment
		(start 147.2 89.7)
		(end 147.2 89.1)
		(width 0.1)
		(layer "F.Cu")
		(net 487)
	)
	(segment
		(start 152.05 82.75)
		(end 151.75 82.45)
		(width 0.1)
		(layer "F.Cu")
		(net 487)
	)
	(segment
		(start 141.8 86.119468)
		(end 141.330532 85.65)
		(width 0.1)
		(layer "F.Cu")
		(net 487)
	)
	(segment
		(start 162.8 66.7)
		(end 167.7 66.7)
		(width 0.1)
		(layer "F.Cu")
		(net 487)
	)
	(segment
		(start 146.9 88.8)
		(end 146.6 88.8)
		(width 0.1)
		(layer "F.Cu")
		(net 487)
	)
	(segment
		(start 146.1 88.1)
		(end 145.4 87.4)
		(width 0.1)
		(layer "F.Cu")
		(net 487)
	)
	(segment
		(start 162 67.5)
		(end 162.8 66.7)
		(width 0.1)
		(layer "F.Cu")
		(net 487)
	)
	(segment
		(start 145.4 87.4)
		(end 142.2 87.4)
		(width 0.1)
		(layer "F.Cu")
		(net 487)
	)
	(segment
		(start 152.85 67.85)
		(end 153.2 67.5)
		(width 0.1)
		(layer "F.Cu")
		(net 487)
	)
	(segment
		(start 146.6 88.8)
		(end 146.1 88.3)
		(width 0.1)
		(layer "F.Cu")
		(net 487)
	)
	(via
		(at 167.9 66.9)
		(size 0.45)
		(drill 0.1)
		(layers "F.Cu" "B.Cu")
		(net 487)
	)
	(via
		(at 147.2 89.7)
		(size 0.45)
		(drill 0.1)
		(layers "F.Cu" "B.Cu")
		(net 487)
	)
	(via
		(at 152.05 82.75)
		(size 0.45)
		(drill 0.1)
		(layers "F.Cu" "B.Cu")
		(net 487)
	)
	(via
		(at 173.9 59.6)
		(size 0.45)
		(drill 0.1)
		(layers "F.Cu" "B.Cu")
		(net 487)
	)
	(via
		(at 74.505532 101.805)
		(size 0.45)
		(drill 0.1)
		(layers "F.Cu" "B.Cu")
		(net 487)
	)
	(segment
		(start 174.55 59.578004)
		(end 175.563002 59.578004)
		(width 0.1)
		(layer "B.Cu")
		(net 487)
	)
	(segment
		(start 175.563002 59.578004)
		(end 175.568 59.583002)
		(width 0.1)
		(layer "B.Cu")
		(net 487)
	)
	(segment
		(start 173.921996 59.578004)
		(end 173.9 59.6)
		(width 0.1)
		(layer "B.Cu")
		(net 487)
	)
	(segment
		(start 174.55 59.578004)
		(end 173.921996 59.578004)
		(width 0.1)
		(layer "B.Cu")
		(net 487)
	)
	(segment
		(start 152.05 84.85)
		(end 152.05 82.75)
		(width 0.1)
		(layer "B.Cu")
		(net 487)
	)
	(segment
		(start 147.2 89.7)
		(end 152.05 84.85)
		(width 0.1)
		(layer "B.Cu")
		(net 487)
	)
	(segment
		(start 102.2 89.2)
		(end 102.8 88.6)
		(width 0.1)
		(layer "In2.Cu")
		(net 487)
	)
	(segment
		(start 74.2 93.5)
		(end 86.5 93.5)
		(width 0.1)
		(layer "In2.Cu")
		(net 487)
	)
	(segment
		(start 86.5 93.5)
		(end 89 91)
		(width 0.1)
		(layer "In2.Cu")
		(net 487)
	)
	(segment
		(start 93.55 88.5)
		(end 94.25 89.2)
		(width 0.1)
		(layer "In2.Cu")
		(net 487)
	)
	(segment
		(start 120.2 87.6)
		(end 145.3 87.6)
		(width 0.1)
		(layer "In2.Cu")
		(net 487)
	)
	(segment
		(start 94.25 89.2)
		(end 102.2 89.2)
		(width 0.1)
		(layer "In2.Cu")
		(net 487)
	)
	(segment
		(start 92.4 89.8)
		(end 92.4 88.619669)
		(width 0.1)
		(layer "In2.Cu")
		(net 487)
	)
	(segment
		(start 74.505532 101.805)
		(end 73.7 100.999468)
		(width 0.1)
		(layer "In2.Cu")
		(net 487)
	)
	(segment
		(start 93.1 88.5)
		(end 93.55 88.5)
		(width 0.1)
		(layer "In2.Cu")
		(net 487)
	)
	(segment
		(start 89 91)
		(end 91.2 91)
		(width 0.1)
		(layer "In2.Cu")
		(net 487)
	)
	(segment
		(start 147.2 88.925)
		(end 147.2 89.7)
		(width 0.1)
		(layer "In2.Cu")
		(net 487)
	)
	(segment
		(start 102.8 88.6)
		(end 119.2 88.6)
		(width 0.1)
		(layer "In2.Cu")
		(net 487)
	)
	(segment
		(start 92.669669 88.35)
		(end 92.95 88.35)
		(width 0.1)
		(layer "In2.Cu")
		(net 487)
	)
	(segment
		(start 73.7 100.999468)
		(end 73.7 94)
		(width 0.1)
		(layer "In2.Cu")
		(net 487)
	)
	(segment
		(start 91.2 91)
		(end 92.4 89.8)
		(width 0.1)
		(layer "In2.Cu")
		(net 487)
	)
	(segment
		(start 92.95 88.35)
		(end 93.1 88.5)
		(width 0.1)
		(layer "In2.Cu")
		(net 487)
	)
	(segment
		(start 119.2 88.6)
		(end 120.2 87.6)
		(width 0.1)
		(layer "In2.Cu")
		(net 487)
	)
	(segment
		(start 146.3875 88.6875)
		(end 146.9625 88.6875)
		(width 0.1)
		(layer "In2.Cu")
		(net 487)
	)
	(segment
		(start 146.9625 88.6875)
		(end 147.2 88.925)
		(width 0.1)
		(layer "In2.Cu")
		(net 487)
	)
	(segment
		(start 73.7 94)
		(end 74.2 93.5)
		(width 0.1)
		(layer "In2.Cu")
		(net 487)
	)
	(segment
		(start 92.4 88.619669)
		(end 92.669669 88.35)
		(width 0.1)
		(layer "In2.Cu")
		(net 487)
	)
	(segment
		(start 145.3 87.6)
		(end 146.3875 88.6875)
		(width 0.1)
		(layer "In2.Cu")
		(net 487)
	)
	(segment
		(start 168 66.9)
		(end 169.2 65.7)
		(width 0.1)
		(layer "In7.Cu")
		(net 487)
	)
	(segment
		(start 170.85 59.6)
		(end 173.9 59.6)
		(width 0.1)
		(layer "In7.Cu")
		(net 487)
	)
	(segment
		(start 167.9 66.9)
		(end 168 66.9)
		(width 0.1)
		(layer "In7.Cu")
		(net 487)
	)
	(segment
		(start 169.2 65.7)
		(end 169.2 61.25)
		(width 0.1)
		(layer "In7.Cu")
		(net 487)
	)
	(segment
		(start 169.2 61.25)
		(end 170.85 59.6)
		(width 0.1)
		(layer "In7.Cu")
		(net 487)
	)
	(segment
		(start 230.325 81.825)
		(end 232.505532 79.644468)
		(width 0.17)
		(layer "F.Cu")
		(net 488)
	)
	(segment
		(start 232.930532 75.0725)
		(end 232.930532 75.839468)
		(width 0.17)
		(layer "F.Cu")
		(net 488)
	)
	(segment
		(start 225.072488 78.475)
		(end 224.675 78.872488)
		(width 0.17)
		(layer "F.Cu")
		(net 488)
	)
	(segment
		(start 232.430532 76.339468)
		(end 232.430532 77.3475)
		(width 0.17)
		(layer "F.Cu")
		(net 488)
	)
	(segment
		(start 226.825 81.5)
		(end 227.613 81.5)
		(width 0.17)
		(layer "F.Cu")
		(net 488)
	)
	(segment
		(start 232.430532 78.566251)
		(end 232.430532 77.3475)
		(width 0.17)
		(layer "F.Cu")
		(net 488)
	)
	(segment
		(start 232.505532 79.644468)
		(end 232.505532 78.641251)
		(width 0.17)
		(layer "F.Cu")
		(net 488)
	)
	(segment
		(start 229.3 81.825)
		(end 230.325 81.825)
		(width 0.17)
		(layer "F.Cu")
		(net 488)
	)
	(segment
		(start 226.175 78.475)
		(end 225.072488 78.475)
		(width 0.17)
		(layer "F.Cu")
		(net 488)
	)
	(segment
		(start 225.572488 81.825)
		(end 226.5 81.825)
		(width 0.17)
		(layer "F.Cu")
		(net 488)
	)
	(segment
		(start 228.385001 81.5)
		(end 228.975 81.5)
		(width 0.17)
		(layer "F.Cu")
		(net 488)
	)
	(segment
		(start 224.675 80.927512)
		(end 225.572488 81.825)
		(width 0.17)
		(layer "F.Cu")
		(net 488)
	)
	(segment
		(start 228.975 81.5)
		(end 229.3 81.825)
		(width 0.17)
		(layer "F.Cu")
		(net 488)
	)
	(segment
		(start 224.675 78.872488)
		(end 224.675 80.927512)
		(width 0.17)
		(layer "F.Cu")
		(net 488)
	)
	(segment
		(start 226.3 78.6)
		(end 226.175 78.475)
		(width 0.17)
		(layer "F.Cu")
		(net 488)
	)
	(segment
		(start 232.930532 75.839468)
		(end 232.430532 76.339468)
		(width 0.17)
		(layer "F.Cu")
		(net 488)
	)
	(segment
		(start 227.613 81.5)
		(end 228.385001 81.5)
		(width 0.17)
		(layer "F.Cu")
		(net 488)
	)
	(segment
		(start 226.5 81.825)
		(end 226.825 81.5)
		(width 0.17)
		(layer "F.Cu")
		(net 488)
	)
	(segment
		(start 232.505532 78.641251)
		(end 232.430532 78.566251)
		(width 0.17)
		(layer "F.Cu")
		(net 488)
	)
	(via
		(at 226.3 78.6)
		(size 0.45)
		(drill 0.1)
		(layers "F.Cu" "B.Cu")
		(net 488)
	)
	(segment
		(start 225.496 78.88)
		(end 225.521 78.855)
		(width 0.17)
		(layer "B.Cu")
		(net 488)
	)
	(segment
		(start 224.52 78.88)
		(end 225.496 78.88)
		(width 0.17)
		(layer "B.Cu")
		(net 488)
	)
	(segment
		(start 226.045 78.855)
		(end 226.3 78.6)
		(width 0.17)
		(layer "B.Cu")
		(net 488)
	)
	(segment
		(start 225.521 78.855)
		(end 226.045 78.855)
		(width 0.17)
		(layer "B.Cu")
		(net 488)
	)
	(segment
		(start 232.930532 78.566251)
		(end 232.930532 77.3475)
		(width 0.17)
		(layer "F.Cu")
		(net 489)
	)
	(segment
		(start 227.611 82.5)
		(end 227.613 82.498)
		(width 0.17)
		(layer "F.Cu")
		(net 489)
	)
	(segment
		(start 224.325 78.727512)
		(end 224.325 81.072488)
		(width 0.17)
		(layer "F.Cu")
		(net 489)
	)
	(segment
		(start 230.469974 82.175)
		(end 232.855532 79.789442)
		(width 0.17)
		(layer "F.Cu")
		(net 489)
	)
	(segment
		(start 228.898 82.498)
		(end 228.9 82.5)
		(width 0.17)
		(layer "F.Cu")
		(net 489)
	)
	(segment
		(start 232.430532 75.0725)
		(end 232.430532 73.860532)
		(width 0.17)
		(layer "F.Cu")
		(net 489)
	)
	(segment
		(start 226.5 82.175)
		(end 226.825 82.5)
		(width 0.17)
		(layer "F.Cu")
		(net 489)
	)
	(segment
		(start 232.930532 78.560532)
		(end 232.930532 77.3475)
		(width 0.17)
		(layer "F.Cu")
		(net 489)
	)
	(segment
		(start 226.825 82.5)
		(end 227.611 82.5)
		(width 0.17)
		(layer "F.Cu")
		(net 489)
	)
	(segment
		(start 226.175 78.125)
		(end 224.927512 78.125)
		(width 0.17)
		(layer "F.Cu")
		(net 489)
	)
	(segment
		(start 228.975 82.5)
		(end 229.3 82.175)
		(width 0.17)
		(layer "F.Cu")
		(net 489)
	)
	(segment
		(start 224.927512 78.125)
		(end 224.325 78.727512)
		(width 0.17)
		(layer "F.Cu")
		(net 489)
	)
	(segment
		(start 228.9 82.5)
		(end 228.975 82.5)
		(width 0.17)
		(layer "F.Cu")
		(net 489)
	)
	(segment
		(start 224.325 81.072488)
		(end 225.427512 82.175)
		(width 0.17)
		(layer "F.Cu")
		(net 489)
	)
	(segment
		(start 228.385 82.498)
		(end 227.613 82.498)
		(width 0.17)
		(layer "F.Cu")
		(net 489)
	)
	(segment
		(start 232.430532 73.860532)
		(end 232.37 73.8)
		(width 0.17)
		(layer "F.Cu")
		(net 489)
	)
	(segment
		(start 232.855532 79.789442)
		(end 232.855532 78.641251)
		(width 0.17)
		(layer "F.Cu")
		(net 489)
	)
	(segment
		(start 228.385 82.498)
		(end 228.898 82.498)
		(width 0.17)
		(layer "F.Cu")
		(net 489)
	)
	(segment
		(start 225.427512 82.175)
		(end 226.5 82.175)
		(width 0.17)
		(layer "F.Cu")
		(net 489)
	)
	(segment
		(start 226.3 78)
		(end 226.175 78.125)
		(width 0.17)
		(layer "F.Cu")
		(net 489)
	)
	(segment
		(start 232.855532 78.641251)
		(end 232.930532 78.566251)
		(width 0.17)
		(layer "F.Cu")
		(net 489)
	)
	(segment
		(start 229.3 82.175)
		(end 230.469974 82.175)
		(width 0.17)
		(layer "F.Cu")
		(net 489)
	)
	(via
		(at 232.37 73.8)
		(size 0.45)
		(drill 0.1)
		(layers "F.Cu" "B.Cu")
		(net 489)
	)
	(via
		(at 232.930532 78.560532)
		(size 0.45)
		(drill 0.1)
		(layers "F.Cu" "B.Cu")
		(net 489)
	)
	(via
		(at 226.3 78)
		(size 0.45)
		(drill 0.1)
		(layers "F.Cu" "B.Cu")
		(net 489)
	)
	(segment
		(start 226.19 77.89)
		(end 226.3 78)
		(width 0.17)
		(layer "B.Cu")
		(net 489)
	)
	(segment
		(start 225.521 77.89)
		(end 226.19 77.89)
		(width 0.17)
		(layer "B.Cu")
		(net 489)
	)
	(segment
		(start 225.496 77.865)
		(end 225.521 77.89)
		(width 0.17)
		(layer "B.Cu")
		(net 489)
	)
	(segment
		(start 224.526 77.865)
		(end 225.496 77.865)
		(width 0.17)
		(layer "B.Cu")
		(net 489)
	)
	(segment
		(start 232.37 73.8)
		(end 232.37 76.2)
		(width 0.125)
		(layer "In7.Cu")
		(net 489)
	)
	(segment
		(start 232.930532 78.560532)
		(end 232.930532 76.760532)
		(width 0.125)
		(layer "In7.Cu")
		(net 489)
	)
	(segment
		(start 232.930532 76.760532)
		(end 232.37 76.2)
		(width 0.125)
		(layer "In7.Cu")
		(net 489)
	)
	(via
		(at 170.75 56.01)
		(size 0.45)
		(drill 0.1)
		(layers "F.Cu" "B.Cu")
		(net 490)
	)
	(segment
		(start 170.75 56)
		(end 170.75 57.02)
		(width 0.1)
		(layer "B.Cu")
		(net 490)
	)
	(segment
		(start 134.7 63.58)
		(end 134.7 57.14)
		(width 0.5)
		(layer "F.Cu")
		(net 491)
	)
	(segment
		(start 134.7 57.14)
		(end 135.64 56.2)
		(width 0.5)
		(layer "F.Cu")
		(net 491)
	)
	(segment
		(start 116.47 63.91)
		(end 119.06 66.5)
		(width 0.5)
		(layer "F.Cu")
		(net 491)
	)
	(segment
		(start 131.78 66.5)
		(end 134.7 63.58)
		(width 0.5)
		(layer "F.Cu")
		(net 491)
	)
	(segment
		(start 135.64 56.2)
		(end 135.65 56.2)
		(width 0.5)
		(layer "F.Cu")
		(net 491)
	)
	(segment
		(start 112.471 59.24)
		(end 116.13 59.24)
		(width 0.5)
		(layer "F.Cu")
		(net 491)
	)
	(segment
		(start 116.47 59.58)
		(end 116.47 63.91)
		(width 0.5)
		(layer "F.Cu")
		(net 491)
	)
	(segment
		(start 137.15 56.3)
		(end 137.15 55.43)
		(width 0.2)
		(layer "F.Cu")
		(net 491)
	)
	(segment
		(start 93.52 57.54)
		(end 94.48 58.5)
		(width 0.2)
		(layer "F.Cu")
		(net 491)
	)
	(segment
		(start 140.88 55.39)
		(end 141.12 55.63)
		(width 0.5)
		(layer "F.Cu")
		(net 491)
	)
	(segment
		(start 92.1 58.553)
		(end 92.467 58.553)
		(width 0.2)
		(layer "F.Cu")
		(net 491)
	)
	(segment
		(start 136.46 55.39)
		(end 137.19 55.39)
		(width 0.5)
		(layer "F.Cu")
		(net 491)
	)
	(segment
		(start 135.65 56.2)
		(end 136.46 55.39)
		(width 0.5)
		(layer "F.Cu")
		(net 491)
	)
	(segment
		(start 94.48 58.5)
		(end 95.25 58.5)
		(width 0.2)
		(layer "F.Cu")
		(net 491)
	)
	(segment
		(start 141.12 55.63)
		(end 141.12 56.3)
		(width 0.5)
		(layer "F.Cu")
		(net 491)
	)
	(segment
		(start 92.467 58.553)
		(end 93.52 57.5)
		(width 0.2)
		(layer "F.Cu")
		(net 491)
	)
	(segment
		(start 87.52 60.5)
		(end 86.75 60.5)
		(width 0.1)
		(layer "F.Cu")
		(net 491)
	)
	(segment
		(start 93.52 57.5)
		(end 93.52 57.54)
		(width 0.2)
		(layer "F.Cu")
		(net 491)
	)
	(segment
		(start 83.98 55.5)
		(end 84.75 55.5)
		(width 0.1)
		(layer "F.Cu")
		(net 491)
	)
	(segment
		(start 137.15 55.43)
		(end 137.19 55.39)
		(width 0.1)
		(layer "F.Cu")
		(net 491)
	)
	(segment
		(start 116.13 59.24)
		(end 116.47 59.58)
		(width 0.5)
		(layer "F.Cu")
		(net 491)
	)
	(segment
		(start 137.19 55.39)
		(end 140.88 55.39)
		(width 0.5)
		(layer "F.Cu")
		(net 491)
	)
	(segment
		(start 140.049 56.3)
		(end 141.12 56.3)
		(width 0.4)
		(layer "F.Cu")
		(net 491)
	)
	(segment
		(start 67.961532 55.75)
		(end 72.25 55.75)
		(width 0.1)
		(layer "F.Cu")
		(net 491)
	)
	(segment
		(start 111.22 60.491)
		(end 112.471 59.24)
		(width 0.5)
		(layer "F.Cu")
		(net 491)
	)
	(segment
		(start 67.500532 55.289)
		(end 67.961532 55.75)
		(width 0.1)
		(layer "F.Cu")
		(net 491)
	)
	(segment
		(start 173 57.15)
		(end 173 58)
		(width 0.1)
		(layer "F.Cu")
		(net 491)
	)
	(segment
		(start 119.06 66.5)
		(end 131.78 66.5)
		(width 0.5)
		(layer "F.Cu")
		(net 491)
	)
	(via
		(at 72.25 55.75)
		(size 0.45)
		(drill 0.1)
		(layers "F.Cu" "B.Cu")
		(net 491)
	)
	(via
		(at 130.65 66.49)
		(size 0.45)
		(drill 0.1)
		(layers "F.Cu" "B.Cu")
		(net 491)
	)
	(via
		(at 109.510001 61.819998)
		(size 0.45)
		(drill 0.1)
		(layers "F.Cu" "B.Cu")
		(net 491)
	)
	(via
		(at 84.75 55.5)
		(size 0.45)
		(drill 0.1)
		(layers "F.Cu" "B.Cu")
		(net 491)
	)
	(via
		(at 109.510001 61.219998)
		(size 0.45)
		(drill 0.1)
		(layers "F.Cu" "B.Cu")
		(net 491)
	)
	(via
		(at 86.75 60.5)
		(size 0.45)
		(drill 0.1)
		(layers "F.Cu" "B.Cu")
		(net 491)
	)
	(via
		(at 173 58)
		(size 0.45)
		(drill 0.1)
		(layers "F.Cu" "B.Cu")
		(net 491)
	)
	(via
		(at 95.25 58.5)
		(size 0.45)
		(drill 0.1)
		(layers "F.Cu" "B.Cu")
		(net 491)
	)
	(via
		(at 107.035 56.68)
		(size 0.45)
		(drill 0.1)
		(layers "F.Cu" "B.Cu")
		(net 491)
	)
	(segment
		(start 109.908999 60.821)
		(end 110.303256 60.821)
		(width 0.1)
		(layer "B.Cu")
		(net 491)
	)
	(segment
		(start 77.2 65.8)
		(end 77.2 64.6)
		(width 0.1)
		(layer "B.Cu")
		(net 491)
	)
	(segment
		(start 174.14 58)
		(end 173 58)
		(width 0.1)
		(layer "B.Cu")
		(net 491)
	)
	(segment
		(start 80.4 70.75)
		(end 79.75 70.75)
		(width 0.1)
		(layer "B.Cu")
		(net 491)
	)
	(segment
		(start 83.2 66.2)
		(end 83.2 67.4)
		(width 0.1)
		(layer "B.Cu")
		(net 491)
	)
	(segment
		(start 78.4 67)
		(end 77.2 65.8)
		(width 0.1)
		(layer "B.Cu")
		(net 491)
	)
	(segment
		(start 83.2 67.4)
		(end 82.9 67.7)
		(width 0.1)
		(layer "B.Cu")
		(net 491)
	)
	(segment
		(start 76.2 63.6)
		(end 72.6 63.6)
		(width 0.1)
		(layer "B.Cu")
		(net 491)
	)
	(segment
		(start 81 70.15)
		(end 80.4 70.75)
		(width 0.1)
		(layer "B.Cu")
		(net 491)
	)
	(segment
		(start 79.75 70.75)
		(end 78.4 69.4)
		(width 0.1)
		(layer "B.Cu")
		(net 491)
	)
	(segment
		(start 72.25 63.25)
		(end 72.25 55.75)
		(width 0.1)
		(layer "B.Cu")
		(net 491)
	)
	(segment
		(start 85.25 62)
		(end 85.25 63.75)
		(width 0.1)
		(layer "B.Cu")
		(net 491)
	)
	(segment
		(start 110.660999 58.220999)
		(end 109.52 57.08)
		(width 0.1)
		(layer "B.Cu")
		(net 491)
	)
	(segment
		(start 110.303256 60.821)
		(end 110.660999 60.463257)
		(width 0.1)
		(layer "B.Cu")
		(net 491)
	)
	(segment
		(start 83.8 65.6)
		(end 83.2 66.2)
		(width 0.1)
		(layer "B.Cu")
		(net 491)
	)
	(segment
		(start 85.25 63.75)
		(end 83.8 65.2)
		(width 0.1)
		(layer "B.Cu")
		(net 491)
	)
	(segment
		(start 81 68.1)
		(end 81 70.15)
		(width 0.1)
		(layer "B.Cu")
		(net 491)
	)
	(segment
		(start 109.52 57.08)
		(end 107.435 57.08)
		(width 0.1)
		(layer "B.Cu")
		(net 491)
	)
	(segment
		(start 81.4 67.7)
		(end 81 68.1)
		(width 0.1)
		(layer "B.Cu")
		(net 491)
	)
	(segment
		(start 78.4 69.4)
		(end 78.4 67)
		(width 0.1)
		(layer "B.Cu")
		(net 491)
	)
	(segment
		(start 107.435 57.08)
		(end 107.035 56.68)
		(width 0.1)
		(layer "B.Cu")
		(net 491)
	)
	(segment
		(start 82.9 67.7)
		(end 81.4 67.7)
		(width 0.1)
		(layer "B.Cu")
		(net 491)
	)
	(segment
		(start 72.6 63.6)
		(end 72.25 63.25)
		(width 0.1)
		(layer "B.Cu")
		(net 491)
	)
	(segment
		(start 110.660999 60.463257)
		(end 110.660999 58.220999)
		(width 0.1)
		(layer "B.Cu")
		(net 491)
	)
	(segment
		(start 83.8 65.2)
		(end 83.8 65.6)
		(width 0.1)
		(layer "B.Cu")
		(net 491)
	)
	(segment
		(start 109.510001 61.219998)
		(end 109.908999 60.821)
		(width 0.1)
		(layer "B.Cu")
		(net 491)
	)
	(segment
		(start 86.75 60.5)
		(end 85.25 62)
		(width 0.1)
		(layer "B.Cu")
		(net 491)
	)
	(segment
		(start 77.2 64.6)
		(end 76.2 63.6)
		(width 0.1)
		(layer "B.Cu")
		(net 491)
	)
	(segment
		(start 130.89 67.5)
		(end 130.65 67.26)
		(width 0.1)
		(layer "In2.Cu")
		(net 491)
	)
	(segment
		(start 173 58)
		(end 173 58.8)
		(width 0.1)
		(layer "In2.Cu")
		(net 491)
	)
	(segment
		(start 164.9 66.9)
		(end 162.7 66.9)
		(width 0.1)
		(layer "In2.Cu")
		(net 491)
	)
	(segment
		(start 162.7 66.9)
		(end 162.1 67.5)
		(width 0.1)
		(layer "In2.Cu")
		(net 491)
	)
	(segment
		(start 162.1 67.5)
		(end 130.89 67.5)
		(width 0.1)
		(layer "In2.Cu")
		(net 491)
	)
	(segment
		(start 173 58.8)
		(end 164.9 66.9)
		(width 0.1)
		(layer "In2.Cu")
		(net 491)
	)
	(segment
		(start 130.65 67.26)
		(end 130.65 66.49)
		(width 0.1)
		(layer "In2.Cu")
		(net 491)
	)
	(segment
		(start 84.75 55.5)
		(end 85.8 55.5)
		(width 0.3)
		(layer "In5.Cu")
		(net 491)
	)
	(segment
		(start 109.510001 61.819998)
		(end 108.140002 61.819998)
		(width 0.3)
		(layer "In5.Cu")
		(net 491)
	)
	(segment
		(start 108.140002 61.819998)
		(end 106.96 63)
		(width 0.3)
		(layer "In5.Cu")
		(net 491)
	)
	(segment
		(start 88.2 58.5)
		(end 88.75 58.5)
		(width 0.3)
		(layer "In5.Cu")
		(net 491)
	)
	(segment
		(start 88.075 58.5)
		(end 88.275 58.7)
		(width 0.3)
		(layer "In5.Cu")
		(net 491)
	)
	(segment
		(start 85.8 55.5)
		(end 87.2 56.9)
		(width 0.3)
		(layer "In5.Cu")
		(net 491)
	)
	(segment
		(start 87.2 56.9)
		(end 87.2 58.2)
		(width 0.3)
		(layer "In5.Cu")
		(net 491)
	)
	(segment
		(start 87.2 58.2)
		(end 87.5 58.5)
		(width 0.3)
		(layer "In5.Cu")
		(net 491)
	)
	(segment
		(start 87.5 58.5)
		(end 87.9 58.5)
		(width 0.3)
		(layer "In5.Cu")
		(net 491)
	)
	(segment
		(start 88.425 58.725)
		(end 88.425 58.825)
		(width 0.3)
		(layer "In5.Cu")
		(net 491)
	)
	(segment
		(start 86.75 61.35)
		(end 86.75 60.5)
		(width 0.3)
		(layer "In5.Cu")
		(net 491)
	)
	(segment
		(start 86.75 60.5)
		(end 88.275 58.975)
		(width 0.3)
		(layer "In5.Cu")
		(net 491)
	)
	(segment
		(start 87.9 58.5)
		(end 88.075 58.5)
		(width 0.3)
		(layer "In5.Cu")
		(net 491)
	)
	(segment
		(start 95.25 58.5)
		(end 88.75 58.5)
		(width 0.3)
		(layer "In5.Cu")
		(net 491)
	)
	(segment
		(start 106.96 63)
		(end 88.4 63)
		(width 0.3)
		(layer "In5.Cu")
		(net 491)
	)
	(segment
		(start 88.4 63)
		(end 86.75 61.35)
		(width 0.3)
		(layer "In5.Cu")
		(net 491)
	)
	(segment
		(start 88.2 58.5)
		(end 88.425 58.725)
		(width 0.3)
		(layer "In5.Cu")
		(net 491)
	)
	(segment
		(start 87.9 58.5)
		(end 88.2 58.5)
		(width 0.3)
		(layer "In5.Cu")
		(net 491)
	)
	(segment
		(start 88.2 58.5)
		(end 88.275 58.575)
		(width 0.3)
		(layer "In5.Cu")
		(net 491)
	)
	(segment
		(start 88.425 58.825)
		(end 88.75 58.5)
		(width 0.3)
		(layer "In5.Cu")
		(net 491)
	)
	(segment
		(start 88.275 58.575)
		(end 88.275 58.7)
		(width 0.3)
		(layer "In5.Cu")
		(net 491)
	)
	(segment
		(start 88.275 58.975)
		(end 88.425 58.825)
		(width 0.3)
		(layer "In5.Cu")
		(net 491)
	)
	(segment
		(start 88.275 58.7)
		(end 88.275 58.975)
		(width 0.3)
		(layer "In5.Cu")
		(net 491)
	)
	(segment
		(start 92.635947 87.252872)
		(end 92.813819 87.252872)
		(width 0.17)
		(layer "F.Cu")
		(net 492)
	)
	(segment
		(start 205.754 131.488)
		(end 205.754 131.8916)
		(width 0.17)
		(layer "F.Cu")
		(net 492)
	)
	(segment
		(start 88.872488 87.525)
		(end 92.363819 87.525)
		(width 0.17)
		(layer "F.Cu")
		(net 492)
	)
	(segment
		(start 204.575 134.325)
		(end 204.45 134.45)
		(width 0.17)
		(layer "F.Cu")
		(net 492)
	)
	(segment
		(start 88.652132 87.127868)
		(end 88.652132 87.304644)
		(width 0.17)
		(layer "F.Cu")
		(net 492)
	)
	(segment
		(start 88.652132 87.304644)
		(end 88.872488 87.525)
		(width 0.17)
		(layer "F.Cu")
		(net 492)
	)
	(segment
		(start 94.705532 86.79698)
		(end 94.705532 85.925)
		(width 0.17)
		(layer "F.Cu")
		(net 492)
	)
	(segment
		(start 94.705532 85.925)
		(end 94.430532 85.65)
		(width 0.17)
		(layer "F.Cu")
		(net 492)
	)
	(segment
		(start 205.325 132.827512)
		(end 205.325 133.027512)
		(width 0.17)
		(layer "F.Cu")
		(net 492)
	)
	(segment
		(start 93.085947 87.525)
		(end 93.977512 87.525)
		(width 0.17)
		(layer "F.Cu")
		(net 492)
	)
	(segment
		(start 205.7795 132.373012)
		(end 205.325 132.827512)
		(width 0.17)
		(layer "F.Cu")
		(net 492)
	)
	(segment
		(start 205.7795 131.9171)
		(end 205.7795 132.373012)
		(width 0.17)
		(layer "F.Cu")
		(net 492)
	)
	(segment
		(start 93.977512 87.525)
		(end 94.705532 86.79698)
		(width 0.17)
		(layer "F.Cu")
		(net 492)
	)
	(segment
		(start 205.754 131.8916)
		(end 205.7795 131.9171)
		(width 0.17)
		(layer "F.Cu")
		(net 492)
	)
	(segment
		(start 204.575 133.777512)
		(end 204.575 134.325)
		(width 0.17)
		(layer "F.Cu")
		(net 492)
	)
	(segment
		(start 205.325 133.027512)
		(end 204.575 133.777512)
		(width 0.17)
		(layer "F.Cu")
		(net 492)
	)
	(via
		(at 204.45 134.45)
		(size 0.45)
		(drill 0.1)
		(layers "F.Cu" "B.Cu")
		(net 492)
	)
	(via
		(at 88.652132 87.127868)
		(size 0.45)
		(drill 0.1)
		(layers "F.Cu" "B.Cu")
		(net 492)
	)
	(arc
		(start 92.813819 87.252872)
		(mid 92.910031 87.292724)
		(end 92.949883 87.388936)
		(width 0.17)
		(layer "F.Cu")
		(net 492)
	)
	(arc
		(start 92.499883 87.388936)
		(mid 92.539735 87.292724)
		(end 92.635947 87.252872)
		(width 0.17)
		(layer "F.Cu")
		(net 492)
	)
	(arc
		(start 92.949883 87.388936)
		(mid 92.989735 87.485148)
		(end 93.085947 87.525)
		(width 0.17)
		(layer "F.Cu")
		(net 492)
	)
	(arc
		(start 92.363819 87.525)
		(mid 92.460031 87.485148)
		(end 92.499883 87.388936)
		(width 0.17)
		(layer "F.Cu")
		(net 492)
	)
	(segment
		(start 89.4875 114.6966)
		(end 91.7875 116.9966)
		(width 0.125)
		(layer "In7.Cu")
		(net 492)
	)
	(segment
		(start 204.637499 134.262501)
		(end 204.45 134.45)
		(width 0.125)
		(layer "In7.Cu")
		(net 492)
	)
	(segment
		(start 91.7875 119.6466)
		(end 96.1534 124.0125)
		(width 0.125)
		(layer "In7.Cu")
		(net 492)
	)
	(segment
		(start 91.7875 116.9966)
		(end 91.7875 119.6466)
		(width 0.125)
		(layer "In7.Cu")
		(net 492)
	)
	(segment
		(start 86.7875 87.3534)
		(end 86.7875 104.1966)
		(width 0.125)
		(layer "In7.Cu")
		(net 492)
	)
	(segment
		(start 193.3534 133.9125)
		(end 198.1466 133.9125)
		(width 0.125)
		(layer "In7.Cu")
		(net 492)
	)
	(segment
		(start 167.5534 108.1125)
		(end 193.3534 133.9125)
		(width 0.125)
		(layer "In7.Cu")
		(net 492)
	)
	(segment
		(start 139.2466 108.1125)
		(end 167.5534 108.1125)
		(width 0.125)
		(layer "In7.Cu")
		(net 492)
	)
	(segment
		(start 88.386968 87.127868)
		(end 88.1466 86.8875)
		(width 0.125)
		(layer "In7.Cu")
		(net 492)
	)
	(segment
		(start 88.1466 86.8875)
		(end 87.2534 86.8875)
		(width 0.125)
		(layer "In7.Cu")
		(net 492)
	)
	(segment
		(start 204.637499 132.396599)
		(end 204.637499 134.262501)
		(width 0.125)
		(layer "In7.Cu")
		(net 492)
	)
	(segment
		(start 198.1466 133.9125)
		(end 200.5466 131.5125)
		(width 0.125)
		(layer "In7.Cu")
		(net 492)
	)
	(segment
		(start 122.5466 119.3125)
		(end 128.0466 119.3125)
		(width 0.125)
		(layer "In7.Cu")
		(net 492)
	)
	(segment
		(start 200.5466 131.5125)
		(end 203.7534 131.5125)
		(width 0.125)
		(layer "In7.Cu")
		(net 492)
	)
	(segment
		(start 89.4875 106.8966)
		(end 89.4875 114.6966)
		(width 0.125)
		(layer "In7.Cu")
		(net 492)
	)
	(segment
		(start 96.1534 124.0125)
		(end 117.8466 124.0125)
		(width 0.125)
		(layer "In7.Cu")
		(net 492)
	)
	(segment
		(start 87.2534 86.8875)
		(end 86.7875 87.3534)
		(width 0.125)
		(layer "In7.Cu")
		(net 492)
	)
	(segment
		(start 128.0466 119.3125)
		(end 139.2466 108.1125)
		(width 0.125)
		(layer "In7.Cu")
		(net 492)
	)
	(segment
		(start 86.7875 104.1966)
		(end 89.4875 106.8966)
		(width 0.125)
		(layer "In7.Cu")
		(net 492)
	)
	(segment
		(start 117.8466 124.0125)
		(end 122.5466 119.3125)
		(width 0.125)
		(layer "In7.Cu")
		(net 492)
	)
	(segment
		(start 88.652132 87.127868)
		(end 88.386968 87.127868)
		(width 0.125)
		(layer "In7.Cu")
		(net 492)
	)
	(segment
		(start 203.7534 131.5125)
		(end 204.637499 132.396599)
		(width 0.125)
		(layer "In7.Cu")
		(net 492)
	)
	(segment
		(start 205.675 133.172488)
		(end 204.925 133.922488)
		(width 0.17)
		(layer "F.Cu")
		(net 493)
	)
	(segment
		(start 88.727512 87.875)
		(end 88.404644 87.552132)
		(width 0.17)
		(layer "F.Cu")
		(net 493)
	)
	(segment
		(start 206.1295 131.9171)
		(end 206.1295 132.517988)
		(width 0.17)
		(layer "F.Cu")
		(net 493)
	)
	(segment
		(start 206.155 131.488)
		(end 206.155 131.8916)
		(width 0.17)
		(layer "F.Cu")
		(net 493)
	)
	(segment
		(start 206.1295 132.517988)
		(end 205.675 132.972488)
		(width 0.17)
		(layer "F.Cu")
		(net 493)
	)
	(segment
		(start 94.122488 87.875)
		(end 88.727512 87.875)
		(width 0.17)
		(layer "F.Cu")
		(net 493)
	)
	(segment
		(start 95.055532 86.941956)
		(end 94.122488 87.875)
		(width 0.17)
		(layer "F.Cu")
		(net 493)
	)
	(segment
		(start 204.925 134.325)
		(end 205.05 134.45)
		(width 0.17)
		(layer "F.Cu")
		(net 493)
	)
	(segment
		(start 88.404644 87.552132)
		(end 88.227868 87.552132)
		(width 0.17)
		(layer "F.Cu")
		(net 493)
	)
	(segment
		(start 205.675 132.972488)
		(end 205.675 133.172488)
		(width 0.17)
		(layer "F.Cu")
		(net 493)
	)
	(segment
		(start 204.925 133.922488)
		(end 204.925 134.325)
		(width 0.17)
		(layer "F.Cu")
		(net 493)
	)
	(segment
		(start 206.155 131.8916)
		(end 206.1295 131.9171)
		(width 0.17)
		(layer "F.Cu")
		(net 493)
	)
	(segment
		(start 95.330532 85.65)
		(end 95.055532 85.925)
		(width 0.17)
		(layer "F.Cu")
		(net 493)
	)
	(segment
		(start 95.055532 85.925)
		(end 95.055532 86.941956)
		(width 0.17)
		(layer "F.Cu")
		(net 493)
	)
	(via
		(at 88.227868 87.552132)
		(size 0.45)
		(drill 0.1)
		(layers "F.Cu" "B.Cu")
		(net 493)
	)
	(via
		(at 205.05 134.45)
		(size 0.45)
		(drill 0.1)
		(layers "F.Cu" "B.Cu")
		(net 493)
	)
	(segment
		(start 87.0125 104.1034)
		(end 89.7125 106.8034)
		(width 0.125)
		(layer "In7.Cu")
		(net 493)
	)
	(segment
		(start 87.0125 87.4466)
		(end 87.0125 104.1034)
		(width 0.125)
		(layer "In7.Cu")
		(net 493)
	)
	(segment
		(start 127.9534 119.0875)
		(end 139.1534 107.8875)
		(width 0.125)
		(layer "In7.Cu")
		(net 493)
	)
	(segment
		(start 200.4534 131.2875)
		(end 203.8466 131.2875)
		(width 0.125)
		(layer "In7.Cu")
		(net 493)
	)
	(segment
		(start 198.0534 133.6875)
		(end 200.4534 131.2875)
		(width 0.125)
		(layer "In7.Cu")
		(net 493)
	)
	(segment
		(start 204.862501 132.303401)
		(end 204.862501 134.262501)
		(width 0.125)
		(layer "In7.Cu")
		(net 493)
	)
	(segment
		(start 89.7125 114.6034)
		(end 92.0125 116.9034)
		(width 0.125)
		(layer "In7.Cu")
		(net 493)
	)
	(segment
		(start 88.227868 87.552132)
		(end 88.227868 87.286968)
		(width 0.125)
		(layer "In7.Cu")
		(net 493)
	)
	(segment
		(start 117.7534 123.7875)
		(end 122.4534 119.0875)
		(width 0.125)
		(layer "In7.Cu")
		(net 493)
	)
	(segment
		(start 167.6466 107.8875)
		(end 193.4466 133.6875)
		(width 0.125)
		(layer "In7.Cu")
		(net 493)
	)
	(segment
		(start 96.2466 123.7875)
		(end 117.7534 123.7875)
		(width 0.125)
		(layer "In7.Cu")
		(net 493)
	)
	(segment
		(start 88.0534 87.1125)
		(end 87.3466 87.1125)
		(width 0.125)
		(layer "In7.Cu")
		(net 493)
	)
	(segment
		(start 122.4534 119.0875)
		(end 127.9534 119.0875)
		(width 0.125)
		(layer "In7.Cu")
		(net 493)
	)
	(segment
		(start 87.3466 87.1125)
		(end 87.0125 87.4466)
		(width 0.125)
		(layer "In7.Cu")
		(net 493)
	)
	(segment
		(start 193.4466 133.6875)
		(end 198.0534 133.6875)
		(width 0.125)
		(layer "In7.Cu")
		(net 493)
	)
	(segment
		(start 203.8466 131.2875)
		(end 204.862501 132.303401)
		(width 0.125)
		(layer "In7.Cu")
		(net 493)
	)
	(segment
		(start 88.227868 87.286968)
		(end 88.0534 87.1125)
		(width 0.125)
		(layer "In7.Cu")
		(net 493)
	)
	(segment
		(start 139.1534 107.8875)
		(end 167.6466 107.8875)
		(width 0.125)
		(layer "In7.Cu")
		(net 493)
	)
	(segment
		(start 92.0125 116.9034)
		(end 92.0125 119.5534)
		(width 0.125)
		(layer "In7.Cu")
		(net 493)
	)
	(segment
		(start 89.7125 106.8034)
		(end 89.7125 114.6034)
		(width 0.125)
		(layer "In7.Cu")
		(net 493)
	)
	(segment
		(start 92.0125 119.5534)
		(end 96.2466 123.7875)
		(width 0.125)
		(layer "In7.Cu")
		(net 493)
	)
	(segment
		(start 204.862501 134.262501)
		(end 205.05 134.45)
		(width 0.125)
		(layer "In7.Cu")
		(net 493)
	)
	(segment
		(start 144.3 71.2)
		(end 146.3 71.2)
		(width 0.1)
		(layer "F.Cu")
		(net 494)
	)
	(segment
		(start 151.8 99.2)
		(end 151 99.2)
		(width 0.1)
		(layer "F.Cu")
		(net 494)
	)
	(segment
		(start 143.909734 71.590266)
		(end 142.990266 71.590266)
		(width 0.1)
		(layer "F.Cu")
		(net 494)
	)
	(segment
		(start 142.990266 71.590266)
		(end 142.430532 72.15)
		(width 0.1)
		(layer "F.Cu")
		(net 494)
	)
	(segment
		(start 146.3 71.2)
		(end 147 70.5)
		(width 0.1)
		(layer "F.Cu")
		(net 494)
	)
	(segment
		(start 144.3 71.2)
		(end 143.909734 71.590266)
		(width 0.1)
		(layer "F.Cu")
		(net 494)
	)
	(via
		(at 147 70.5)
		(size 0.45)
		(drill 0.1)
		(layers "F.Cu" "B.Cu")
		(net 494)
	)
	(via
		(at 151 99.2)
		(size 0.45)
		(drill 0.1)
		(layers "F.Cu" "B.Cu")
		(net 494)
	)
	(via
		(at 145.6 86.175)
		(size 0.45)
		(drill 0.1)
		(layers "F.Cu" "B.Cu")
		(net 494)
	)
	(segment
		(start 144.6 89.4)
		(end 148.7 93.5)
		(width 0.1)
		(layer "B.Cu")
		(net 494)
	)
	(segment
		(start 145.6 87.2)
		(end 144.6 88.2)
		(width 0.1)
		(layer "B.Cu")
		(net 494)
	)
	(segment
		(start 148.7 98.1)
		(end 149.8 99.2)
		(width 0.1)
		(layer "B.Cu")
		(net 494)
	)
	(segment
		(start 145.6 86.175)
		(end 145.6 87.2)
		(width 0.1)
		(layer "B.Cu")
		(net 494)
	)
	(segment
		(start 148.7 93.5)
		(end 148.7 98.1)
		(width 0.1)
		(layer "B.Cu")
		(net 494)
	)
	(segment
		(start 149.8 99.2)
		(end 151 99.2)
		(width 0.1)
		(layer "B.Cu")
		(net 494)
	)
	(segment
		(start 144.6 88.2)
		(end 144.6 89.4)
		(width 0.1)
		(layer "B.Cu")
		(net 494)
	)
	(segment
		(start 145.6 86.175)
		(end 148.9 82.875)
		(width 0.1)
		(layer "In5.Cu")
		(net 494)
	)
	(segment
		(start 147.4 70.5)
		(end 147 70.5)
		(width 0.1)
		(layer "In5.Cu")
		(net 494)
	)
	(segment
		(start 148.9 72)
		(end 147.4 70.5)
		(width 0.1)
		(layer "In5.Cu")
		(net 494)
	)
	(segment
		(start 148.9 82.875)
		(end 148.9 72)
		(width 0.1)
		(layer "In5.Cu")
		(net 494)
	)
	(segment
		(start 202.752 111.798)
		(end 203.872 111.798)
		(width 0.1)
		(layer "F.Cu")
		(net 495)
	)
	(segment
		(start 205.248 56.497999)
		(end 208.750001 56.497999)
		(width 0.2)
		(layer "F.Cu")
		(net 495)
	)
	(segment
		(start 203.248 56.768)
		(end 203.25 56.77)
		(width 0.2)
		(layer "F.Cu")
		(net 495)
	)
	(segment
		(start 206.94 102.86804)
		(end 205.87 101.79804)
		(width 0.1)
		(layer "F.Cu")
		(net 495)
	)
	(segment
		(start 201.6 112.1)
		(end 202.45 112.1)
		(width 0.1)
		(layer "F.Cu")
		(net 495)
	)
	(segment
		(start 205.87 97.47804)
		(end 204.78598 96.39402)
		(width 0.1)
		(layer "F.Cu")
		(net 495)
	)
	(segment
		(start 208.750001 56.497999)
		(end 209.048 56.2)
		(width 0.2)
		(layer "F.Cu")
		(net 495)
	)
	(segment
		(start 204.597 55.846999)
		(end 204.95 56.199999)
		(width 0.2)
		(layer "F.Cu")
		(net 495)
	)
	(segment
		(start 204.95 56.199999)
		(end 205.248 56.497999)
		(width 0.2)
		(layer "F.Cu")
		(net 495)
	)
	(segment
		(start 204.862 111.798)
		(end 205.23 111.43)
		(width 0.1)
		(layer "F.Cu")
		(net 495)
	)
	(segment
		(start 203.872 111.798)
		(end 204.862 111.798)
		(width 0.1)
		(layer "F.Cu")
		(net 495)
	)
	(segment
		(start 206.94 108.76)
		(end 206.94 102.86804)
		(width 0.1)
		(layer "F.Cu")
		(net 495)
	)
	(segment
		(start 205.87 101.79804)
		(end 205.87 97.47804)
		(width 0.1)
		(layer "F.Cu")
		(net 495)
	)
	(segment
		(start 203.248 55.846999)
		(end 204.597 55.846999)
		(width 0.2)
		(layer "F.Cu")
		(net 495)
	)
	(segment
		(start 202.45 112.1)
		(end 202.752 111.798)
		(width 0.1)
		(layer "F.Cu")
		(net 495)
	)
	(segment
		(start 205.23 111.43)
		(end 205.23 110.47)
		(width 0.1)
		(layer "F.Cu")
		(net 495)
	)
	(segment
		(start 204.29 95.89804)
		(end 204.29 95.49)
		(width 0.1)
		(layer "F.Cu")
		(net 495)
	)
	(segment
		(start 94.430532 69.930532)
		(end 93.8 69.3)
		(width 0.1)
		(layer "F.Cu")
		(net 495)
	)
	(segment
		(start 204.78598 96.39402)
		(end 204.29 95.89804)
		(width 0.1)
		(layer "F.Cu")
		(net 495)
	)
	(segment
		(start 205.23 110.47)
		(end 206.94 108.76)
		(width 0.1)
		(layer "F.Cu")
		(net 495)
	)
	(segment
		(start 94.430532 70.65)
		(end 94.430532 69.930532)
		(width 0.1)
		(layer "F.Cu")
		(net 495)
	)
	(segment
		(start 203.248 55.846999)
		(end 203.248 56.768)
		(width 0.2)
		(layer "F.Cu")
		(net 495)
	)
	(via
		(at 93.8 69.3)
		(size 0.45)
		(drill 0.1)
		(layers "F.Cu" "B.Cu")
		(net 495)
	)
	(via
		(at 204 55.9)
		(size 0.45)
		(drill 0.1)
		(layers "F.Cu" "B.Cu")
		(net 495)
	)
	(via
		(at 204.29 95.49)
		(size 0.45)
		(drill 0.1)
		(layers "F.Cu" "B.Cu")
		(net 495)
	)
	(segment
		(start 93.8 69.3)
		(end 92.6 69.3)
		(width 0.1)
		(layer "B.Cu")
		(net 495)
	)
	(segment
		(start 204.29 95.49)
		(end 203.81 95.97)
		(width 0.1)
		(layer "In5.Cu")
		(net 495)
	)
	(segment
		(start 216.72 55.42)
		(end 216.33 55.03)
		(width 0.1)
		(layer "In5.Cu")
		(net 495)
	)
	(segment
		(start 192.79 78.62)
		(end 192.79 72.22)
		(width 0.1)
		(layer "In5.Cu")
		(net 495)
	)
	(segment
		(start 198.45 59.22)
		(end 198.92 58.75)
		(width 0.1)
		(layer "In5.Cu")
		(net 495)
	)
	(segment
		(start 195.410416 90.830416)
		(end 191.609584 87.029584)
		(width 0.1)
		(layer "In5.Cu")
		(net 495)
	)
	(segment
		(start 192.3 79.11)
		(end 192.79 78.62)
		(width 0.1)
		(layer "In5.Cu")
		(net 495)
	)
	(segment
		(start 216.72 56.41)
		(end 216.72 55.42)
		(width 0.1)
		(layer "In5.Cu")
		(net 495)
	)
	(segment
		(start 203.81 95.97)
		(end 201.73 95.97)
		(width 0.1)
		(layer "In5.Cu")
		(net 495)
	)
	(segment
		(start 192.3 81.22)
		(end 192.3 79.11)
		(width 0.1)
		(layer "In5.Cu")
		(net 495)
	)
	(segment
		(start 198.18 60.53)
		(end 198.45 60.26)
		(width 0.1)
		(layer "In5.Cu")
		(net 495)
	)
	(segment
		(start 194.74 70.27)
		(end 194.74 62.85)
		(width 0.1)
		(layer "In5.Cu")
		(net 495)
	)
	(segment
		(start 191.609584 81.910416)
		(end 192.3 81.22)
		(width 0.1)
		(layer "In5.Cu")
		(net 495)
	)
	(segment
		(start 216.33 55.03)
		(end 212.36 55.03)
		(width 0.1)
		(layer "In5.Cu")
		(net 495)
	)
	(segment
		(start 198.92 58.75)
		(end 214.38 58.75)
		(width 0.1)
		(layer "In5.Cu")
		(net 495)
	)
	(segment
		(start 197.06 60.53)
		(end 198.18 60.53)
		(width 0.1)
		(layer "In5.Cu")
		(net 495)
	)
	(segment
		(start 211.49 55.9)
		(end 204 55.9)
		(width 0.1)
		(layer "In5.Cu")
		(net 495)
	)
	(segment
		(start 192.79 72.22)
		(end 194.74 70.27)
		(width 0.1)
		(layer "In5.Cu")
		(net 495)
	)
	(segment
		(start 201.73 95.97)
		(end 196.590416 90.830416)
		(width 0.1)
		(layer "In5.Cu")
		(net 495)
	)
	(segment
		(start 198.45 60.26)
		(end 198.45 59.22)
		(width 0.1)
		(layer "In5.Cu")
		(net 495)
	)
	(segment
		(start 194.74 62.85)
		(end 197.06 60.53)
		(width 0.1)
		(layer "In5.Cu")
		(net 495)
	)
	(segment
		(start 212.36 55.03)
		(end 211.49 55.9)
		(width 0.1)
		(layer "In5.Cu")
		(net 495)
	)
	(segment
		(start 191.609584 87.029584)
		(end 191.609584 81.910416)
		(width 0.1)
		(layer "In5.Cu")
		(net 495)
	)
	(segment
		(start 196.590416 90.830416)
		(end 195.410416 90.830416)
		(width 0.1)
		(layer "In5.Cu")
		(net 495)
	)
	(segment
		(start 214.38 58.75)
		(end 216.72 56.41)
		(width 0.1)
		(layer "In5.Cu")
		(net 495)
	)
	(segment
		(start 203.18 55.08)
		(end 204 55.9)
		(width 0.1)
		(layer "In7.Cu")
		(net 495)
	)
	(segment
		(start 124.1 56.5)
		(end 124.41 56.19)
		(width 0.1)
		(layer "In7.Cu")
		(net 495)
	)
	(segment
		(start 146.5 62.5)
		(end 149.25 65.25)
		(width 0.1)
		(layer "In7.Cu")
		(net 495)
	)
	(segment
		(start 109.55 56.5)
		(end 124.1 56.5)
		(width 0.1)
		(layer "In7.Cu")
		(net 495)
	)
	(segment
		(start 165.25 67.25)
		(end 166.2 66.3)
		(width 0.1)
		(layer "In7.Cu")
		(net 495)
	)
	(segment
		(start 149.25 65.75)
		(end 150.75 67.25)
		(width 0.1)
		(layer "In7.Cu")
		(net 495)
	)
	(segment
		(start 168.9 65.6)
		(end 168.9 61.1)
		(width 0.1)
		(layer "In7.Cu")
		(net 495)
	)
	(segment
		(start 170.9 59.1)
		(end 174.1 59.1)
		(width 0.1)
		(layer "In7.Cu")
		(net 495)
	)
	(segment
		(start 174.1 59.1)
		(end 174.49 59.49)
		(width 0.1)
		(layer "In7.Cu")
		(net 495)
	)
	(segment
		(start 168.9 61.1)
		(end 170.9 59.1)
		(width 0.1)
		(layer "In7.Cu")
		(net 495)
	)
	(segment
		(start 166.2 66.3)
		(end 168.2 66.3)
		(width 0.1)
		(layer "In7.Cu")
		(net 495)
	)
	(segment
		(start 98.6 67.45)
		(end 109.55 56.5)
		(width 0.1)
		(layer "In7.Cu")
		(net 495)
	)
	(segment
		(start 98.05 67.45)
		(end 98.6 67.45)
		(width 0.1)
		(layer "In7.Cu")
		(net 495)
	)
	(segment
		(start 186.2 55.9)
		(end 187.02 55.08)
		(width 0.1)
		(layer "In7.Cu")
		(net 495)
	)
	(segment
		(start 124.41 56.19)
		(end 141.72 56.19)
		(width 0.1)
		(layer "In7.Cu")
		(net 495)
	)
	(segment
		(start 186.2 58.6)
		(end 186.2 55.9)
		(width 0.1)
		(layer "In7.Cu")
		(net 495)
	)
	(segment
		(start 150.75 67.25)
		(end 165.25 67.25)
		(width 0.1)
		(layer "In7.Cu")
		(net 495)
	)
	(segment
		(start 141.72 56.19)
		(end 146.5 60.97)
		(width 0.1)
		(layer "In7.Cu")
		(net 495)
	)
	(segment
		(start 146.5 60.97)
		(end 146.5 62.5)
		(width 0.1)
		(layer "In7.Cu")
		(net 495)
	)
	(segment
		(start 96.2 69.3)
		(end 98.05 67.45)
		(width 0.1)
		(layer "In7.Cu")
		(net 495)
	)
	(segment
		(start 174.49 59.49)
		(end 185.31 59.49)
		(width 0.1)
		(layer "In7.Cu")
		(net 495)
	)
	(segment
		(start 168.2 66.3)
		(end 168.9 65.6)
		(width 0.1)
		(layer "In7.Cu")
		(net 495)
	)
	(segment
		(start 93.8 69.3)
		(end 96.2 69.3)
		(width 0.1)
		(layer "In7.Cu")
		(net 495)
	)
	(segment
		(start 185.31 59.49)
		(end 186.2 58.6)
		(width 0.1)
		(layer "In7.Cu")
		(net 495)
	)
	(segment
		(start 187.02 55.08)
		(end 203.18 55.08)
		(width 0.1)
		(layer "In7.Cu")
		(net 495)
	)
	(segment
		(start 149.25 65.25)
		(end 149.25 65.75)
		(width 0.1)
		(layer "In7.Cu")
		(net 495)
	)
	(segment
		(start 149.7 98.8)
		(end 151.8 98.8)
		(width 0.1)
		(layer "F.Cu")
		(net 496)
	)
	(segment
		(start 149.2 99.3)
		(end 149.7 98.8)
		(width 0.1)
		(layer "F.Cu")
		(net 496)
	)
	(via
		(at 149.2 99.3)
		(size 0.45)
		(drill 0.1)
		(layers "F.Cu" "B.Cu")
		(net 496)
	)
	(via
		(at 144.230532 75.15)
		(size 0.45)
		(drill 0.1)
		(layers "F.Cu" "B.Cu")
		(net 496)
	)
	(segment
		(start 144.4 90.5)
		(end 146.1 92.2)
		(width 0.1)
		(layer "B.Cu")
		(net 496)
	)
	(segment
		(start 147.1 92.2)
		(end 148.1 93.2)
		(width 0.1)
		(layer "B.Cu")
		(net 496)
	)
	(segment
		(start 145.7 83.9)
		(end 144.4 85.2)
		(width 0.1)
		(layer "B.Cu")
		(net 496)
	)
	(segment
		(start 146.1 75.25)
		(end 146.1 76.25)
		(width 0.1)
		(layer "B.Cu")
		(net 496)
	)
	(segment
		(start 146.1 92.2)
		(end 147.1 92.2)
		(width 0.1)
		(layer "B.Cu")
		(net 496)
	)
	(segment
		(start 148.1 93.2)
		(end 148.1 98.2)
		(width 0.1)
		(layer "B.Cu")
		(net 496)
	)
	(segment
		(start 144.230532 75.15)
		(end 144.730532 74.65)
		(width 0.1)
		(layer "B.Cu")
		(net 496)
	)
	(segment
		(start 146.1 76.25)
		(end 145.7 76.65)
		(width 0.1)
		(layer "B.Cu")
		(net 496)
	)
	(segment
		(start 145.7 76.65)
		(end 145.7 83.9)
		(width 0.1)
		(layer "B.Cu")
		(net 496)
	)
	(segment
		(start 144.730532 74.65)
		(end 145.5 74.65)
		(width 0.1)
		(layer "B.Cu")
		(net 496)
	)
	(segment
		(start 148.1 98.2)
		(end 149.2 99.3)
		(width 0.1)
		(layer "B.Cu")
		(net 496)
	)
	(segment
		(start 144.4 87.7)
		(end 144.4 90.5)
		(width 0.1)
		(layer "B.Cu")
		(net 496)
	)
	(segment
		(start 144.4 85.2)
		(end 144.4 85.9)
		(width 0.1)
		(layer "B.Cu")
		(net 496)
	)
	(segment
		(start 145 87.1)
		(end 144.4 87.7)
		(width 0.1)
		(layer "B.Cu")
		(net 496)
	)
	(segment
		(start 145 86.5)
		(end 145 87.1)
		(width 0.1)
		(layer "B.Cu")
		(net 496)
	)
	(segment
		(start 144.4 85.9)
		(end 145 86.5)
		(width 0.1)
		(layer "B.Cu")
		(net 496)
	)
	(segment
		(start 145.5 74.65)
		(end 146.1 75.25)
		(width 0.1)
		(layer "B.Cu")
		(net 496)
	)
	(segment
		(start 219.990499 124.862)
		(end 220.055499 124.927)
		(width 0.19)
		(layer "F.Cu")
		(net 498)
	)
	(segment
		(start 220.055499 124.927)
		(end 220.468 124.927)
		(width 0.19)
		(layer "F.Cu")
		(net 498)
	)
	(segment
		(start 211.97563 123.286)
		(end 212.27663 122.985)
		(width 0.19)
		(layer "F.Cu")
		(net 498)
	)
	(segment
		(start 221.24 124.927)
		(end 221.652501 124.927)
		(width 0.19)
		(layer "F.Cu")
		(net 498)
	)
	(segment
		(start 211.142 123.301)
		(end 211.5456 123.301)
		(width 0.19)
		(layer "F.Cu")
		(net 498)
	)
	(segment
		(start 211.5606 123.286)
		(end 211.97563 123.286)
		(width 0.19)
		(layer "F.Cu")
		(net 498)
	)
	(segment
		(start 234.430532 125.853749)
		(end 234.495532 125.788749)
		(width 0.19)
		(layer "F.Cu")
		(net 498)
	)
	(segment
		(start 225.695077 123.885)
		(end 225.695077 123.963162)
		(width 0.19)
		(layer "F.Cu")
		(net 498)
	)
	(segment
		(start 217.80037 124.862)
		(end 219.990499 124.862)
		(width 0.19)
		(layer "F.Cu")
		(net 498)
	)
	(segment
		(start 221.24 124.927)
		(end 220.468 124.927)
		(width 0.19)
		(layer "F.Cu")
		(net 498)
	)
	(segment
		(start 221.717501 124.862)
		(end 223.89963 124.862)
		(width 0.19)
		(layer "F.Cu")
		(net 498)
	)
	(segment
		(start 234.495532 125.788749)
		(end 234.495532 124.887162)
		(width 0.19)
		(layer "F.Cu")
		(net 498)
	)
	(segment
		(start 215.92337 122.985)
		(end 217.80037 124.862)
		(width 0.19)
		(layer "F.Cu")
		(net 498)
	)
	(segment
		(start 225.07663 123.685)
		(end 225.495077 123.685)
		(width 0.19)
		(layer "F.Cu")
		(net 498)
	)
	(segment
		(start 212.27663 122.985)
		(end 215.92337 122.985)
		(width 0.19)
		(layer "F.Cu")
		(net 498)
	)
	(segment
		(start 234.430532 127.0725)
		(end 234.430532 125.853749)
		(width 0.19)
		(layer "F.Cu")
		(net 498)
	)
	(segment
		(start 234.495532 124.887162)
		(end 233.29337 123.685)
		(width 0.19)
		(layer "F.Cu")
		(net 498)
	)
	(segment
		(start 221.652501 124.927)
		(end 221.717501 124.862)
		(width 0.19)
		(layer "F.Cu")
		(net 498)
	)
	(segment
		(start 226.195077 123.963162)
		(end 226.195077 123.885)
		(width 0.19)
		(layer "F.Cu")
		(net 498)
	)
	(segment
		(start 211.5456 123.301)
		(end 211.5606 123.286)
		(width 0.19)
		(layer "F.Cu")
		(net 498)
	)
	(segment
		(start 233.29337 123.685)
		(end 226.395077 123.685)
		(width 0.19)
		(layer "F.Cu")
		(net 498)
	)
	(segment
		(start 225.895077 124.163162)
		(end 225.995077 124.163162)
		(width 0.19)
		(layer "F.Cu")
		(net 498)
	)
	(segment
		(start 223.89963 124.862)
		(end 225.07663 123.685)
		(width 0.19)
		(layer "F.Cu")
		(net 498)
	)
	(arc
		(start 225.495077 123.685)
		(mid 225.636498 123.743579)
		(end 225.695077 123.885)
		(width 0.19)
		(layer "F.Cu")
		(net 498)
	)
	(arc
		(start 225.695077 123.963162)
		(mid 225.753656 124.104583)
		(end 225.895077 124.163162)
		(width 0.19)
		(layer "F.Cu")
		(net 498)
	)
	(arc
		(start 225.995077 124.163162)
		(mid 226.136498 124.104583)
		(end 226.195077 123.963162)
		(width 0.19)
		(layer "F.Cu")
		(net 498)
	)
	(arc
		(start 226.195077 123.885)
		(mid 226.253656 123.743579)
		(end 226.395077 123.685)
		(width 0.19)
		(layer "F.Cu")
		(net 498)
	)
	(segment
		(start 211.5706 128.525)
		(end 211.972488 128.525)
		(width 0.17)
		(layer "F.Cu")
		(net 499)
	)
	(segment
		(start 232.930532 126.039468)
		(end 233.07 125.9)
		(width 0.17)
		(layer "F.Cu")
		(net 499)
	)
	(segment
		(start 232.930532 127.0725)
		(end 232.930532 126.039468)
		(width 0.17)
		(layer "F.Cu")
		(net 499)
	)
	(segment
		(start 219.980499 127.925)
		(end 219.625 127.925)
		(width 0.17)
		(layer "F.Cu")
		(net 499)
	)
	(segment
		(start 219.625 127.925)
		(end 219.5 128.05)
		(width 0.17)
		(layer "F.Cu")
		(net 499)
	)
	(segment
		(start 221.652501 128)
		(end 221.727501 127.925)
		(width 0.17)
		(layer "F.Cu")
		(net 499)
	)
	(segment
		(start 220.055499 128)
		(end 219.980499 127.925)
		(width 0.17)
		(layer "F.Cu")
		(net 499)
	)
	(segment
		(start 232.430532 129.3475)
		(end 232.430532 128.439468)
		(width 0.17)
		(layer "F.Cu")
		(net 499)
	)
	(segment
		(start 232.430532 128.439468)
		(end 232.930532 127.939468)
		(width 0.17)
		(layer "F.Cu")
		(net 499)
	)
	(segment
		(start 212.975 129.425)
		(end 213.1 129.3)
		(width 0.17)
		(layer "F.Cu")
		(net 499)
	)
	(segment
		(start 220.468 128)
		(end 220.055499 128)
		(width 0.17)
		(layer "F.Cu")
		(net 499)
	)
	(segment
		(start 211.142 128.5)
		(end 211.5456 128.5)
		(width 0.17)
		(layer "F.Cu")
		(net 499)
	)
	(segment
		(start 212.872488 129.425)
		(end 212.975 129.425)
		(width 0.17)
		(layer "F.Cu")
		(net 499)
	)
	(segment
		(start 211.5456 128.5)
		(end 211.5706 128.525)
		(width 0.17)
		(layer "F.Cu")
		(net 499)
	)
	(segment
		(start 222.075 127.925)
		(end 222.2 128.05)
		(width 0.17)
		(layer "F.Cu")
		(net 499)
	)
	(segment
		(start 232.930532 127.939468)
		(end 232.930532 127.0725)
		(width 0.17)
		(layer "F.Cu")
		(net 499)
	)
	(segment
		(start 211.972488 128.525)
		(end 212.872488 129.425)
		(width 0.17)
		(layer "F.Cu")
		(net 499)
	)
	(segment
		(start 221.727501 127.925)
		(end 222.075 127.925)
		(width 0.17)
		(layer "F.Cu")
		(net 499)
	)
	(segment
		(start 221.24 128)
		(end 221.652501 128)
		(width 0.17)
		(layer "F.Cu")
		(net 499)
	)
	(segment
		(start 220.468 128)
		(end 221.24 128)
		(width 0.17)
		(layer "F.Cu")
		(net 499)
	)
	(via
		(at 222.2 128.05)
		(size 0.45)
		(drill 0.1)
		(layers "F.Cu" "B.Cu")
		(net 499)
	)
	(via
		(at 213.1 129.3)
		(size 0.45)
		(drill 0.1)
		(layers "F.Cu" "B.Cu")
		(net 499)
	)
	(via
		(at 219.5 128.05)
		(size 0.45)
		(drill 0.1)
		(layers "F.Cu" "B.Cu")
		(net 499)
	)
	(via
		(at 233.07 125.9)
		(size 0.45)
		(drill 0.1)
		(layers "F.Cu" "B.Cu")
		(net 499)
	)
	(segment
		(start 226.7466 123.5125)
		(end 225.6125 124.6466)
		(width 0.125)
		(layer "In7.Cu")
		(net 499)
	)
	(segment
		(start 233.07 125.9)
		(end 232.882501 126.087499)
		(width 0.125)
		(layer "In7.Cu")
		(net 499)
	)
	(segment
		(start 225.6125 124.6466)
		(end 225.6125 125.9466)
		(width 0.125)
		(layer "In7.Cu")
		(net 499)
	)
	(segment
		(start 215.547821 128.002501)
		(end 215.547821 128.215517)
		(width 0.125)
		(layer "In7.Cu")
		(net 499)
	)
	(segment
		(start 212.3125 129.1534)
		(end 212.3125 128.4466)
		(width 0.125)
		(layer "In7.Cu")
		(net 499)
	)
	(segment
		(start 212.896599 127.862501)
		(end 215.407821 127.862501)
		(width 0.125)
		(layer "In7.Cu")
		(net 499)
	)
	(segment
		(start 232.882501 126.353401)
		(end 233.1166 126.5875)
		(width 0.125)
		(layer "In7.Cu")
		(net 499)
	)
	(segment
		(start 232.9234 123.5125)
		(end 232.18 123.5125)
		(width 0.125)
		(layer "In7.Cu")
		(net 499)
	)
	(segment
		(start 230.2 123.6925)
		(end 230.2 123.878119)
		(width 0.125)
		(layer "In7.Cu")
		(net 499)
	)
	(segment
		(start 229.75 123.878119)
		(end 229.75 123.6925)
		(width 0.125)
		(layer "In7.Cu")
		(net 499)
	)
	(segment
		(start 212.912501 129.487499)
		(end 212.646599 129.487499)
		(width 0.125)
		(layer "In7.Cu")
		(net 499)
	)
	(segment
		(start 215.687821 128.355517)
		(end 215.757821 128.355517)
		(width 0.125)
		(layer "In7.Cu")
		(net 499)
	)
	(segment
		(start 233.9575 124.5466)
		(end 232.9234 123.5125)
		(width 0.125)
		(layer "In7.Cu")
		(net 499)
	)
	(segment
		(start 232.882501 126.087499)
		(end 232.882501 126.353401)
		(width 0.125)
		(layer "In7.Cu")
		(net 499)
	)
	(segment
		(start 229.3 123.6925)
		(end 229.3 123.878098)
		(width 0.125)
		(layer "In7.Cu")
		(net 499)
	)
	(segment
		(start 213.1 129.3)
		(end 212.912501 129.487499)
		(width 0.125)
		(layer "In7.Cu")
		(net 499)
	)
	(segment
		(start 227.77 123.5125)
		(end 227.68 123.5125)
		(width 0.125)
		(layer "In7.Cu")
		(net 499)
	)
	(segment
		(start 230.92 124.058098)
		(end 230.83 124.058098)
		(width 0.125)
		(layer "In7.Cu")
		(net 499)
	)
	(segment
		(start 228.67 123.5125)
		(end 228.58 123.5125)
		(width 0.125)
		(layer "In7.Cu")
		(net 499)
	)
	(segment
		(start 230.47 123.5125)
		(end 230.38 123.5125)
		(width 0.125)
		(layer "In7.Cu")
		(net 499)
	)
	(segment
		(start 227.45 123.5125)
		(end 226.7466 123.5125)
		(width 0.125)
		(layer "In7.Cu")
		(net 499)
	)
	(segment
		(start 223.696599 127.862501)
		(end 222.387499 127.862501)
		(width 0.125)
		(layer "In7.Cu")
		(net 499)
	)
	(segment
		(start 228.85 123.878098)
		(end 228.85 123.6925)
		(width 0.125)
		(layer "In7.Cu")
		(net 499)
	)
	(segment
		(start 231.37 123.5125)
		(end 231.28 123.5125)
		(width 0.125)
		(layer "In7.Cu")
		(net 499)
	)
	(segment
		(start 233.1166 126.5875)
		(end 233.7234 126.5875)
		(width 0.125)
		(layer "In7.Cu")
		(net 499)
	)
	(segment
		(start 212.646599 129.487499)
		(end 212.3125 129.1534)
		(width 0.125)
		(layer "In7.Cu")
		(net 499)
	)
	(segment
		(start 230.02 124.058119)
		(end 229.93 124.058119)
		(width 0.125)
		(layer "In7.Cu")
		(net 499)
	)
	(segment
		(start 232 123.6925)
		(end 232 123.878119)
		(width 0.125)
		(layer "In7.Cu")
		(net 499)
	)
	(segment
		(start 233.7234 126.5875)
		(end 233.9575 126.3534)
		(width 0.125)
		(layer "In7.Cu")
		(net 499)
	)
	(segment
		(start 225.6125 125.9466)
		(end 223.696599 127.862501)
		(width 0.125)
		(layer "In7.Cu")
		(net 499)
	)
	(segment
		(start 228.22 124.058119)
		(end 228.13 124.058119)
		(width 0.125)
		(layer "In7.Cu")
		(net 499)
	)
	(segment
		(start 216.037821 127.862501)
		(end 219.312501 127.862501)
		(width 0.125)
		(layer "In7.Cu")
		(net 499)
	)
	(segment
		(start 230.65 123.878098)
		(end 230.65 123.6925)
		(width 0.125)
		(layer "In7.Cu")
		(net 499)
	)
	(segment
		(start 212.3125 128.4466)
		(end 212.896599 127.862501)
		(width 0.125)
		(layer "In7.Cu")
		(net 499)
	)
	(segment
		(start 227.68 123.5125)
		(end 227.45 123.5125)
		(width 0.125)
		(layer "In7.Cu")
		(net 499)
	)
	(segment
		(start 231.55 123.878119)
		(end 231.55 123.6925)
		(width 0.125)
		(layer "In7.Cu")
		(net 499)
	)
	(segment
		(start 229.12 124.058098)
		(end 229.03 124.058098)
		(width 0.125)
		(layer "In7.Cu")
		(net 499)
	)
	(segment
		(start 227.95 123.878119)
		(end 227.95 123.6925)
		(width 0.125)
		(layer "In7.Cu")
		(net 499)
	)
	(segment
		(start 222.387499 127.862501)
		(end 222.2 128.05)
		(width 0.125)
		(layer "In7.Cu")
		(net 499)
	)
	(segment
		(start 231.1 123.6925)
		(end 231.1 123.878098)
		(width 0.125)
		(layer "In7.Cu")
		(net 499)
	)
	(segment
		(start 231.82 124.058119)
		(end 231.73 124.058119)
		(width 0.125)
		(layer "In7.Cu")
		(net 499)
	)
	(segment
		(start 215.897821 128.215517)
		(end 215.897821 128.002501)
		(width 0.125)
		(layer "In7.Cu")
		(net 499)
	)
	(segment
		(start 219.312501 127.862501)
		(end 219.5 128.05)
		(width 0.125)
		(layer "In7.Cu")
		(net 499)
	)
	(segment
		(start 233.9575 126.3534)
		(end 233.9575 124.5466)
		(width 0.125)
		(layer "In7.Cu")
		(net 499)
	)
	(segment
		(start 229.57 123.5125)
		(end 229.48 123.5125)
		(width 0.125)
		(layer "In7.Cu")
		(net 499)
	)
	(segment
		(start 228.4 123.6925)
		(end 228.4 123.878119)
		(width 0.125)
		(layer "In7.Cu")
		(net 499)
	)
	(arc
		(start 231.28 123.5125)
		(mid 231.152721 123.565221)
		(end 231.1 123.6925)
		(width 0.125)
		(layer "In7.Cu")
		(net 499)
	)
	(arc
		(start 230.83 124.058098)
		(mid 230.702721 124.005377)
		(end 230.65 123.878098)
		(width 0.125)
		(layer "In7.Cu")
		(net 499)
	)
	(arc
		(start 228.4 123.878119)
		(mid 228.347279 124.005398)
		(end 228.22 124.058119)
		(width 0.125)
		(layer "In7.Cu")
		(net 499)
	)
	(arc
		(start 215.407821 127.862501)
		(mid 215.506816 127.903506)
		(end 215.547821 128.002501)
		(width 0.125)
		(layer "In7.Cu")
		(net 499)
	)
	(arc
		(start 228.58 123.5125)
		(mid 228.452721 123.565221)
		(end 228.4 123.6925)
		(width 0.125)
		(layer "In7.Cu")
		(net 499)
	)
	(arc
		(start 229.03 124.058098)
		(mid 228.902721 124.005377)
		(end 228.85 123.878098)
		(width 0.125)
		(layer "In7.Cu")
		(net 499)
	)
	(arc
		(start 229.75 123.6925)
		(mid 229.697279 123.565221)
		(end 229.57 123.5125)
		(width 0.125)
		(layer "In7.Cu")
		(net 499)
	)
	(arc
		(start 215.757821 128.355517)
		(mid 215.856816 128.314512)
		(end 215.897821 128.215517)
		(width 0.125)
		(layer "In7.Cu")
		(net 499)
	)
	(arc
		(start 228.13 124.058119)
		(mid 228.002721 124.005398)
		(end 227.95 123.878119)
		(width 0.125)
		(layer "In7.Cu")
		(net 499)
	)
	(arc
		(start 229.48 123.5125)
		(mid 229.352721 123.565221)
		(end 229.3 123.6925)
		(width 0.125)
		(layer "In7.Cu")
		(net 499)
	)
	(arc
		(start 229.93 124.058119)
		(mid 229.802721 124.005398)
		(end 229.75 123.878119)
		(width 0.125)
		(layer "In7.Cu")
		(net 499)
	)
	(arc
		(start 229.3 123.878098)
		(mid 229.247279 124.005377)
		(end 229.12 124.058098)
		(width 0.125)
		(layer "In7.Cu")
		(net 499)
	)
	(arc
		(start 231.73 124.058119)
		(mid 231.602721 124.005398)
		(end 231.55 123.878119)
		(width 0.125)
		(layer "In7.Cu")
		(net 499)
	)
	(arc
		(start 232 123.878119)
		(mid 231.947279 124.005398)
		(end 231.82 124.058119)
		(width 0.125)
		(layer "In7.Cu")
		(net 499)
	)
	(arc
		(start 232.18 123.5125)
		(mid 232.052721 123.565221)
		(end 232 123.6925)
		(width 0.125)
		(layer "In7.Cu")
		(net 499)
	)
	(arc
		(start 227.95 123.6925)
		(mid 227.897279 123.565221)
		(end 227.77 123.5125)
		(width 0.125)
		(layer "In7.Cu")
		(net 499)
	)
	(arc
		(start 231.1 123.878098)
		(mid 231.047279 124.005377)
		(end 230.92 124.058098)
		(width 0.125)
		(layer "In7.Cu")
		(net 499)
	)
	(arc
		(start 230.65 123.6925)
		(mid 230.597279 123.565221)
		(end 230.47 123.5125)
		(width 0.125)
		(layer "In7.Cu")
		(net 499)
	)
	(arc
		(start 215.547821 128.215517)
		(mid 215.588826 128.314512)
		(end 215.687821 128.355517)
		(width 0.125)
		(layer "In7.Cu")
		(net 499)
	)
	(arc
		(start 215.897821 128.002501)
		(mid 215.938826 127.903506)
		(end 216.037821 127.862501)
		(width 0.125)
		(layer "In7.Cu")
		(net 499)
	)
	(arc
		(start 230.2 123.878119)
		(mid 230.147279 124.005398)
		(end 230.02 124.058119)
		(width 0.125)
		(layer "In7.Cu")
		(net 499)
	)
	(arc
		(start 231.55 123.6925)
		(mid 231.497279 123.565221)
		(end 231.37 123.5125)
		(width 0.125)
		(layer "In7.Cu")
		(net 499)
	)
	(arc
		(start 228.85 123.6925)
		(mid 228.797279 123.565221)
		(end 228.67 123.5125)
		(width 0.125)
		(layer "In7.Cu")
		(net 499)
	)
	(arc
		(start 230.38 123.5125)
		(mid 230.252721 123.565221)
		(end 230.2 123.6925)
		(width 0.125)
		(layer "In7.Cu")
		(net 499)
	)
	(segment
		(start 211.82237 122.916)
		(end 212.12337 122.615)
		(width 0.19)
		(layer "F.Cu")
		(net 500)
	)
	(segment
		(start 221.652501 124.427)
		(end 221.24 124.427)
		(width 0.19)
		(layer "F.Cu")
		(net 500)
	)
	(segment
		(start 211.142 122.901)
		(end 211.5456 122.901)
		(width 0.19)
		(layer "F.Cu")
		(net 500)
	)
	(segment
		(start 220.055499 124.427)
		(end 220.468 124.427)
		(width 0.19)
		(layer "F.Cu")
		(net 500)
	)
	(segment
		(start 216.07663 122.615)
		(end 217.95363 124.492)
		(width 0.19)
		(layer "F.Cu")
		(net 500)
	)
	(segment
		(start 234.865532 124.733902)
		(end 233.44663 123.315)
		(width 0.19)
		(layer "F.Cu")
		(net 500)
	)
	(segment
		(start 211.5456 122.901)
		(end 211.5606 122.916)
		(width 0.19)
		(layer "F.Cu")
		(net 500)
	)
	(segment
		(start 234.930532 127.0725)
		(end 234.930532 125.853749)
		(width 0.19)
		(layer "F.Cu")
		(net 500)
	)
	(segment
		(start 221.717501 124.492)
		(end 221.652501 124.427)
		(width 0.19)
		(layer "F.Cu")
		(net 500)
	)
	(segment
		(start 223.74637 124.492)
		(end 221.717501 124.492)
		(width 0.19)
		(layer "F.Cu")
		(net 500)
	)
	(segment
		(start 234.865532 125.788749)
		(end 234.865532 124.733902)
		(width 0.19)
		(layer "F.Cu")
		(net 500)
	)
	(segment
		(start 234.930532 125.853749)
		(end 234.865532 125.788749)
		(width 0.19)
		(layer "F.Cu")
		(net 500)
	)
	(segment
		(start 219.990499 124.492)
		(end 220.055499 124.427)
		(width 0.19)
		(layer "F.Cu")
		(net 500)
	)
	(segment
		(start 224.92337 123.315)
		(end 223.74637 124.492)
		(width 0.19)
		(layer "F.Cu")
		(net 500)
	)
	(segment
		(start 212.12337 122.615)
		(end 216.07663 122.615)
		(width 0.19)
		(layer "F.Cu")
		(net 500)
	)
	(segment
		(start 217.95363 124.492)
		(end 219.990499 124.492)
		(width 0.19)
		(layer "F.Cu")
		(net 500)
	)
	(segment
		(start 220.468 124.427)
		(end 221.24 124.427)
		(width 0.19)
		(layer "F.Cu")
		(net 500)
	)
	(segment
		(start 211.5606 122.916)
		(end 211.82237 122.916)
		(width 0.19)
		(layer "F.Cu")
		(net 500)
	)
	(segment
		(start 233.44663 123.315)
		(end 224.92337 123.315)
		(width 0.19)
		(layer "F.Cu")
		(net 500)
	)
	(segment
		(start 211.914401 126.515)
		(end 212.385 126.515)
		(width 0.19)
		(layer "F.Cu")
		(net 501)
	)
	(segment
		(start 221.24 130.575)
		(end 221.652501 130.575)
		(width 0.19)
		(layer "F.Cu")
		(net 501)
	)
	(segment
		(start 230.485 130.685)
		(end 230.37 130.8)
		(width 0.19)
		(layer "F.Cu")
		(net 501)
	)
	(segment
		(start 212.785 126.115)
		(end 215.07663 126.115)
		(width 0.19)
		(layer "F.Cu")
		(net 501)
	)
	(segment
		(start 230.485 130.310532)
		(end 230.485 130.685)
		(width 0.19)
		(layer "F.Cu")
		(net 501)
	)
	(segment
		(start 221.652501 130.575)
		(end 221.717501 130.64)
		(width 0.19)
		(layer "F.Cu")
		(net 501)
	)
	(segment
		(start 220.468 130.575)
		(end 221.24 130.575)
		(width 0.19)
		(layer "F.Cu")
		(net 501)
	)
	(segment
		(start 222.785 130.64)
		(end 222.9 130.525)
		(width 0.19)
		(layer "F.Cu")
		(net 501)
	)
	(segment
		(start 215.07663 126.115)
		(end 219.60163 130.64)
		(width 0.19)
		(layer "F.Cu")
		(net 501)
	)
	(segment
		(start 230.430532 129.3475)
		(end 230.430532 130.035)
		(width 0.19)
		(layer "F.Cu")
		(net 501)
	)
	(segment
		(start 230.430532 130.035)
		(end 230.495532 130.1)
		(width 0.19)
		(layer "F.Cu")
		(net 501)
	)
	(segment
		(start 230.495532 130.1)
		(end 230.495532 130.3)
		(width 0.19)
		(layer "F.Cu")
		(net 501)
	)
	(segment
		(start 212.385 126.515)
		(end 212.785 126.115)
		(width 0.19)
		(layer "F.Cu")
		(net 501)
	)
	(segment
		(start 211.900401 126.501)
		(end 211.914401 126.515)
		(width 0.19)
		(layer "F.Cu")
		(net 501)
	)
	(segment
		(start 219.990499 130.64)
		(end 220.055499 130.575)
		(width 0.19)
		(layer "F.Cu")
		(net 501)
	)
	(segment
		(start 221.717501 130.64)
		(end 222.785 130.64)
		(width 0.19)
		(layer "F.Cu")
		(net 501)
	)
	(segment
		(start 220.055499 130.575)
		(end 220.468 130.575)
		(width 0.19)
		(layer "F.Cu")
		(net 501)
	)
	(segment
		(start 211.142 126.501)
		(end 211.900401 126.501)
		(width 0.19)
		(layer "F.Cu")
		(net 501)
	)
	(segment
		(start 230.495532 130.3)
		(end 230.485 130.310532)
		(width 0.19)
		(layer "F.Cu")
		(net 501)
	)
	(segment
		(start 219.60163 130.64)
		(end 219.990499 130.64)
		(width 0.19)
		(layer "F.Cu")
		(net 501)
	)
	(via
		(at 222.9 130.525)
		(size 0.45)
		(drill 0.1)
		(layers "F.Cu" "B.Cu")
		(net 501)
	)
	(via
		(at 230.37 130.8)
		(size 0.45)
		(drill 0.1)
		(layers "F.Cu" "B.Cu")
		(net 501)
	)
	(segment
		(start 227.72 132.5625)
		(end 225.956956 132.5625)
		(width 0.15)
		(layer "In7.Cu")
		(net 501)
	)
	(segment
		(start 230.37 130.8)
		(end 230.5325 130.9625)
		(width 0.15)
		(layer "In7.Cu")
		(net 501)
	)
	(segment
		(start 223.0625 130.6875)
		(end 222.9 130.525)
		(width 0.15)
		(layer "In7.Cu")
		(net 501)
	)
	(segment
		(start 229.216552 132.4225)
		(end 229.216552 132.354433)
		(width 0.15)
		(layer "In7.Cu")
		(net 501)
	)
	(segment
		(start 225.956956 132.5625)
		(end 224.081956 130.6875)
		(width 0.15)
		(layer "In7.Cu")
		(net 501)
	)
	(segment
		(start 228.866552 132.354433)
		(end 228.866552 132.4225)
		(width 0.15)
		(layer "In7.Cu")
		(net 501)
	)
	(segment
		(start 229.813044 132.5625)
		(end 229.356552 132.5625)
		(width 0.15)
		(layer "In7.Cu")
		(net 501)
	)
	(segment
		(start 229.076552 132.214433)
		(end 229.006552 132.214433)
		(width 0.15)
		(layer "In7.Cu")
		(net 501)
	)
	(segment
		(start 224.081956 130.6875)
		(end 223.0625 130.6875)
		(width 0.15)
		(layer "In7.Cu")
		(net 501)
	)
	(segment
		(start 230.5325 130.9625)
		(end 230.5325 131.843044)
		(width 0.15)
		(layer "In7.Cu")
		(net 501)
	)
	(segment
		(start 230.5325 131.843044)
		(end 229.813044 132.5625)
		(width 0.15)
		(layer "In7.Cu")
		(net 501)
	)
	(segment
		(start 228.656552 132.5625)
		(end 227.72 132.5625)
		(width 0.15)
		(layer "In7.Cu")
		(net 501)
	)
	(segment
		(start 228.726552 132.5625)
		(end 228.656552 132.5625)
		(width 0.15)
		(layer "In7.Cu")
		(net 501)
	)
	(arc
		(start 228.866552 132.4225)
		(mid 228.825547 132.521495)
		(end 228.726552 132.5625)
		(width 0.15)
		(layer "In7.Cu")
		(net 501)
	)
	(arc
		(start 229.356552 132.5625)
		(mid 229.257557 132.521495)
		(end 229.216552 132.4225)
		(width 0.15)
		(layer "In7.Cu")
		(net 501)
	)
	(arc
		(start 229.006552 132.214433)
		(mid 228.907557 132.255438)
		(end 228.866552 132.354433)
		(width 0.15)
		(layer "In7.Cu")
		(net 501)
	)
	(arc
		(start 229.216552 132.354433)
		(mid 229.175547 132.255438)
		(end 229.076552 132.214433)
		(width 0.15)
		(layer "In7.Cu")
		(net 501)
	)
	(segment
		(start 233.430532 129.3475)
		(end 233.430532 130.660532)
		(width 0.1)
		(layer "F.Cu")
		(net 502)
	)
	(segment
		(start 220.468 128.998)
		(end 221.24 128.998)
		(width 0.1)
		(layer "F.Cu")
		(net 502)
	)
	(segment
		(start 219.898 128.998)
		(end 219.7 128.8)
		(width 0.1)
		(layer "F.Cu")
		(net 502)
	)
	(segment
		(start 212.6 125.6)
		(end 211.9 125.6)
		(width 0.1)
		(layer "F.Cu")
		(net 502)
	)
	(segment
		(start 222.902 128.998)
		(end 223.1 128.8)
		(width 0.1)
		(layer "F.Cu")
		(net 502)
	)
	(segment
		(start 233.430532 130.660532)
		(end 233.47 130.7)
		(width 0.1)
		(layer "F.Cu")
		(net 502)
	)
	(segment
		(start 221.24 128.998)
		(end 222.902 128.998)
		(width 0.1)
		(layer "F.Cu")
		(net 502)
	)
	(segment
		(start 211.801 125.699)
		(end 211.142 125.699)
		(width 0.1)
		(layer "F.Cu")
		(net 502)
	)
	(segment
		(start 220.468 128.998)
		(end 219.898 128.998)
		(width 0.1)
		(layer "F.Cu")
		(net 502)
	)
	(segment
		(start 211.9 125.6)
		(end 211.801 125.699)
		(width 0.1)
		(layer "F.Cu")
		(net 502)
	)
	(segment
		(start 223.1 128.8)
		(end 223.1 128.4)
		(width 0.1)
		(layer "F.Cu")
		(net 502)
	)
	(via
		(at 233.47 130.7)
		(size 0.45)
		(drill 0.1)
		(layers "F.Cu" "B.Cu")
		(net 502)
	)
	(via
		(at 212.6 125.6)
		(size 0.45)
		(drill 0.1)
		(layers "F.Cu" "B.Cu")
		(net 502)
	)
	(via
		(at 219.7 128.8)
		(size 0.45)
		(drill 0.1)
		(layers "F.Cu" "B.Cu")
		(net 502)
	)
	(via
		(at 223.1 128.4)
		(size 0.45)
		(drill 0.1)
		(layers "F.Cu" "B.Cu")
		(net 502)
	)
	(segment
		(start 220.9 124.42)
		(end 220.9 128.2)
		(width 0.1)
		(layer "B.Cu")
		(net 502)
	)
	(segment
		(start 220.3 128.8)
		(end 219.7 128.8)
		(width 0.1)
		(layer "B.Cu")
		(net 502)
	)
	(segment
		(start 215.7 128.8)
		(end 212.6 125.7)
		(width 0.1)
		(layer "B.Cu")
		(net 502)
	)
	(segment
		(start 220.88 124.4)
		(end 220.9 124.42)
		(width 0.1)
		(layer "B.Cu")
		(net 502)
	)
	(segment
		(start 212.6 125.7)
		(end 212.6 125.6)
		(width 0.1)
		(layer "B.Cu")
		(net 502)
	)
	(segment
		(start 219.7 128.8)
		(end 215.7 128.8)
		(width 0.1)
		(layer "B.Cu")
		(net 502)
	)
	(segment
		(start 220.9 128.2)
		(end 220.3 128.8)
		(width 0.1)
		(layer "B.Cu")
		(net 502)
	)
	(segment
		(start 233.47 130)
		(end 232.87 129.4)
		(width 0.1)
		(layer "In5.Cu")
		(net 502)
	)
	(segment
		(start 233.47 130.7)
		(end 233.47 130)
		(width 0.1)
		(layer "In5.Cu")
		(net 502)
	)
	(segment
		(start 232.87 129.4)
		(end 226.6 129.4)
		(width 0.1)
		(layer "In5.Cu")
		(net 502)
	)
	(segment
		(start 226.2 129)
		(end 223.4 129)
		(width 0.1)
		(layer "In5.Cu")
		(net 502)
	)
	(segment
		(start 223.4 129)
		(end 223.1 128.7)
		(width 0.1)
		(layer "In5.Cu")
		(net 502)
	)
	(segment
		(start 223.1 128.7)
		(end 223.1 128.4)
		(width 0.1)
		(layer "In5.Cu")
		(net 502)
	)
	(segment
		(start 226.6 129.4)
		(end 226.2 129)
		(width 0.1)
		(layer "In5.Cu")
		(net 502)
	)
	(segment
		(start 212 126.1)
		(end 211.142 126.1)
		(width 0.1)
		(layer "F.Cu")
		(net 503)
	)
	(segment
		(start 231.930532 126.039468)
		(end 231.97 126)
		(width 0.1)
		(layer "F.Cu")
		(net 503)
	)
	(segment
		(start 212.1 126)
		(end 212 126.1)
		(width 0.1)
		(layer "F.Cu")
		(net 503)
	)
	(segment
		(start 223.8 129.1)
		(end 223.402 129.498)
		(width 0.1)
		(layer "F.Cu")
		(net 503)
	)
	(segment
		(start 231.930532 127.0725)
		(end 231.930532 126.039468)
		(width 0.1)
		(layer "F.Cu")
		(net 503)
	)
	(segment
		(start 231.97 126)
		(end 231.97 125.3)
		(width 0.1)
		(layer "F.Cu")
		(net 503)
	)
	(segment
		(start 220.468 129.498)
		(end 219.602 129.498)
		(width 0.1)
		(layer "F.Cu")
		(net 503)
	)
	(segment
		(start 221.24 129.498)
		(end 220.468 129.498)
		(width 0.1)
		(layer "F.Cu")
		(net 503)
	)
	(segment
		(start 223.8 128.5)
		(end 223.8 129.1)
		(width 0.1)
		(layer "F.Cu")
		(net 503)
	)
	(segment
		(start 223.402 129.498)
		(end 221.24 129.498)
		(width 0.1)
		(layer "F.Cu")
		(net 503)
	)
	(segment
		(start 219.602 129.498)
		(end 219.6 129.5)
		(width 0.1)
		(layer "F.Cu")
		(net 503)
	)
	(via
		(at 219.6 129.5)
		(size 0.45)
		(drill 0.1)
		(layers "F.Cu" "B.Cu")
		(net 503)
	)
	(via
		(at 212.1 126)
		(size 0.45)
		(drill 0.1)
		(layers "F.Cu" "B.Cu")
		(net 503)
	)
	(via
		(at 223.8 128.5)
		(size 0.45)
		(drill 0.1)
		(layers "F.Cu" "B.Cu")
		(net 503)
	)
	(via
		(at 231.97 125.3)
		(size 0.45)
		(drill 0.1)
		(layers "F.Cu" "B.Cu")
		(net 503)
	)
	(segment
		(start 221.5 128.6)
		(end 220.6 129.5)
		(width 0.1)
		(layer "B.Cu")
		(net 503)
	)
	(segment
		(start 224.04 125.26)
		(end 223.5 125.8)
		(width 0.1)
		(layer "B.Cu")
		(net 503)
	)
	(segment
		(start 222.5 125.8)
		(end 221.5 126.8)
		(width 0.1)
		(layer "B.Cu")
		(net 503)
	)
	(segment
		(start 214.5 129.5)
		(end 219.6 129.5)
		(width 0.1)
		(layer "B.Cu")
		(net 503)
	)
	(segment
		(start 212.1 127.1)
		(end 214.5 129.5)
		(width 0.1)
		(layer "B.Cu")
		(net 503)
	)
	(segment
		(start 223.5 125.8)
		(end 222.5 125.8)
		(width 0.1)
		(layer "B.Cu")
		(net 503)
	)
	(segment
		(start 221.5 126.8)
		(end 221.5 128.6)
		(width 0.1)
		(layer "B.Cu")
		(net 503)
	)
	(segment
		(start 220.6 129.5)
		(end 219.6 129.5)
		(width 0.1)
		(layer "B.Cu")
		(net 503)
	)
	(segment
		(start 212.1 126)
		(end 212.1 127.1)
		(width 0.1)
		(layer "B.Cu")
		(net 503)
	)
	(segment
		(start 224.04 124.4)
		(end 224.04 125.26)
		(width 0.1)
		(layer "B.Cu")
		(net 503)
	)
	(segment
		(start 231.37 127)
		(end 231.97 126.4)
		(width 0.1)
		(layer "In5.Cu")
		(net 503)
	)
	(segment
		(start 225.3 127)
		(end 231.37 127)
		(width 0.1)
		(layer "In5.Cu")
		(net 503)
	)
	(segment
		(start 223.8 128.5)
		(end 225.3 127)
		(width 0.1)
		(layer "In5.Cu")
		(net 503)
	)
	(segment
		(start 231.97 126.4)
		(end 231.97 125.3)
		(width 0.1)
		(layer "In5.Cu")
		(net 503)
	)
	(segment
		(start 211.914401 126.885)
		(end 212.515 126.885)
		(width 0.19)
		(layer "F.Cu")
		(net 504)
	)
	(segment
		(start 214.92337 126.485)
		(end 219.44837 131.01)
		(width 0.19)
		(layer "F.Cu")
		(net 504)
	)
	(segment
		(start 211.142 126.899)
		(end 211.900401 126.899)
		(width 0.19)
		(layer "F.Cu")
		(net 504)
	)
	(segment
		(start 219.990499 131.01)
		(end 220.055499 131.075)
		(width 0.19)
		(layer "F.Cu")
		(net 504)
	)
	(segment
		(start 219.44837 131.01)
		(end 219.990499 131.01)
		(width 0.19)
		(layer "F.Cu")
		(net 504)
	)
	(segment
		(start 230.865532 130.1)
		(end 230.865532 130.441592)
		(width 0.19)
		(layer "F.Cu")
		(net 504)
	)
	(segment
		(start 221.717501 131.01)
		(end 222.785 131.01)
		(width 0.19)
		(layer "F.Cu")
		(net 504)
	)
	(segment
		(start 221.24 131.075)
		(end 221.652501 131.075)
		(width 0.19)
		(layer "F.Cu")
		(net 504)
	)
	(segment
		(start 212.515 126.885)
		(end 212.915 126.485)
		(width 0.19)
		(layer "F.Cu")
		(net 504)
	)
	(segment
		(start 230.855 130.452124)
		(end 230.855 130.685)
		(width 0.19)
		(layer "F.Cu")
		(net 504)
	)
	(segment
		(start 211.900401 126.899)
		(end 211.914401 126.885)
		(width 0.19)
		(layer "F.Cu")
		(net 504)
	)
	(segment
		(start 230.930532 129.3475)
		(end 230.930532 130.035)
		(width 0.19)
		(layer "F.Cu")
		(net 504)
	)
	(segment
		(start 222.785 131.01)
		(end 222.9 131.125)
		(width 0.19)
		(layer "F.Cu")
		(net 504)
	)
	(segment
		(start 221.24 131.075)
		(end 220.468 131.075)
		(width 0.19)
		(layer "F.Cu")
		(net 504)
	)
	(segment
		(start 230.855 130.685)
		(end 230.97 130.8)
		(width 0.19)
		(layer "F.Cu")
		(net 504)
	)
	(segment
		(start 212.915 126.485)
		(end 214.92337 126.485)
		(width 0.19)
		(layer "F.Cu")
		(net 504)
	)
	(segment
		(start 221.652501 131.075)
		(end 221.717501 131.01)
		(width 0.19)
		(layer "F.Cu")
		(net 504)
	)
	(segment
		(start 230.865532 130.441592)
		(end 230.855 130.452124)
		(width 0.19)
		(layer "F.Cu")
		(net 504)
	)
	(segment
		(start 230.930532 130.035)
		(end 230.865532 130.1)
		(width 0.19)
		(layer "F.Cu")
		(net 504)
	)
	(segment
		(start 220.055499 131.075)
		(end 220.468 131.075)
		(width 0.19)
		(layer "F.Cu")
		(net 504)
	)
	(via
		(at 230.97 130.8)
		(size 0.45)
		(drill 0.1)
		(layers "F.Cu" "B.Cu")
		(net 504)
	)
	(via
		(at 222.9 131.125)
		(size 0.45)
		(drill 0.1)
		(layers "F.Cu" "B.Cu")
		(net 504)
	)
	(segment
		(start 223.968044 130.9625)
		(end 223.0625 130.9625)
		(width 0.15)
		(layer "In7.Cu")
		(net 504)
	)
	(segment
		(start 229.926956 132.8375)
		(end 225.843044 132.8375)
		(width 0.15)
		(layer "In7.Cu")
		(net 504)
	)
	(segment
		(start 223.0625 130.9625)
		(end 222.9 131.125)
		(width 0.15)
		(layer "In7.Cu")
		(net 504)
	)
	(segment
		(start 230.8075 130.9625)
		(end 230.8075 131.956956)
		(width 0.15)
		(layer "In7.Cu")
		(net 504)
	)
	(segment
		(start 225.843044 132.8375)
		(end 223.968044 130.9625)
		(width 0.15)
		(layer "In7.Cu")
		(net 504)
	)
	(segment
		(start 230.8075 131.956956)
		(end 229.926956 132.8375)
		(width 0.15)
		(layer "In7.Cu")
		(net 504)
	)
	(segment
		(start 230.97 130.8)
		(end 230.8075 130.9625)
		(width 0.15)
		(layer "In7.Cu")
		(net 504)
	)
	(segment
		(start 232.930532 130.360532)
		(end 232.97 130.4)
		(width 0.17)
		(layer "F.Cu")
		(net 505)
	)
	(segment
		(start 232.47 127.033032)
		(end 232.430532 127.0725)
		(width 0.17)
		(layer "F.Cu")
		(net 505)
	)
	(segment
		(start 221.652501 127.5)
		(end 221.727501 127.575)
		(width 0.17)
		(layer "F.Cu")
		(net 505)
	)
	(segment
		(start 212.975 129.775)
		(end 213.1 129.9)
		(width 0.17)
		(layer "F.Cu")
		(net 505)
	)
	(segment
		(start 220.468 127.5)
		(end 220.055499 127.5)
		(width 0.17)
		(layer "F.Cu")
		(net 505)
	)
	(segment
		(start 219.980499 127.575)
		(end 219.625 127.575)
		(width 0.17)
		(layer "F.Cu")
		(net 505)
	)
	(segment
		(start 232.47 125.9)
		(end 232.47 127.033032)
		(width 0.17)
		(layer "F.Cu")
		(net 505)
	)
	(segment
		(start 212.727512 129.775)
		(end 212.975 129.775)
		(width 0.17)
		(layer "F.Cu")
		(net 505)
	)
	(segment
		(start 211.142 128.9)
		(end 211.5456 128.9)
		(width 0.17)
		(layer "F.Cu")
		(net 505)
	)
	(segment
		(start 211.5456 128.9)
		(end 211.5706 128.875)
		(width 0.17)
		(layer "F.Cu")
		(net 505)
	)
	(segment
		(start 219.625 127.575)
		(end 219.5 127.45)
		(width 0.17)
		(layer "F.Cu")
		(net 505)
	)
	(segment
		(start 221.727501 127.575)
		(end 222.075 127.575)
		(width 0.17)
		(layer "F.Cu")
		(net 505)
	)
	(segment
		(start 221.24 127.5)
		(end 221.652501 127.5)
		(width 0.17)
		(layer "F.Cu")
		(net 505)
	)
	(segment
		(start 220.468 127.5)
		(end 221.24 127.5)
		(width 0.17)
		(layer "F.Cu")
		(net 505)
	)
	(segment
		(start 232.930532 129.3475)
		(end 232.930532 130.360532)
		(width 0.17)
		(layer "F.Cu")
		(net 505)
	)
	(segment
		(start 222.075 127.575)
		(end 222.2 127.45)
		(width 0.17)
		(layer "F.Cu")
		(net 505)
	)
	(segment
		(start 211.827512 128.875)
		(end 212.727512 129.775)
		(width 0.17)
		(layer "F.Cu")
		(net 505)
	)
	(segment
		(start 220.055499 127.5)
		(end 219.980499 127.575)
		(width 0.17)
		(layer "F.Cu")
		(net 505)
	)
	(segment
		(start 211.5706 128.875)
		(end 211.827512 128.875)
		(width 0.17)
		(layer "F.Cu")
		(net 505)
	)
	(via
		(at 222.2 127.45)
		(size 0.45)
		(drill 0.1)
		(layers "F.Cu" "B.Cu")
		(net 505)
	)
	(via
		(at 232.97 130.4)
		(size 0.45)
		(drill 0.1)
		(layers "F.Cu" "B.Cu")
		(net 505)
	)
	(via
		(at 213.1 129.9)
		(size 0.45)
		(drill 0.1)
		(layers "F.Cu" "B.Cu")
		(net 505)
	)
	(via
		(at 232.47 125.9)
		(size 0.45)
		(drill 0.1)
		(layers "F.Cu" "B.Cu")
		(net 505)
	)
	(via
		(at 219.5 127.45)
		(size 0.45)
		(drill 0.1)
		(layers "F.Cu" "B.Cu")
		(net 505)
	)
	(segment
		(start 232.47 127.9)
		(end 232.97 128.4)
		(width 0.17)
		(layer "B.Cu")
		(net 505)
	)
	(segment
		(start 232.47 127.9)
		(end 232.47 125.9)
		(width 0.17)
		(layer "B.Cu")
		(net 505)
	)
	(segment
		(start 232.97 130.4)
		(end 232.97 128.4)
		(width 0.17)
		(layer "B.Cu")
		(net 505)
	)
	(segment
		(start 212.0875 129.2466)
		(end 212.0875 128.3534)
		(width 0.125)
		(layer "In7.Cu")
		(net 505)
	)
	(segment
		(start 225.3875 124.5534)
		(end 225.3875 125.8534)
		(width 0.125)
		(layer "In7.Cu")
		(net 505)
	)
	(segment
		(start 232.47 125.9)
		(end 232.657499 126.087499)
		(width 0.125)
		(layer "In7.Cu")
		(net 505)
	)
	(segment
		(start 212.0875 128.3534)
		(end 212.803401 127.637499)
		(width 0.125)
		(layer "In7.Cu")
		(net 505)
	)
	(segment
		(start 213.1 129.9)
		(end 212.912501 129.712501)
		(width 0.125)
		(layer "In7.Cu")
		(net 505)
	)
	(segment
		(start 219.312501 127.637499)
		(end 219.5 127.45)
		(width 0.125)
		(layer "In7.Cu")
		(net 505)
	)
	(segment
		(start 212.553401 129.712501)
		(end 212.0875 129.2466)
		(width 0.125)
		(layer "In7.Cu")
		(net 505)
	)
	(segment
		(start 233.0234 126.8125)
		(end 233.8166 126.8125)
		(width 0.125)
		(layer "In7.Cu")
		(net 505)
	)
	(segment
		(start 233.8166 126.8125)
		(end 234.1825 126.4466)
		(width 0.125)
		(layer "In7.Cu")
		(net 505)
	)
	(segment
		(start 225.3875 125.8534)
		(end 223.603401 127.637499)
		(width 0.125)
		(layer "In7.Cu")
		(net 505)
	)
	(segment
		(start 232.657499 126.087499)
		(end 232.657499 126.446599)
		(width 0.125)
		(layer "In7.Cu")
		(net 505)
	)
	(segment
		(start 212.912501 129.712501)
		(end 212.553401 129.712501)
		(width 0.125)
		(layer "In7.Cu")
		(net 505)
	)
	(segment
		(start 233.0166 123.2875)
		(end 226.6534 123.2875)
		(width 0.125)
		(layer "In7.Cu")
		(net 505)
	)
	(segment
		(start 223.603401 127.637499)
		(end 222.387499 127.637499)
		(width 0.125)
		(layer "In7.Cu")
		(net 505)
	)
	(segment
		(start 226.6534 123.2875)
		(end 225.3875 124.5534)
		(width 0.125)
		(layer "In7.Cu")
		(net 505)
	)
	(segment
		(start 234.1825 124.4534)
		(end 233.0166 123.2875)
		(width 0.125)
		(layer "In7.Cu")
		(net 505)
	)
	(segment
		(start 212.803401 127.637499)
		(end 219.312501 127.637499)
		(width 0.125)
		(layer "In7.Cu")
		(net 505)
	)
	(segment
		(start 234.1825 126.4466)
		(end 234.1825 124.4534)
		(width 0.125)
		(layer "In7.Cu")
		(net 505)
	)
	(segment
		(start 222.387499 127.637499)
		(end 222.2 127.45)
		(width 0.125)
		(layer "In7.Cu")
		(net 505)
	)
	(segment
		(start 232.657499 126.446599)
		(end 233.0234 126.8125)
		(width 0.125)
		(layer "In7.Cu")
		(net 505)
	)
	(segment
		(start 210.335356 117.512132)
		(end 210.512132 117.512132)
		(width 0.17)
		(layer "F.Cu")
		(net 506)
	)
	(segment
		(start 232.430532 114.0725)
		(end 232.430532 112.960532)
		(width 0.17)
		(layer "F.Cu")
		(net 506)
	)
	(segment
		(start 208.954 119.152599)
		(end 208.929 119.127599)
		(width 0.17)
		(layer "F.Cu")
		(net 506)
	)
	(segment
		(start 208.929 118.918488)
		(end 210.335356 117.512132)
		(width 0.17)
		(layer "F.Cu")
		(net 506)
	)
	(segment
		(start 216.681636 114.213693)
		(end 216.681636 114.152)
		(width 0.17)
		(layer "F.Cu")
		(net 506)
	)
	(segment
		(start 221.686501 113.952)
		(end 223.175 113.952)
		(width 0.17)
		(layer "F.Cu")
		(net 506)
	)
	(segment
		(start 208.929 119.127599)
		(end 208.929 118.918488)
		(width 0.17)
		(layer "F.Cu")
		(net 506)
	)
	(segment
		(start 220.014499 114.027)
		(end 220.427 114.027)
		(width 0.17)
		(layer "F.Cu")
		(net 506)
	)
	(segment
		(start 216.381636 114.413693)
		(end 216.481636 114.413693)
		(width 0.17)
		(layer "F.Cu")
		(net 506)
	)
	(segment
		(start 216.181636 114.152)
		(end 216.181636 114.213693)
		(width 0.17)
		(layer "F.Cu")
		(net 506)
	)
	(segment
		(start 223.175 113.952)
		(end 223.3 114.077)
		(width 0.17)
		(layer "F.Cu")
		(net 506)
	)
	(segment
		(start 221.611501 114.027)
		(end 221.686501 113.952)
		(width 0.17)
		(layer "F.Cu")
		(net 506)
	)
	(segment
		(start 232.930532 117.460532)
		(end 232.97 117.5)
		(width 0.17)
		(layer "F.Cu")
		(net 506)
	)
	(segment
		(start 208.954 119.911)
		(end 208.954 119.152599)
		(width 0.17)
		(layer "F.Cu")
		(net 506)
	)
	(segment
		(start 214.825 113.952)
		(end 215.981636 113.952)
		(width 0.17)
		(layer "F.Cu")
		(net 506)
	)
	(segment
		(start 218.386527 113.952)
		(end 219.939499 113.952)
		(width 0.17)
		(layer "F.Cu")
		(net 506)
	)
	(segment
		(start 221.199 114.027)
		(end 221.611501 114.027)
		(width 0.17)
		(layer "F.Cu")
		(net 506)
	)
	(segment
		(start 232.930532 116.3475)
		(end 232.930532 117.460532)
		(width 0.17)
		(layer "F.Cu")
		(net 506)
	)
	(segment
		(start 219.939499 113.952)
		(end 220.014499 114.027)
		(width 0.17)
		(layer "F.Cu")
		(net 506)
	)
	(segment
		(start 216.981636 113.952)
		(end 218.386527 113.952)
		(width 0.17)
		(layer "F.Cu")
		(net 506)
	)
	(segment
		(start 220.427 114.027)
		(end 221.199 114.027)
		(width 0.17)
		(layer "F.Cu")
		(net 506)
	)
	(segment
		(start 232.430532 112.960532)
		(end 232.37 112.9)
		(width 0.17)
		(layer "F.Cu")
		(net 506)
	)
	(segment
		(start 214.7 114.077)
		(end 214.825 113.952)
		(width 0.17)
		(layer "F.Cu")
		(net 506)
	)
	(segment
		(start 216.881636 113.952)
		(end 216.981636 113.952)
		(width 0.17)
		(layer "F.Cu")
		(net 506)
	)
	(via
		(at 232.97 117.5)
		(size 0.45)
		(drill 0.1)
		(layers "F.Cu" "B.Cu")
		(net 506)
	)
	(via
		(at 232.37 112.9)
		(size 0.45)
		(drill 0.1)
		(layers "F.Cu" "B.Cu")
		(net 506)
	)
	(via
		(at 223.3 114.077)
		(size 0.45)
		(drill 0.1)
		(layers "F.Cu" "B.Cu")
		(net 506)
	)
	(via
		(at 210.512132 117.512132)
		(size 0.45)
		(drill 0.1)
		(layers "F.Cu" "B.Cu")
		(net 506)
	)
	(via
		(at 214.7 114.077)
		(size 0.45)
		(drill 0.1)
		(layers "F.Cu" "B.Cu")
		(net 506)
	)
	(arc
		(start 216.681636 114.152)
		(mid 216.740215 114.010579)
		(end 216.881636 113.952)
		(width 0.17)
		(layer "F.Cu")
		(net 506)
	)
	(arc
		(start 215.981636 113.952)
		(mid 216.123057 114.010579)
		(end 216.181636 114.152)
		(width 0.17)
		(layer "F.Cu")
		(net 506)
	)
	(arc
		(start 216.181636 114.213693)
		(mid 216.240215 114.355114)
		(end 216.381636 114.413693)
		(width 0.17)
		(layer "F.Cu")
		(net 506)
	)
	(arc
		(start 216.481636 114.413693)
		(mid 216.623057 114.355114)
		(end 216.681636 114.213693)
		(width 0.17)
		(layer "F.Cu")
		(net 506)
	)
	(segment
		(start 213.895488 113.952)
		(end 210.512132 117.335356)
		(width 0.17)
		(layer "B.Cu")
		(net 506)
	)
	(segment
		(start 210.512132 117.335356)
		(end 210.512132 117.512132)
		(width 0.17)
		(layer "B.Cu")
		(net 506)
	)
	(segment
		(start 214.7 114.077)
		(end 214.575 113.952)
		(width 0.17)
		(layer "B.Cu")
		(net 506)
	)
	(segment
		(start 214.575 113.952)
		(end 213.895488 113.952)
		(width 0.17)
		(layer "B.Cu")
		(net 506)
	)
	(segment
		(start 232.37 114.9)
		(end 232.37 112.9)
		(width 0.125)
		(layer "In2.Cu")
		(net 506)
	)
	(segment
		(start 232.97 117.5)
		(end 232.97 115.5)
		(width 0.125)
		(layer "In2.Cu")
		(net 506)
	)
	(segment
		(start 232.97 115.5)
		(end 232.37 114.9)
		(width 0.125)
		(layer "In2.Cu")
		(net 506)
	)
	(segment
		(start 233.6666 114.2625)
		(end 224.6834 114.2625)
		(width 0.125)
		(layer "In7.Cu")
		(net 506)
	)
	(segment
		(start 224.6834 114.2625)
		(end 224.310401 113.889501)
		(width 0.125)
		(layer "In7.Cu")
		(net 506)
	)
	(segment
		(start 232.9234 111.7875)
		(end 234.0166 111.7875)
		(width 0.125)
		(layer "In7.Cu")
		(net 506)
	)
	(segment
		(start 234.0166 111.7875)
		(end 234.6825 112.4534)
		(width 0.125)
		(layer "In7.Cu")
		(net 506)
	)
	(segment
		(start 232.557499 112.153401)
		(end 232.9234 111.7875)
		(width 0.125)
		(layer "In7.Cu")
		(net 506)
	)
	(segment
		(start 234.6825 112.4534)
		(end 234.6825 113.2466)
		(width 0.125)
		(layer "In7.Cu")
		(net 506)
	)
	(segment
		(start 232.557499 112.712501)
		(end 232.557499 112.153401)
		(width 0.125)
		(layer "In7.Cu")
		(net 506)
	)
	(segment
		(start 234.6825 113.2466)
		(end 233.6666 114.2625)
		(width 0.125)
		(layer "In7.Cu")
		(net 506)
	)
	(segment
		(start 224.310401 113.889501)
		(end 223.487499 113.889501)
		(width 0.125)
		(layer "In7.Cu")
		(net 506)
	)
	(segment
		(start 223.487499 113.889501)
		(end 223.3 114.077)
		(width 0.125)
		(layer "In7.Cu")
		(net 506)
	)
	(segment
		(start 232.37 112.9)
		(end 232.557499 112.712501)
		(width 0.125)
		(layer "In7.Cu")
		(net 506)
	)
	(segment
		(start 206.365 118.67663)
		(end 206.365 115.97337)
		(width 0.19)
		(layer "F.Cu")
		(net 507)
	)
	(segment
		(start 222.685 116.692)
		(end 222.8 116.577)
		(width 0.19)
		(layer "F.Cu")
		(net 507)
	)
	(segment
		(start 230.495532 117.685)
		(end 230.380532 117.8)
		(width 0.19)
		(layer "F.Cu")
		(net 507)
	)
	(segment
		(start 215.15363 116.692)
		(end 219.952499 116.692)
		(width 0.19)
		(layer "F.Cu")
		(net 507)
	)
	(segment
		(start 220.43 116.627)
		(end 221.202 116.627)
		(width 0.19)
		(layer "F.Cu")
		(net 507)
	)
	(segment
		(start 221.202 116.627)
		(end 221.614501 116.627)
		(width 0.19)
		(layer "F.Cu")
		(net 507)
	)
	(segment
		(start 212.27663 113.815)
		(end 215.15363 116.692)
		(width 0.19)
		(layer "F.Cu")
		(net 507)
	)
	(segment
		(start 230.495532 117.1)
		(end 230.495532 117.685)
		(width 0.19)
		(layer "F.Cu")
		(net 507)
	)
	(segment
		(start 220.017499 116.627)
		(end 220.43 116.627)
		(width 0.19)
		(layer "F.Cu")
		(net 507)
	)
	(segment
		(start 221.614501 116.627)
		(end 221.679501 116.692)
		(width 0.19)
		(layer "F.Cu")
		(net 507)
	)
	(segment
		(start 206.634 119.25)
		(end 206.634 118.94563)
		(width 0.19)
		(layer "F.Cu")
		(net 507)
	)
	(segment
		(start 221.679501 116.692)
		(end 222.685 116.692)
		(width 0.19)
		(layer "F.Cu")
		(net 507)
	)
	(segment
		(start 230.430532 117.035)
		(end 230.495532 117.1)
		(width 0.19)
		(layer "F.Cu")
		(net 507)
	)
	(segment
		(start 206.553 119.911)
		(end 206.553 119.331)
		(width 0.19)
		(layer "F.Cu")
		(net 507)
	)
	(segment
		(start 219.952499 116.692)
		(end 220.017499 116.627)
		(width 0.19)
		(layer "F.Cu")
		(net 507)
	)
	(segment
		(start 206.365 115.97337)
		(end 208.52337 113.815)
		(width 0.19)
		(layer "F.Cu")
		(net 507)
	)
	(segment
		(start 206.634 118.94563)
		(end 206.365 118.67663)
		(width 0.19)
		(layer "F.Cu")
		(net 507)
	)
	(segment
		(start 206.553 119.331)
		(end 206.634 119.25)
		(width 0.19)
		(layer "F.Cu")
		(net 507)
	)
	(segment
		(start 230.430532 116.3475)
		(end 230.430532 117.035)
		(width 0.19)
		(layer "F.Cu")
		(net 507)
	)
	(segment
		(start 208.52337 113.815)
		(end 212.27663 113.815)
		(width 0.19)
		(layer "F.Cu")
		(net 507)
	)
	(via
		(at 230.380532 117.8)
		(size 0.45)
		(drill 0.1)
		(layers "F.Cu" "B.Cu")
		(net 507)
	)
	(via
		(at 222.8 116.577)
		(size 0.45)
		(drill 0.1)
		(layers "F.Cu" "B.Cu")
		(net 507)
	)
	(segment
		(start 230.543032 117.9625)
		(end 230.380532 117.8)
		(width 0.15)
		(layer "In7.Cu")
		(net 507)
	)
	(segment
		(start 229.713044 119.6625)
		(end 230.543032 118.832512)
		(width 0.15)
		(layer "In7.Cu")
		(net 507)
	)
	(segment
		(start 224.890608 116.926447)
		(end 224.954819 116.862233)
		(width 0.15)
		(layer "In7.Cu")
		(net 507)
	)
	(segment
		(start 222.8 116.577)
		(end 222.9625 116.7395)
		(width 0.15)
		(layer "In7.Cu")
		(net 507)
	)
	(segment
		(start 225.5375 118.5)
		(end 225.5375 118.743044)
		(width 0.15)
		(layer "In7.Cu")
		(net 507)
	)
	(segment
		(start 222.9625 116.7395)
		(end 224.533956 116.7395)
		(width 0.15)
		(layer "In7.Cu")
		(net 507)
	)
	(segment
		(start 225.5375 117.743044)
		(end 225.5375 118.5)
		(width 0.15)
		(layer "In7.Cu")
		(net 507)
	)
	(segment
		(start 225.102738 117.308283)
		(end 225.145166 117.35071)
		(width 0.15)
		(layer "In7.Cu")
		(net 507)
	)
	(segment
		(start 225.145166 117.35071)
		(end 225.5375 117.743044)
		(width 0.15)
		(layer "In7.Cu")
		(net 507)
	)
	(segment
		(start 225.166951 117.074366)
		(end 225.102737 117.138577)
		(width 0.15)
		(layer "In7.Cu")
		(net 507)
	)
	(segment
		(start 224.533956 116.7395)
		(end 224.720902 116.926446)
		(width 0.15)
		(layer "In7.Cu")
		(net 507)
	)
	(segment
		(start 225.124525 116.862234)
		(end 225.166951 116.90466)
		(width 0.15)
		(layer "In7.Cu")
		(net 507)
	)
	(segment
		(start 230.543032 118.832512)
		(end 230.543032 117.9625)
		(width 0.15)
		(layer "In7.Cu")
		(net 507)
	)
	(segment
		(start 226.456956 119.6625)
		(end 229.713044 119.6625)
		(width 0.15)
		(layer "In7.Cu")
		(net 507)
	)
	(segment
		(start 225.5375 118.743044)
		(end 226.456956 119.6625)
		(width 0.15)
		(layer "In7.Cu")
		(net 507)
	)
	(arc
		(start 224.954819 116.862233)
		(mid 225.039672 116.827087)
		(end 225.124525 116.862234)
		(width 0.15)
		(layer "In7.Cu")
		(net 507)
	)
	(arc
		(start 225.102737 117.138577)
		(mid 225.067591 117.22343)
		(end 225.102738 117.308283)
		(width 0.15)
		(layer "In7.Cu")
		(net 507)
	)
	(arc
		(start 225.166951 116.90466)
		(mid 225.202098 116.989513)
		(end 225.166951 117.074366)
		(width 0.15)
		(layer "In7.Cu")
		(net 507)
	)
	(arc
		(start 224.720902 116.926446)
		(mid 224.805755 116.961593)
		(end 224.890608 116.926447)
		(width 0.15)
		(layer "In7.Cu")
		(net 507)
	)
	(segment
		(start 232.930532 112.939468)
		(end 232.97 112.9)
		(width 0.17)
		(layer "F.Cu")
		(net 508)
	)
	(segment
		(start 221.199 113.527)
		(end 221.611501 113.527)
		(width 0.17)
		(layer "F.Cu")
		(net 508)
	)
	(segment
		(start 223.175 113.602)
		(end 223.3 113.477)
		(width 0.17)
		(layer "F.Cu")
		(net 508)
	)
	(segment
		(start 208.579 119.127599)
		(end 208.579 118.773512)
		(width 0.17)
		(layer "F.Cu")
		(net 508)
	)
	(segment
		(start 219.939499 113.602)
		(end 214.825 113.602)
		(width 0.17)
		(layer "F.Cu")
		(net 508)
	)
	(segment
		(start 208.579 118.773512)
		(end 210.087868 117.264644)
		(width 0.17)
		(layer "F.Cu")
		(net 508)
	)
	(segment
		(start 210.087868 117.264644)
		(end 210.087868 117.087868)
		(width 0.17)
		(layer "F.Cu")
		(net 508)
	)
	(segment
		(start 232.430532 116.3475)
		(end 232.430532 115.539468)
		(width 0.17)
		(layer "F.Cu")
		(net 508)
	)
	(segment
		(start 220.427 113.527)
		(end 220.014499 113.527)
		(width 0.17)
		(layer "F.Cu")
		(net 508)
	)
	(segment
		(start 208.554 119.911)
		(end 208.554 119.152599)
		(width 0.17)
		(layer "F.Cu")
		(net 508)
	)
	(segment
		(start 232.930532 115.039468)
		(end 232.930532 114.0725)
		(width 0.17)
		(layer "F.Cu")
		(net 508)
	)
	(segment
		(start 232.430532 115.539468)
		(end 232.930532 115.039468)
		(width 0.17)
		(layer "F.Cu")
		(net 508)
	)
	(segment
		(start 232.930532 114.0725)
		(end 232.930532 112.939468)
		(width 0.17)
		(layer "F.Cu")
		(net 508)
	)
	(segment
		(start 221.686501 113.602)
		(end 223.175 113.602)
		(width 0.17)
		(layer "F.Cu")
		(net 508)
	)
	(segment
		(start 221.611501 113.527)
		(end 221.686501 113.602)
		(width 0.17)
		(layer "F.Cu")
		(net 508)
	)
	(segment
		(start 208.554 119.152599)
		(end 208.579 119.127599)
		(width 0.17)
		(layer "F.Cu")
		(net 508)
	)
	(segment
		(start 220.427 113.527)
		(end 221.199 113.527)
		(width 0.17)
		(layer "F.Cu")
		(net 508)
	)
	(segment
		(start 214.825 113.602)
		(end 214.7 113.477)
		(width 0.17)
		(layer "F.Cu")
		(net 508)
	)
	(segment
		(start 220.014499 113.527)
		(end 219.939499 113.602)
		(width 0.17)
		(layer "F.Cu")
		(net 508)
	)
	(via
		(at 210.087868 117.087868)
		(size 0.45)
		(drill 0.1)
		(layers "F.Cu" "B.Cu")
		(net 508)
	)
	(via
		(at 232.97 112.9)
		(size 0.45)
		(drill 0.1)
		(layers "F.Cu" "B.Cu")
		(net 508)
	)
	(via
		(at 214.7 113.477)
		(size 0.45)
		(drill 0.1)
		(layers "F.Cu" "B.Cu")
		(net 508)
	)
	(via
		(at 223.3 113.477)
		(size 0.45)
		(drill 0.1)
		(layers "F.Cu" "B.Cu")
		(net 508)
	)
	(segment
		(start 214.7 113.477)
		(end 214.575 113.602)
		(width 0.17)
		(layer "B.Cu")
		(net 508)
	)
	(segment
		(start 214.575 113.602)
		(end 213.750512 113.602)
		(width 0.17)
		(layer "B.Cu")
		(net 508)
	)
	(segment
		(start 210.264644 117.087868)
		(end 210.087868 117.087868)
		(width 0.17)
		(layer "B.Cu")
		(net 508)
	)
	(segment
		(start 213.750512 113.602)
		(end 210.264644 117.087868)
		(width 0.17)
		(layer "B.Cu")
		(net 508)
	)
	(segment
		(start 224.7766 114.0375)
		(end 224.403599 113.664499)
		(width 0.125)
		(layer "In7.Cu")
		(net 508)
	)
	(segment
		(start 231.540289 113.8775)
		(end 231.540289 113.713468)
		(width 0.125)
		(layer "In7.Cu")
		(net 508)
	)
	(segment
		(start 232.782501 112.246599)
		(end 233.0166 112.0125)
		(width 0.125)
		(layer "In7.Cu")
		(net 508)
	)
	(segment
		(start 234.4575 113.1534)
		(end 233.5734 114.0375)
		(width 0.125)
		(layer "In7.Cu")
		(net 508)
	)
	(segment
		(start 233.140289 113.8775)
		(end 233.140289 113.713468)
		(width 0.125)
		(layer "In7.Cu")
		(net 508)
	)
	(segment
		(start 230.180289 114.0375)
		(end 230.100289 114.0375)
		(width 0.125)
		(layer "In7.Cu")
		(net 508)
	)
	(segment
		(start 232.980289 113.553468)
		(end 232.900289 113.553468)
		(width 0.125)
		(layer "In7.Cu")
		(net 508)
	)
	(segment
		(start 229.380289 114.0375)
		(end 229.300289 114.0375)
		(width 0.125)
		(layer "In7.Cu")
		(net 508)
	)
	(segment
		(start 234.4575 112.5466)
		(end 234.4575 113.1534)
		(width 0.125)
		(layer "In7.Cu")
		(net 508)
	)
	(segment
		(start 230.980289 114.0375)
		(end 230.900289 114.0375)
		(width 0.125)
		(layer "In7.Cu")
		(net 508)
	)
	(segment
		(start 231.140289 113.713468)
		(end 231.140289 113.8775)
		(width 0.125)
		(layer "In7.Cu")
		(net 508)
	)
	(segment
		(start 232.740289 113.713468)
		(end 232.740289 113.8775)
		(width 0.125)
		(layer "In7.Cu")
		(net 508)
	)
	(segment
		(start 232.340289 113.8775)
		(end 232.340289 113.713468)
		(width 0.125)
		(layer "In7.Cu")
		(net 508)
	)
	(segment
		(start 233.9234 112.0125)
		(end 234.4575 112.5466)
		(width 0.125)
		(layer "In7.Cu")
		(net 508)
	)
	(segment
		(start 232.782501 112.712501)
		(end 232.782501 112.246599)
		(width 0.125)
		(layer "In7.Cu")
		(net 508)
	)
	(segment
		(start 231.380289 113.553468)
		(end 231.300289 113.553468)
		(width 0.125)
		(layer "In7.Cu")
		(net 508)
	)
	(segment
		(start 232.580289 114.0375)
		(end 232.500289 114.0375)
		(width 0.125)
		(layer "In7.Cu")
		(net 508)
	)
	(segment
		(start 229.540289 113.71345)
		(end 229.540289 113.8775)
		(width 0.125)
		(layer "In7.Cu")
		(net 508)
	)
	(segment
		(start 233.0166 112.0125)
		(end 233.9234 112.0125)
		(width 0.125)
		(layer "In7.Cu")
		(net 508)
	)
	(segment
		(start 223.487499 113.664499)
		(end 223.3 113.477)
		(width 0.125)
		(layer "In7.Cu")
		(net 508)
	)
	(segment
		(start 229.780289 113.55345)
		(end 229.700289 113.55345)
		(width 0.125)
		(layer "In7.Cu")
		(net 508)
	)
	(segment
		(start 230.740289 113.8775)
		(end 230.740289 113.713468)
		(width 0.125)
		(layer "In7.Cu")
		(net 508)
	)
	(segment
		(start 230.580289 113.553468)
		(end 230.500289 113.553468)
		(width 0.125)
		(layer "In7.Cu")
		(net 508)
	)
	(segment
		(start 233.5734 114.0375)
		(end 233.300289 114.0375)
		(width 0.125)
		(layer "In7.Cu")
		(net 508)
	)
	(segment
		(start 231.780289 114.0375)
		(end 231.700289 114.0375)
		(width 0.125)
		(layer "In7.Cu")
		(net 508)
	)
	(segment
		(start 224.403599 113.664499)
		(end 223.487499 113.664499)
		(width 0.125)
		(layer "In7.Cu")
		(net 508)
	)
	(segment
		(start 232.180289 113.553468)
		(end 232.100289 113.553468)
		(width 0.125)
		(layer "In7.Cu")
		(net 508)
	)
	(segment
		(start 229.940289 113.8775)
		(end 229.940289 113.71345)
		(width 0.125)
		(layer "In7.Cu")
		(net 508)
	)
	(segment
		(start 232.97 112.9)
		(end 232.782501 112.712501)
		(width 0.125)
		(layer "In7.Cu")
		(net 508)
	)
	(segment
		(start 231.940289 113.713468)
		(end 231.940289 113.8775)
		(width 0.125)
		(layer "In7.Cu")
		(net 508)
	)
	(segment
		(start 229.300289 114.0375)
		(end 228.242799 114.0375)
		(width 0.125)
		(layer "In7.Cu")
		(net 508)
	)
	(segment
		(start 228.242799 114.0375)
		(end 224.7766 114.0375)
		(width 0.125)
		(layer "In7.Cu")
		(net 508)
	)
	(segment
		(start 230.340289 113.713468)
		(end 230.340289 113.8775)
		(width 0.125)
		(layer "In7.Cu")
		(net 508)
	)
	(arc
		(start 231.540289 113.713468)
		(mid 231.493426 113.600331)
		(end 231.380289 113.553468)
		(width 0.125)
		(layer "In7.Cu")
		(net 508)
	)
	(arc
		(start 229.940289 113.71345)
		(mid 229.893426 113.600313)
		(end 229.780289 113.55345)
		(width 0.125)
		(layer "In7.Cu")
		(net 508)
	)
	(arc
		(start 232.100289 113.553468)
		(mid 231.987152 113.600331)
		(end 231.940289 113.713468)
		(width 0.125)
		(layer "In7.Cu")
		(net 508)
	)
	(arc
		(start 230.340289 113.8775)
		(mid 230.293426 113.990637)
		(end 230.180289 114.0375)
		(width 0.125)
		(layer "In7.Cu")
		(net 508)
	)
	(arc
		(start 233.300289 114.0375)
		(mid 233.187152 113.990637)
		(end 233.140289 113.8775)
		(width 0.125)
		(layer "In7.Cu")
		(net 508)
	)
	(arc
		(start 232.340289 113.713468)
		(mid 232.293426 113.600331)
		(end 232.180289 113.553468)
		(width 0.125)
		(layer "In7.Cu")
		(net 508)
	)
	(arc
		(start 230.500289 113.553468)
		(mid 230.387152 113.600331)
		(end 230.340289 113.713468)
		(width 0.125)
		(layer "In7.Cu")
		(net 508)
	)
	(arc
		(start 230.900289 114.0375)
		(mid 230.787152 113.990637)
		(end 230.740289 113.8775)
		(width 0.125)
		(layer "In7.Cu")
		(net 508)
	)
	(arc
		(start 232.740289 113.8775)
		(mid 232.693426 113.990637)
		(end 232.580289 114.0375)
		(width 0.125)
		(layer "In7.Cu")
		(net 508)
	)
	(arc
		(start 230.740289 113.713468)
		(mid 230.693426 113.600331)
		(end 230.580289 113.553468)
		(width 0.125)
		(layer "In7.Cu")
		(net 508)
	)
	(arc
		(start 229.540289 113.8775)
		(mid 229.493426 113.990637)
		(end 229.380289 114.0375)
		(width 0.125)
		(layer "In7.Cu")
		(net 508)
	)
	(arc
		(start 232.500289 114.0375)
		(mid 232.387152 113.990637)
		(end 232.340289 113.8775)
		(width 0.125)
		(layer "In7.Cu")
		(net 508)
	)
	(arc
		(start 231.140289 113.8775)
		(mid 231.093426 113.990637)
		(end 230.980289 114.0375)
		(width 0.125)
		(layer "In7.Cu")
		(net 508)
	)
	(arc
		(start 232.900289 113.553468)
		(mid 232.787152 113.600331)
		(end 232.740289 113.713468)
		(width 0.125)
		(layer "In7.Cu")
		(net 508)
	)
	(arc
		(start 233.140289 113.713468)
		(mid 233.093426 113.600331)
		(end 232.980289 113.553468)
		(width 0.125)
		(layer "In7.Cu")
		(net 508)
	)
	(arc
		(start 229.700289 113.55345)
		(mid 229.587152 113.600313)
		(end 229.540289 113.71345)
		(width 0.125)
		(layer "In7.Cu")
		(net 508)
	)
	(arc
		(start 231.940289 113.8775)
		(mid 231.893426 113.990637)
		(end 231.780289 114.0375)
		(width 0.125)
		(layer "In7.Cu")
		(net 508)
	)
	(arc
		(start 230.100289 114.0375)
		(mid 229.987152 113.990637)
		(end 229.940289 113.8775)
		(width 0.125)
		(layer "In7.Cu")
		(net 508)
	)
	(arc
		(start 231.700289 114.0375)
		(mid 231.587152 113.990637)
		(end 231.540289 113.8775)
		(width 0.125)
		(layer "In7.Cu")
		(net 508)
	)
	(arc
		(start 231.300289 113.553468)
		(mid 231.187152 113.600331)
		(end 231.140289 113.713468)
		(width 0.125)
		(layer "In7.Cu")
		(net 508)
	)
	(segment
		(start 218.025 115.025)
		(end 218 115)
		(width 0.1)
		(layer "F.Cu")
		(net 509)
	)
	(segment
		(start 232.97 118.6)
		(end 229.97 118.6)
		(width 0.1)
		(layer "F.Cu")
		(net 509)
	)
	(segment
		(start 232.97 118.6)
		(end 233.430532 118.139468)
		(width 0.1)
		(layer "F.Cu")
		(net 509)
	)
	(segment
		(start 222.575 115.025)
		(end 222.6 115)
		(width 0.1)
		(layer "F.Cu")
		(net 509)
	)
	(segment
		(start 209.353 119.247)
		(end 209.353 119.911)
		(width 0.1)
		(layer "F.Cu")
		(net 509)
	)
	(segment
		(start 220.427 115.025)
		(end 218.025 115.025)
		(width 0.1)
		(layer "F.Cu")
		(net 509)
	)
	(segment
		(start 209.4 119.2)
		(end 209.353 119.247)
		(width 0.1)
		(layer "F.Cu")
		(net 509)
	)
	(segment
		(start 209.4 119.1)
		(end 209.4 119.2)
		(width 0.1)
		(layer "F.Cu")
		(net 509)
	)
	(segment
		(start 221.199 115.025)
		(end 220.427 115.025)
		(width 0.1)
		(layer "F.Cu")
		(net 509)
	)
	(segment
		(start 221.199 115.025)
		(end 222.575 115.025)
		(width 0.1)
		(layer "F.Cu")
		(net 509)
	)
	(segment
		(start 233.430532 116.3475)
		(end 233.430532 118.139468)
		(width 0.1)
		(layer "F.Cu")
		(net 509)
	)
	(via
		(at 209.4 119.1)
		(size 0.45)
		(drill 0.1)
		(layers "F.Cu" "B.Cu")
		(net 509)
	)
	(via
		(at 229.97 118.6)
		(size 0.45)
		(drill 0.1)
		(layers "F.Cu" "B.Cu")
		(net 509)
	)
	(via
		(at 222.6 115)
		(size 0.45)
		(drill 0.1)
		(layers "F.Cu" "B.Cu")
		(net 509)
	)
	(via
		(at 218 115)
		(size 0.45)
		(drill 0.1)
		(layers "F.Cu" "B.Cu")
		(net 509)
	)
	(segment
		(start 218 115)
		(end 213.9 115)
		(width 0.1)
		(layer "B.Cu")
		(net 509)
	)
	(segment
		(start 211.7 118.1)
		(end 210.7 119.1)
		(width 0.1)
		(layer "B.Cu")
		(net 509)
	)
	(segment
		(start 211.7 117.2)
		(end 211.7 118.1)
		(width 0.1)
		(layer "B.Cu")
		(net 509)
	)
	(segment
		(start 213.9 115)
		(end 211.7 117.2)
		(width 0.1)
		(layer "B.Cu")
		(net 509)
	)
	(segment
		(start 218.03 114.03)
		(end 218.03 114.97)
		(width 0.1)
		(layer "B.Cu")
		(net 509)
	)
	(segment
		(start 218.03 114.97)
		(end 218 115)
		(width 0.1)
		(layer "B.Cu")
		(net 509)
	)
	(segment
		(start 210.7 119.1)
		(end 209.4 119.1)
		(width 0.1)
		(layer "B.Cu")
		(net 509)
	)
	(segment
		(start 229.27 119.3)
		(end 229.97 118.6)
		(width 0.1)
		(layer "In5.Cu")
		(net 509)
	)
	(segment
		(start 224.175 115.875)
		(end 225.9 117.6)
		(width 0.1)
		(layer "In5.Cu")
		(net 509)
	)
	(segment
		(start 221.9 115)
		(end 221.6 115.3)
		(width 0.1)
		(layer "In5.Cu")
		(net 509)
	)
	(segment
		(start 222.5 116.1)
		(end 222.725 115.875)
		(width 0.1)
		(layer "In5.Cu")
		(net 509)
	)
	(segment
		(start 222.725 115.875)
		(end 224.175 115.875)
		(width 0.1)
		(layer "In5.Cu")
		(net 509)
	)
	(segment
		(start 225.9 118.7)
		(end 226.5 119.3)
		(width 0.1)
		(layer "In5.Cu")
		(net 509)
	)
	(segment
		(start 225.9 117.6)
		(end 225.9 118.7)
		(width 0.1)
		(layer "In5.Cu")
		(net 509)
	)
	(segment
		(start 221.8 116.1)
		(end 222.5 116.1)
		(width 0.1)
		(layer "In5.Cu")
		(net 509)
	)
	(segment
		(start 226.5 119.3)
		(end 229.27 119.3)
		(width 0.1)
		(layer "In5.Cu")
		(net 509)
	)
	(segment
		(start 221.6 115.3)
		(end 221.6 115.9)
		(width 0.1)
		(layer "In5.Cu")
		(net 509)
	)
	(segment
		(start 221.6 115.9)
		(end 221.8 116.1)
		(width 0.1)
		(layer "In5.Cu")
		(net 509)
	)
	(segment
		(start 222.6 115)
		(end 221.9 115)
		(width 0.1)
		(layer "In5.Cu")
		(net 509)
	)
	(segment
		(start 231.67 112)
		(end 231.67 112.530331)
		(width 0.1)
		(layer "F.Cu")
		(net 510)
	)
	(segment
		(start 221.199 115.525)
		(end 222.125 115.525)
		(width 0.1)
		(layer "F.Cu")
		(net 510)
	)
	(segment
		(start 231.67 112.530331)
		(end 231.930532 112.790863)
		(width 0.1)
		(layer "F.Cu")
		(net 510)
	)
	(segment
		(start 209.8 118.7)
		(end 209.8 119.865)
		(width 0.1)
		(layer "F.Cu")
		(net 510)
	)
	(segment
		(start 209.8 119.865)
		(end 209.754 119.911)
		(width 0.1)
		(layer "F.Cu")
		(net 510)
	)
	(segment
		(start 220.427 115.525)
		(end 219.475 115.525)
		(width 0.1)
		(layer "F.Cu")
		(net 510)
	)
	(segment
		(start 232.07 111.6)
		(end 231.67 112)
		(width 0.1)
		(layer "F.Cu")
		(net 510)
	)
	(segment
		(start 222.125 115.525)
		(end 222.2 115.6)
		(width 0.1)
		(layer "F.Cu")
		(net 510)
	)
	(segment
		(start 219.475 115.525)
		(end 219.4 115.6)
		(width 0.1)
		(layer "F.Cu")
		(net 510)
	)
	(segment
		(start 231.930532 112.790863)
		(end 231.930532 114.0725)
		(width 0.1)
		(layer "F.Cu")
		(net 510)
	)
	(segment
		(start 220.427 115.525)
		(end 221.199 115.525)
		(width 0.1)
		(layer "F.Cu")
		(net 510)
	)
	(via
		(at 219.4 115.6)
		(size 0.45)
		(drill 0.1)
		(layers "F.Cu" "B.Cu")
		(net 510)
	)
	(via
		(at 209.8 118.7)
		(size 0.45)
		(drill 0.1)
		(layers "F.Cu" "B.Cu")
		(net 510)
	)
	(via
		(at 222.2 115.6)
		(size 0.45)
		(drill 0.1)
		(layers "F.Cu" "B.Cu")
		(net 510)
	)
	(via
		(at 232.07 111.6)
		(size 0.45)
		(drill 0.1)
		(layers "F.Cu" "B.Cu")
		(net 510)
	)
	(segment
		(start 208.8 119)
		(end 208.8 119.5)
		(width 0.1)
		(layer "B.Cu")
		(net 510)
	)
	(segment
		(start 218.1 115.6)
		(end 219.4 115.6)
		(width 0.1)
		(layer "B.Cu")
		(net 510)
	)
	(segment
		(start 209.1 118.7)
		(end 208.8 119)
		(width 0.1)
		(layer "B.Cu")
		(net 510)
	)
	(segment
		(start 208.8 119.5)
		(end 209 119.7)
		(width 0.1)
		(layer "B.Cu")
		(net 510)
	)
	(segment
		(start 220.54 115.6)
		(end 221.14 115)
		(width 0.1)
		(layer "B.Cu")
		(net 510)
	)
	(segment
		(start 209.8 118.7)
		(end 209.1 118.7)
		(width 0.1)
		(layer "B.Cu")
		(net 510)
	)
	(segment
		(start 221.14 115)
		(end 221.14 114.01)
		(width 0.1)
		(layer "B.Cu")
		(net 510)
	)
	(segment
		(start 209 119.7)
		(end 214 119.7)
		(width 0.1)
		(layer "B.Cu")
		(net 510)
	)
	(segment
		(start 214 119.7)
		(end 218.1 115.6)
		(width 0.1)
		(layer "B.Cu")
		(net 510)
	)
	(segment
		(start 219.4 115.6)
		(end 220.54 115.6)
		(width 0.1)
		(layer "B.Cu")
		(net 510)
	)
	(segment
		(start 222.2 115.6)
		(end 223.6 115.6)
		(width 0.1)
		(layer "In5.Cu")
		(net 510)
	)
	(segment
		(start 229.9 111.6)
		(end 232.07 111.6)
		(width 0.1)
		(layer "In5.Cu")
		(net 510)
	)
	(segment
		(start 225.2 114)
		(end 225.2 112.3)
		(width 0.1)
		(layer "In5.Cu")
		(net 510)
	)
	(segment
		(start 226.4 111.1)
		(end 229.4 111.1)
		(width 0.1)
		(layer "In5.Cu")
		(net 510)
	)
	(segment
		(start 229.4 111.1)
		(end 229.9 111.6)
		(width 0.1)
		(layer "In5.Cu")
		(net 510)
	)
	(segment
		(start 223.6 115.6)
		(end 225.2 114)
		(width 0.1)
		(layer "In5.Cu")
		(net 510)
	)
	(segment
		(start 225.2 112.3)
		(end 226.4 111.1)
		(width 0.1)
		(layer "In5.Cu")
		(net 510)
	)
	(segment
		(start 220.43 110.429)
		(end 221.202 110.429)
		(width 0.19)
		(layer "F.Cu")
		(net 511)
	)
	(segment
		(start 234.865532 113.32)
		(end 234.930532 113.385)
		(width 0.19)
		(layer "F.Cu")
		(net 511)
	)
	(segment
		(start 204.154 119.152599)
		(end 204.1685 119.138099)
		(width 0.19)
		(layer "F.Cu")
		(net 511)
	)
	(segment
		(start 220.017499 110.429)
		(end 220.43 110.429)
		(width 0.19)
		(layer "F.Cu")
		(net 511)
	)
	(segment
		(start 221.679501 110.494)
		(end 233.82563 110.494)
		(width 0.19)
		(layer "F.Cu")
		(net 511)
	)
	(segment
		(start 203.865 113.67337)
		(end 207.04437 110.494)
		(width 0.19)
		(layer "F.Cu")
		(net 511)
	)
	(segment
		(start 204.1685 119.08013)
		(end 203.865 118.77663)
		(width 0.19)
		(layer "F.Cu")
		(net 511)
	)
	(segment
		(start 203.865 118.77663)
		(end 203.865 113.67337)
		(width 0.19)
		(layer "F.Cu")
		(net 511)
	)
	(segment
		(start 234.865532 111.533902)
		(end 234.865532 113.32)
		(width 0.19)
		(layer "F.Cu")
		(net 511)
	)
	(segment
		(start 219.952499 110.494)
		(end 220.017499 110.429)
		(width 0.19)
		(layer "F.Cu")
		(net 511)
	)
	(segment
		(start 221.614501 110.429)
		(end 221.679501 110.494)
		(width 0.19)
		(layer "F.Cu")
		(net 511)
	)
	(segment
		(start 233.82563 110.494)
		(end 234.865532 111.533902)
		(width 0.19)
		(layer "F.Cu")
		(net 511)
	)
	(segment
		(start 204.1685 119.138099)
		(end 204.1685 119.08013)
		(width 0.19)
		(layer "F.Cu")
		(net 511)
	)
	(segment
		(start 234.930532 113.385)
		(end 234.930532 114.0725)
		(width 0.19)
		(layer "F.Cu")
		(net 511)
	)
	(segment
		(start 204.154 119.911)
		(end 204.154 119.152599)
		(width 0.19)
		(layer "F.Cu")
		(net 511)
	)
	(segment
		(start 221.202 110.429)
		(end 221.614501 110.429)
		(width 0.19)
		(layer "F.Cu")
		(net 511)
	)
	(segment
		(start 207.04437 110.494)
		(end 219.952499 110.494)
		(width 0.19)
		(layer "F.Cu")
		(net 511)
	)
	(segment
		(start 221.614501 110.929)
		(end 221.679501 110.864)
		(width 0.19)
		(layer "F.Cu")
		(net 512)
	)
	(segment
		(start 204.553 119.911)
		(end 204.553 119.152599)
		(width 0.19)
		(layer "F.Cu")
		(net 512)
	)
	(segment
		(start 234.430532 113.385)
		(end 234.430532 114.0725)
		(width 0.19)
		(layer "F.Cu")
		(net 512)
	)
	(segment
		(start 221.679501 110.864)
		(end 225.459549 110.864)
		(width 0.19)
		(layer "F.Cu")
		(net 512)
	)
	(segment
		(start 226.359549 110.864)
		(end 232.70237 110.864)
		(width 0.19)
		(layer "F.Cu")
		(net 512)
	)
	(segment
		(start 207.19763 110.864)
		(end 219.952499 110.864)
		(width 0.19)
		(layer "F.Cu")
		(net 512)
	)
	(segment
		(start 219.952499 110.864)
		(end 220.017499 110.929)
		(width 0.19)
		(layer "F.Cu")
		(net 512)
	)
	(segment
		(start 204.5385 119.138099)
		(end 204.5385 118.92687)
		(width 0.19)
		(layer "F.Cu")
		(net 512)
	)
	(segment
		(start 234.495532 113.32)
		(end 234.430532 113.385)
		(width 0.19)
		(layer "F.Cu")
		(net 512)
	)
	(segment
		(start 204.553 119.152599)
		(end 204.5385 119.138099)
		(width 0.19)
		(layer "F.Cu")
		(net 512)
	)
	(segment
		(start 204.235 118.62337)
		(end 204.235 113.82663)
		(width 0.19)
		(layer "F.Cu")
		(net 512)
	)
	(segment
		(start 232.70237 110.864)
		(end 233.67237 110.864)
		(width 0.19)
		(layer "F.Cu")
		(net 512)
	)
	(segment
		(start 233.67237 110.864)
		(end 234.495532 111.687162)
		(width 0.19)
		(layer "F.Cu")
		(net 512)
	)
	(segment
		(start 205.879125 112.437063)
		(end 205.950573 112.508511)
		(width 0.19)
		(layer "F.Cu")
		(net 512)
	)
	(segment
		(start 220.43 110.929)
		(end 221.202 110.929)
		(width 0.19)
		(layer "F.Cu")
		(net 512)
	)
	(segment
		(start 225.659549 111.064)
		(end 225.659549 111.142222)
		(width 0.19)
		(layer "F.Cu")
		(net 512)
	)
	(segment
		(start 226.159549 111.142222)
		(end 226.159549 111.064)
		(width 0.19)
		(layer "F.Cu")
		(net 512)
	)
	(segment
		(start 206.197321 111.864305)
		(end 206.260963 111.800666)
		(width 0.19)
		(layer "F.Cu")
		(net 512)
	)
	(segment
		(start 206.260963 111.800666)
		(end 207.19763 110.864)
		(width 0.19)
		(layer "F.Cu")
		(net 512)
	)
	(segment
		(start 206.205131 112.508511)
		(end 206.26877 112.444871)
		(width 0.19)
		(layer "F.Cu")
		(net 512)
	)
	(segment
		(start 204.5385 118.92687)
		(end 204.235 118.62337)
		(width 0.19)
		(layer "F.Cu")
		(net 512)
	)
	(segment
		(start 206.26877 112.190312)
		(end 206.197321 112.118863)
		(width 0.19)
		(layer "F.Cu")
		(net 512)
	)
	(segment
		(start 204.235 113.82663)
		(end 205.624567 112.437063)
		(width 0.19)
		(layer "F.Cu")
		(net 512)
	)
	(segment
		(start 234.495532 111.687162)
		(end 234.495532 113.32)
		(width 0.19)
		(layer "F.Cu")
		(net 512)
	)
	(segment
		(start 221.202 110.929)
		(end 221.614501 110.929)
		(width 0.19)
		(layer "F.Cu")
		(net 512)
	)
	(segment
		(start 220.017499 110.929)
		(end 220.43 110.929)
		(width 0.19)
		(layer "F.Cu")
		(net 512)
	)
	(segment
		(start 225.859549 111.342222)
		(end 225.959549 111.342222)
		(width 0.19)
		(layer "F.Cu")
		(net 512)
	)
	(arc
		(start 225.459549 110.864)
		(mid 225.60097 110.922579)
		(end 225.659549 111.064)
		(width 0.19)
		(layer "F.Cu")
		(net 512)
	)
	(arc
		(start 225.659549 111.142222)
		(mid 225.718128 111.283643)
		(end 225.859549 111.342222)
		(width 0.19)
		(layer "F.Cu")
		(net 512)
	)
	(arc
		(start 205.624567 112.437063)
		(mid 205.751846 112.384342)
		(end 205.879125 112.437063)
		(width 0.19)
		(layer "F.Cu")
		(net 512)
	)
	(arc
		(start 225.959549 111.342222)
		(mid 226.10097 111.283643)
		(end 226.159549 111.142222)
		(width 0.19)
		(layer "F.Cu")
		(net 512)
	)
	(arc
		(start 205.950573 112.508511)
		(mid 206.077852 112.561232)
		(end 206.205131 112.508511)
		(width 0.19)
		(layer "F.Cu")
		(net 512)
	)
	(arc
		(start 206.26877 112.444871)
		(mid 206.321491 112.317591)
		(end 206.26877 112.190312)
		(width 0.19)
		(layer "F.Cu")
		(net 512)
	)
	(arc
		(start 226.159549 111.064)
		(mid 226.218128 110.922579)
		(end 226.359549 110.864)
		(width 0.19)
		(layer "F.Cu")
		(net 512)
	)
	(arc
		(start 206.197321 112.118863)
		(mid 206.1446 111.991584)
		(end 206.197321 111.864305)
		(width 0.19)
		(layer "F.Cu")
		(net 512)
	)
	(segment
		(start 215.00037 117.062)
		(end 219.952499 117.062)
		(width 0.19)
		(layer "F.Cu")
		(net 513)
	)
	(segment
		(start 230.865532 117.685)
		(end 230.980532 117.8)
		(width 0.19)
		(layer "F.Cu")
		(net 513)
	)
	(segment
		(start 211.875155 114.185)
		(end 212.12337 114.185)
		(width 0.19)
		(layer "F.Cu")
		(net 513)
	)
	(segment
		(start 230.865532 117.1)
		(end 230.865532 117.685)
		(width 0.19)
		(layer "F.Cu")
		(net 513)
	)
	(segment
		(start 222.685 117.062)
		(end 222.8 117.177)
		(width 0.19)
		(layer "F.Cu")
		(net 513)
	)
	(segment
		(start 212.12337 114.185)
		(end 215.00037 117.062)
		(width 0.19)
		(layer "F.Cu")
		(net 513)
	)
	(segment
		(start 206.954 119.911)
		(end 206.954 118.74237)
		(width 0.19)
		(layer "F.Cu")
		(net 513)
	)
	(segment
		(start 211.245155 114.365)
		(end 211.245155 114.493087)
		(width 0.19)
		(layer "F.Cu")
		(net 513)
	)
	(segment
		(start 219.952499 117.062)
		(end 220.017499 117.127)
		(width 0.19)
		(layer "F.Cu")
		(net 513)
	)
	(segment
		(start 230.930532 116.3475)
		(end 230.930532 117.035)
		(width 0.19)
		(layer "F.Cu")
		(net 513)
	)
	(segment
		(start 221.202 117.127)
		(end 221.614501 117.127)
		(width 0.19)
		(layer "F.Cu")
		(net 513)
	)
	(segment
		(start 221.614501 117.127)
		(end 221.679501 117.062)
		(width 0.19)
		(layer "F.Cu")
		(net 513)
	)
	(segment
		(start 206.735 118.52337)
		(end 206.735 116.12663)
		(width 0.19)
		(layer "F.Cu")
		(net 513)
	)
	(segment
		(start 220.017499 117.127)
		(end 220.43 117.127)
		(width 0.19)
		(layer "F.Cu")
		(net 513)
	)
	(segment
		(start 206.954 118.74237)
		(end 206.735 118.52337)
		(width 0.19)
		(layer "F.Cu")
		(net 513)
	)
	(segment
		(start 220.43 117.127)
		(end 221.202 117.127)
		(width 0.19)
		(layer "F.Cu")
		(net 513)
	)
	(segment
		(start 206.735 116.12663)
		(end 208.67663 114.185)
		(width 0.19)
		(layer "F.Cu")
		(net 513)
	)
	(segment
		(start 211.695155 114.493087)
		(end 211.695155 114.365)
		(width 0.19)
		(layer "F.Cu")
		(net 513)
	)
	(segment
		(start 221.679501 117.062)
		(end 222.685 117.062)
		(width 0.19)
		(layer "F.Cu")
		(net 513)
	)
	(segment
		(start 211.425155 114.673087)
		(end 211.515155 114.673087)
		(width 0.19)
		(layer "F.Cu")
		(net 513)
	)
	(segment
		(start 208.67663 114.185)
		(end 211.065155 114.185)
		(width 0.19)
		(layer "F.Cu")
		(net 513)
	)
	(segment
		(start 230.930532 117.035)
		(end 230.865532 117.1)
		(width 0.19)
		(layer "F.Cu")
		(net 513)
	)
	(via
		(at 222.8 117.177)
		(size 0.45)
		(drill 0.1)
		(layers "F.Cu" "B.Cu")
		(net 513)
	)
	(via
		(at 230.980532 117.8)
		(size 0.45)
		(drill 0.1)
		(layers "F.Cu" "B.Cu")
		(net 513)
	)
	(arc
		(start 211.515155 114.673087)
		(mid 211.642434 114.620366)
		(end 211.695155 114.493087)
		(width 0.19)
		(layer "F.Cu")
		(net 513)
	)
	(arc
		(start 211.065155 114.185)
		(mid 211.192434 114.237721)
		(end 211.245155 114.365)
		(width 0.19)
		(layer "F.Cu")
		(net 513)
	)
	(arc
		(start 211.695155 114.365)
		(mid 211.747876 114.237721)
		(end 211.875155 114.185)
		(width 0.19)
		(layer "F.Cu")
		(net 513)
	)
	(arc
		(start 211.245155 114.493087)
		(mid 211.297876 114.620366)
		(end 211.425155 114.673087)
		(width 0.19)
		(layer "F.Cu")
		(net 513)
	)
	(segment
		(start 230.818032 118.946424)
		(end 230.818032 117.9625)
		(width 0.15)
		(layer "In7.Cu")
		(net 513)
	)
	(segment
		(start 225.2625 118.856956)
		(end 226.343044 119.9375)
		(width 0.15)
		(layer "In7.Cu")
		(net 513)
	)
	(segment
		(start 222.8 117.177)
		(end 222.9625 117.0145)
		(width 0.15)
		(layer "In7.Cu")
		(net 513)
	)
	(segment
		(start 226.343044 119.9375)
		(end 229.826956 119.9375)
		(width 0.15)
		(layer "In7.Cu")
		(net 513)
	)
	(segment
		(start 230.818032 117.9625)
		(end 230.980532 117.8)
		(width 0.15)
		(layer "In7.Cu")
		(net 513)
	)
	(segment
		(start 229.826956 119.9375)
		(end 230.818032 118.946424)
		(width 0.15)
		(layer "In7.Cu")
		(net 513)
	)
	(segment
		(start 222.9625 117.0145)
		(end 224.420044 117.0145)
		(width 0.15)
		(layer "In7.Cu")
		(net 513)
	)
	(segment
		(start 224.420044 117.0145)
		(end 225.2625 117.856956)
		(width 0.15)
		(layer "In7.Cu")
		(net 513)
	)
	(segment
		(start 225.2625 117.856956)
		(end 225.2625 118.856956)
		(width 0.15)
		(layer "In7.Cu")
		(net 513)
	)
	(segment
		(start 227.613 81)
		(end 227 81)
		(width 0.1)
		(layer "F.Cu")
		(net 514)
	)
	(segment
		(start 227.613 81)
		(end 228.385 81)
		(width 0.1)
		(layer "F.Cu")
		(net 514)
	)
	(segment
		(start 229.2 81)
		(end 228.385 81)
		(width 0.1)
		(layer "F.Cu")
		(net 514)
	)
	(segment
		(start 199.601 75.13)
		(end 199.601 74.349)
		(width 0.1)
		(layer "F.Cu")
		(net 514)
	)
	(segment
		(start 231.930532 73.439468)
		(end 231.930532 75.0725)
		(width 0.1)
		(layer "F.Cu")
		(net 514)
	)
	(segment
		(start 231.97 73.4)
		(end 231.930532 73.439468)
		(width 0.1)
		(layer "F.Cu")
		(net 514)
	)
	(segment
		(start 199.601 74.349)
		(end 199.65 74.3)
		(width 0.1)
		(layer "F.Cu")
		(net 514)
	)
	(via
		(at 231.97 73.4)
		(size 0.45)
		(drill 0.1)
		(layers "F.Cu" "B.Cu")
		(net 514)
	)
	(via
		(at 199.65 74.3)
		(size 0.45)
		(drill 0.1)
		(layers "F.Cu" "B.Cu")
		(net 514)
	)
	(via
		(at 227 81)
		(size 0.45)
		(drill 0.1)
		(layers "F.Cu" "B.Cu")
		(net 514)
	)
	(via
		(at 229.2 81)
		(size 0.45)
		(drill 0.1)
		(layers "F.Cu" "B.Cu")
		(net 514)
	)
	(segment
		(start 215 79.3)
		(end 217.9 82.2)
		(width 0.1)
		(layer "In5.Cu")
		(net 514)
	)
	(segment
		(start 203.224264 74.900002)
		(end 204.524264 76.200002)
		(width 0.1)
		(layer "In5.Cu")
		(net 514)
	)
	(segment
		(start 199.65 74.3)
		(end 200.250002 74.900002)
		(width 0.1)
		(layer "In5.Cu")
		(net 514)
	)
	(segment
		(start 206.700002 76.200002)
		(end 208.4 77.9)
		(width 0.1)
		(layer "In5.Cu")
		(net 514)
	)
	(segment
		(start 200.250002 74.900002)
		(end 203.224264 74.900002)
		(width 0.1)
		(layer "In5.Cu")
		(net 514)
	)
	(segment
		(start 214.1 79.3)
		(end 215 79.3)
		(width 0.1)
		(layer "In5.Cu")
		(net 514)
	)
	(segment
		(start 208.4 77.9)
		(end 210.4 77.9)
		(width 0.1)
		(layer "In5.Cu")
		(net 514)
	)
	(segment
		(start 225.2 82.2)
		(end 226.4 81)
		(width 0.1)
		(layer "In5.Cu")
		(net 514)
	)
	(segment
		(start 226.4 81)
		(end 227 81)
		(width 0.1)
		(layer "In5.Cu")
		(net 514)
	)
	(segment
		(start 213.5 79.9)
		(end 214.1 79.3)
		(width 0.1)
		(layer "In5.Cu")
		(net 514)
	)
	(segment
		(start 217.9 82.2)
		(end 225.2 82.2)
		(width 0.1)
		(layer "In5.Cu")
		(net 514)
	)
	(segment
		(start 204.524264 76.200002)
		(end 206.700002 76.200002)
		(width 0.1)
		(layer "In5.Cu")
		(net 514)
	)
	(segment
		(start 210.4 77.9)
		(end 212.4 79.9)
		(width 0.1)
		(layer "In5.Cu")
		(net 514)
	)
	(segment
		(start 212.4 79.9)
		(end 213.5 79.9)
		(width 0.1)
		(layer "In5.Cu")
		(net 514)
	)
	(segment
		(start 231.97 76.88)
		(end 230.8 78.05)
		(width 0.1)
		(layer "In7.Cu")
		(net 514)
	)
	(segment
		(start 230.15 81)
		(end 229.2 81)
		(width 0.1)
		(layer "In7.Cu")
		(net 514)
	)
	(segment
		(start 230.8 78.05)
		(end 230.8 80.35)
		(width 0.1)
		(layer "In7.Cu")
		(net 514)
	)
	(segment
		(start 230.8 80.35)
		(end 230.15 81)
		(width 0.1)
		(layer "In7.Cu")
		(net 514)
	)
	(segment
		(start 231.97 73.4)
		(end 231.97 76.88)
		(width 0.1)
		(layer "In7.Cu")
		(net 514)
	)
	(segment
		(start 233.47 79.98)
		(end 233.47 77.386968)
		(width 0.1)
		(layer "F.Cu")
		(net 515)
	)
	(segment
		(start 229.102 82.998)
		(end 229.55 82.55)
		(width 0.1)
		(layer "F.Cu")
		(net 515)
	)
	(segment
		(start 228.385001 82.998)
		(end 229.102 82.998)
		(width 0.1)
		(layer "F.Cu")
		(net 515)
	)
	(segment
		(start 226.7 83.5)
		(end 225.85 83.5)
		(width 0.1)
		(layer "F.Cu")
		(net 515)
	)
	(segment
		(start 227.613 82.998)
		(end 227.202 82.998)
		(width 0.1)
		(layer "F.Cu")
		(net 515)
	)
	(segment
		(start 233.47 77.386968)
		(end 233.430532 77.3475)
		(width 0.1)
		(layer "F.Cu")
		(net 515)
	)
	(segment
		(start 226.7 83.5)
		(end 227.202 82.998)
		(width 0.1)
		(layer "F.Cu")
		(net 515)
	)
	(segment
		(start 227.613 82.998)
		(end 228.385001 82.998)
		(width 0.1)
		(layer "F.Cu")
		(net 515)
	)
	(segment
		(start 230.9 82.55)
		(end 233.47 79.98)
		(width 0.1)
		(layer "F.Cu")
		(net 515)
	)
	(segment
		(start 229.55 82.55)
		(end 230.9 82.55)
		(width 0.1)
		(layer "F.Cu")
		(net 515)
	)
	(segment
		(start 198.799 75.13)
		(end 198.799 74.449)
		(width 0.1)
		(layer "F.Cu")
		(net 515)
	)
	(segment
		(start 198.799 74.449)
		(end 198.75 74.4)
		(width 0.1)
		(layer "F.Cu")
		(net 515)
	)
	(via
		(at 225.85 83.5)
		(size 0.45)
		(drill 0.1)
		(layers "F.Cu" "B.Cu")
		(net 515)
	)
	(via
		(at 198.75 74.4)
		(size 0.45)
		(drill 0.1)
		(layers "F.Cu" "B.Cu")
		(net 515)
	)
	(segment
		(start 214.224263 79.599999)
		(end 214.875735 79.599999)
		(width 0.1)
		(layer "In5.Cu")
		(net 515)
	)
	(segment
		(start 206.575738 76.5)
		(end 208.275736 78.199998)
		(width 0.1)
		(layer "In5.Cu")
		(net 515)
	)
	(segment
		(start 214.875735 79.599999)
		(end 217.775736 82.5)
		(width 0.1)
		(layer "In5.Cu")
		(net 515)
	)
	(segment
		(start 208.275736 78.199998)
		(end 210.275736 78.199998)
		(width 0.1)
		(layer "In5.Cu")
		(net 515)
	)
	(segment
		(start 212.275736 80.199998)
		(end 213.624264 80.199998)
		(width 0.1)
		(layer "In5.Cu")
		(net 515)
	)
	(segment
		(start 199.55 75.2)
		(end 203.1 75.2)
		(width 0.1)
		(layer "In5.Cu")
		(net 515)
	)
	(segment
		(start 224.85 82.5)
		(end 225.85 83.5)
		(width 0.1)
		(layer "In5.Cu")
		(net 515)
	)
	(segment
		(start 204.4 76.5)
		(end 206.575738 76.5)
		(width 0.1)
		(layer "In5.Cu")
		(net 515)
	)
	(segment
		(start 203.1 75.2)
		(end 204.4 76.5)
		(width 0.1)
		(layer "In5.Cu")
		(net 515)
	)
	(segment
		(start 210.275736 78.199998)
		(end 212.275736 80.199998)
		(width 0.1)
		(layer "In5.Cu")
		(net 515)
	)
	(segment
		(start 213.624264 80.199998)
		(end 214.224263 79.599999)
		(width 0.1)
		(layer "In5.Cu")
		(net 515)
	)
	(segment
		(start 217.775736 82.5)
		(end 224.85 82.5)
		(width 0.1)
		(layer "In5.Cu")
		(net 515)
	)
	(segment
		(start 198.75 74.4)
		(end 199.55 75.2)
		(width 0.1)
		(layer "In5.Cu")
		(net 515)
	)
	(segment
		(start 102.915 91.925)
		(end 102.915 100.79837)
		(width 0.19)
		(layer "F.Cu")
		(net 516)
	)
	(segment
		(start 102.39746 91.001489)
		(end 102.39746 91.101489)
		(width 0.19)
		(layer "F.Cu")
		(net 516)
	)
	(segment
		(start 102.250502 88.212132)
		(end 102.915 88.87663)
		(width 0.19)
		(layer "F.Cu")
		(net 516)
	)
	(segment
		(start 104.695532 72.415)
		(end 104.695532 72.685)
		(width 0.19)
		(layer "F.Cu")
		(net 516)
	)
	(segment
		(start 102.715 90.801489)
		(end 102.59746 90.801489)
		(width 0.19)
		(layer "F.Cu")
		(net 516)
	)
	(segment
		(start 104.430532 72.15)
		(end 104.695532 72.415)
		(width 0.19)
		(layer "F.Cu")
		(net 516)
	)
	(segment
		(start 102.087868 88.212132)
		(end 102.250502 88.212132)
		(width 0.19)
		(layer "F.Cu")
		(net 516)
	)
	(segment
		(start 102.915 88.87663)
		(end 102.915 90.601489)
		(width 0.19)
		(layer "F.Cu")
		(net 516)
	)
	(segment
		(start 99.450502 115.487868)
		(end 99.287868 115.487868)
		(width 0.19)
		(layer "F.Cu")
		(net 516)
	)
	(segment
		(start 102.915 100.79837)
		(end 99.615 104.09837)
		(width 0.19)
		(layer "F.Cu")
		(net 516)
	)
	(segment
		(start 102.915 91.601489)
		(end 102.915 91.925)
		(width 0.19)
		(layer "F.Cu")
		(net 516)
	)
	(segment
		(start 102.59746 91.301489)
		(end 102.715 91.301489)
		(width 0.19)
		(layer "F.Cu")
		(net 516)
	)
	(segment
		(start 104.695532 72.685)
		(end 104.580532 72.8)
		(width 0.19)
		(layer "F.Cu")
		(net 516)
	)
	(segment
		(start 99.615 115.32337)
		(end 99.450502 115.487868)
		(width 0.19)
		(layer "F.Cu")
		(net 516)
	)
	(segment
		(start 102.915 91.501489)
		(end 102.915 91.601489)
		(width 0.19)
		(layer "F.Cu")
		(net 516)
	)
	(segment
		(start 99.615 104.09837)
		(end 99.615 115.32337)
		(width 0.19)
		(layer "F.Cu")
		(net 516)
	)
	(via
		(at 104.580532 72.8)
		(size 0.45)
		(drill 0.1)
		(layers "F.Cu" "B.Cu")
		(net 516)
	)
	(via
		(at 99.287868 115.487868)
		(size 0.45)
		(drill 0.1)
		(layers "F.Cu" "B.Cu")
		(net 516)
	)
	(via
		(at 102.087868 88.212132)
		(size 0.45)
		(drill 0.1)
		(layers "F.Cu" "B.Cu")
		(net 516)
	)
	(arc
		(start 102.915 90.601489)
		(mid 102.856421 90.74291)
		(end 102.715 90.801489)
		(width 0.19)
		(layer "F.Cu")
		(net 516)
	)
	(arc
		(start 102.59746 90.801489)
		(mid 102.456039 90.860068)
		(end 102.39746 91.001489)
		(width 0.19)
		(layer "F.Cu")
		(net 516)
	)
	(arc
		(start 102.715 91.301489)
		(mid 102.856421 91.360068)
		(end 102.915 91.501489)
		(width 0.19)
		(layer "F.Cu")
		(net 516)
	)
	(arc
		(start 102.39746 91.101489)
		(mid 102.456039 91.24291)
		(end 102.59746 91.301489)
		(width 0.19)
		(layer "F.Cu")
		(net 516)
	)
	(segment
		(start 94.83 120.105)
		(end 95.63337 120.105)
		(width 0.19)
		(layer "B.Cu")
		(net 516)
	)
	(segment
		(start 94.505 119.78)
		(end 94.83 120.105)
		(width 0.19)
		(layer "B.Cu")
		(net 516)
	)
	(segment
		(start 94.48 119.78)
		(end 94.505 119.78)
		(width 0.19)
		(layer "B.Cu")
		(net 516)
	)
	(segment
		(start 99.287868 115.650502)
		(end 99.287868 115.487868)
		(width 0.19)
		(layer "B.Cu")
		(net 516)
	)
	(segment
		(start 95.63337 120.105)
		(end 97.915 117.82337)
		(width 0.19)
		(layer "B.Cu")
		(net 516)
	)
	(segment
		(start 97.915 117.02337)
		(end 99.287868 115.650502)
		(width 0.19)
		(layer "B.Cu")
		(net 516)
	)
	(segment
		(start 97.915 117.82337)
		(end 97.915 117.02337)
		(width 0.19)
		(layer "B.Cu")
		(net 516)
	)
	(segment
		(start 104.343044 74.2625)
		(end 104.743032 73.862512)
		(width 0.15)
		(layer "In7.Cu")
		(net 516)
	)
	(segment
		(start 104.743032 73.862512)
		(end 104.743032 72.9625)
		(width 0.15)
		(layer "In7.Cu")
		(net 516)
	)
	(segment
		(start 102.8625 74.743044)
		(end 103.343044 74.2625)
		(width 0.15)
		(layer "In7.Cu")
		(net 516)
	)
	(segment
		(start 102.343044 75.6625)
		(end 102.8625 75.143044)
		(width 0.15)
		(layer "In7.Cu")
		(net 516)
	)
	(segment
		(start 100.7625 81.756956)
		(end 99.8625 80.856956)
		(width 0.15)
		(layer "In7.Cu")
		(net 516)
	)
	(segment
		(start 102.087868 88.212132)
		(end 102.087868 87.982323)
		(width 0.15)
		(layer "In7.Cu")
		(net 516)
	)
	(segment
		(start 101.343044 75.6625)
		(end 102.343044 75.6625)
		(width 0.15)
		(layer "In7.Cu")
		(net 516)
	)
	(segment
		(start 100.8625 77.743044)
		(end 100.8625 76.143044)
		(width 0.15)
		(layer "In7.Cu")
		(net 516)
	)
	(segment
		(start 104.743032 72.9625)
		(end 104.580532 72.8)
		(width 0.15)
		(layer "In7.Cu")
		(net 516)
	)
	(segment
		(start 103.343044 74.2625)
		(end 104.343044 74.2625)
		(width 0.15)
		(layer "In7.Cu")
		(net 516)
	)
	(segment
		(start 100.8625 76.143044)
		(end 101.343044 75.6625)
		(width 0.15)
		(layer "In7.Cu")
		(net 516)
	)
	(segment
		(start 102.8625 75.143044)
		(end 102.8625 74.743044)
		(width 0.15)
		(layer "In7.Cu")
		(net 516)
	)
	(segment
		(start 99.8625 80.256956)
		(end 99.5125 79.906956)
		(width 0.15)
		(layer "In7.Cu")
		(net 516)
	)
	(segment
		(start 99.5125 79.906956)
		(end 99.5125 79.093044)
		(width 0.15)
		(layer "In7.Cu")
		(net 516)
	)
	(segment
		(start 99.8625 80.856956)
		(end 99.8625 80.256956)
		(width 0.15)
		(layer "In7.Cu")
		(net 516)
	)
	(segment
		(start 100.7625 86.656955)
		(end 100.7625 81.756956)
		(width 0.15)
		(layer "In7.Cu")
		(net 516)
	)
	(segment
		(start 102.087868 87.982323)
		(end 100.7625 86.656955)
		(width 0.15)
		(layer "In7.Cu")
		(net 516)
	)
	(segment
		(start 99.5125 79.093044)
		(end 100.8625 77.743044)
		(width 0.15)
		(layer "In7.Cu")
		(net 516)
	)
	(segment
		(start 95.99 90.27663)
		(end 95.99 97.57663)
		(width 0.19)
		(layer "F.Cu")
		(net 517)
	)
	(segment
		(start 94.17663 89.485)
		(end 95.19837 89.485)
		(width 0.19)
		(layer "F.Cu")
		(net 517)
	)
	(segment
		(start 93.4 90.09)
		(end 93.53 89.96)
		(width 0.19)
		(layer "F.Cu")
		(net 517)
	)
	(segment
		(start 93.53 89.96)
		(end 93.70163 89.96)
		(width 0.19)
		(layer "F.Cu")
		(net 517)
	)
	(segment
		(start 96.695532 72.685)
		(end 96.580532 72.8)
		(width 0.19)
		(layer "F.Cu")
		(net 517)
	)
	(segment
		(start 94.915 105.29837)
		(end 94.915 116.07663)
		(width 0.19)
		(layer "F.Cu")
		(net 517)
	)
	(segment
		(start 94.915 116.07663)
		(end 98.62337 119.785)
		(width 0.19)
		(layer "F.Cu")
		(net 517)
	)
	(segment
		(start 101.385 117.53)
		(end 101.515 117.4)
		(width 0.19)
		(layer "F.Cu")
		(net 517)
	)
	(segment
		(start 96.695532 72.415)
		(end 96.695532 72.685)
		(width 0.19)
		(layer "F.Cu")
		(net 517)
	)
	(segment
		(start 96.430532 72.15)
		(end 96.695532 72.415)
		(width 0.19)
		(layer "F.Cu")
		(net 517)
	)
	(segment
		(start 93.70163 89.96)
		(end 94.17663 89.485)
		(width 0.19)
		(layer "F.Cu")
		(net 517)
	)
	(segment
		(start 98.265 101.94837)
		(end 94.915 105.29837)
		(width 0.19)
		(layer "F.Cu")
		(net 517)
	)
	(segment
		(start 98.265 99.85163)
		(end 98.265 101.94837)
		(width 0.19)
		(layer "F.Cu")
		(net 517)
	)
	(segment
		(start 95.99 97.57663)
		(end 98.265 99.85163)
		(width 0.19)
		(layer "F.Cu")
		(net 517)
	)
	(segment
		(start 95.19837 89.485)
		(end 95.99 90.27663)
		(width 0.19)
		(layer "F.Cu")
		(net 517)
	)
	(segment
		(start 100.57663 119.785)
		(end 101.385 118.97663)
		(width 0.19)
		(layer "F.Cu")
		(net 517)
	)
	(segment
		(start 98.62337 119.785)
		(end 100.57663 119.785)
		(width 0.19)
		(layer "F.Cu")
		(net 517)
	)
	(segment
		(start 101.385 118.97663)
		(end 101.385 117.53)
		(width 0.19)
		(layer "F.Cu")
		(net 517)
	)
	(via
		(at 93.4 90.09)
		(size 0.45)
		(drill 0.1)
		(layers "F.Cu" "B.Cu")
		(net 517)
	)
	(via
		(at 101.515 117.4)
		(size 0.45)
		(drill 0.1)
		(layers "F.Cu" "B.Cu")
		(net 517)
	)
	(via
		(at 96.580532 72.8)
		(size 0.45)
		(drill 0.1)
		(layers "F.Cu" "B.Cu")
		(net 517)
	)
	(segment
		(start 92.465 76.07337)
		(end 92.465 86.02337)
		(width 0.19)
		(layer "B.Cu")
		(net 517)
	)
	(segment
		(start 91.365 87.12337)
		(end 91.365 89.12663)
		(width 0.19)
		(layer "B.Cu")
		(net 517)
	)
	(segment
		(start 91.365 89.12663)
		(end 92.19837 89.96)
		(width 0.19)
		(layer "B.Cu")
		(net 517)
	)
	(segment
		(start 99.97663 114.215)
		(end 101.385 115.62337)
		(width 0.19)
		(layer "B.Cu")
		(net 517)
	)
	(segment
		(start 101.385 117.27)
		(end 101.515 117.4)
		(width 0.19)
		(layer "B.Cu")
		(net 517)
	)
	(segment
		(start 96.665 116.32337)
		(end 98.77337 114.215)
		(width 0.19)
		(layer "B.Cu")
		(net 517)
	)
	(segment
		(start 94.32337 74.215)
		(end 92.465 76.07337)
		(width 0.19)
		(layer "B.Cu")
		(net 517)
	)
	(segment
		(start 101.385 115.62337)
		(end 101.385 117.27)
		(width 0.19)
		(layer "B.Cu")
		(net 517)
	)
	(segment
		(start 96.695532 72.915)
		(end 96.695532 73.892838)
		(width 0.19)
		(layer "B.Cu")
		(net 517)
	)
	(segment
		(start 93.27 89.96)
		(end 93.4 90.09)
		(width 0.19)
		(layer "B.Cu")
		(net 517)
	)
	(segment
		(start 95.63837 118.1)
		(end 96.665 117.07337)
		(width 0.19)
		(layer "B.Cu")
		(net 517)
	)
	(segment
		(start 94.505 117.8)
		(end 94.805 118.1)
		(width 0.19)
		(layer "B.Cu")
		(net 517)
	)
	(segment
		(start 96.695532 73.892838)
		(end 96.37337 74.215)
		(width 0.19)
		(layer "B.Cu")
		(net 517)
	)
	(segment
		(start 94.48 117.8)
		(end 94.505 117.8)
		(width 0.19)
		(layer "B.Cu")
		(net 517)
	)
	(segment
		(start 96.580532 72.8)
		(end 96.695532 72.915)
		(width 0.19)
		(layer "B.Cu")
		(net 517)
	)
	(segment
		(start 96.37337 74.215)
		(end 94.32337 74.215)
		(width 0.19)
		(layer "B.Cu")
		(net 517)
	)
	(segment
		(start 92.465 86.02337)
		(end 91.365 87.12337)
		(width 0.19)
		(layer "B.Cu")
		(net 517)
	)
	(segment
		(start 96.665 117.07337)
		(end 96.665 116.32337)
		(width 0.19)
		(layer "B.Cu")
		(net 517)
	)
	(segment
		(start 92.19837 89.96)
		(end 93.27 89.96)
		(width 0.19)
		(layer "B.Cu")
		(net 517)
	)
	(segment
		(start 98.77337 114.215)
		(end 99.97663 114.215)
		(width 0.19)
		(layer "B.Cu")
		(net 517)
	)
	(segment
		(start 94.805 118.1)
		(end 95.63837 118.1)
		(width 0.19)
		(layer "B.Cu")
		(net 517)
	)
	(segment
		(start 86.385532 121.305)
		(end 85.935532 120.855)
		(width 0.19)
		(layer "B.Cu")
		(net 518)
	)
	(segment
		(start 93.195 118.1)
		(end 90.33837 118.1)
		(width 0.19)
		(layer "B.Cu")
		(net 518)
	)
	(segment
		(start 93.52 117.8)
		(end 93.495 117.8)
		(width 0.19)
		(layer "B.Cu")
		(net 518)
	)
	(segment
		(start 90.33837 118.1)
		(end 87.13337 121.305)
		(width 0.19)
		(layer "B.Cu")
		(net 518)
	)
	(segment
		(start 93.495 117.8)
		(end 93.195 118.1)
		(width 0.19)
		(layer "B.Cu")
		(net 518)
	)
	(segment
		(start 87.13337 121.305)
		(end 86.385532 121.305)
		(width 0.19)
		(layer "B.Cu")
		(net 518)
	)
	(segment
		(start 97.094736 89.006366)
		(end 97.151306 89.062936)
		(width 0.19)
		(layer "F.Cu")
		(net 519)
	)
	(segment
		(start 96.364733 89.170686)
		(end 96.421301 89.227254)
		(width 0.19)
		(layer "F.Cu")
		(net 519)
	)
	(segment
		(start 97.235497 89.147127)
		(end 97.615 89.52663)
		(width 0.19)
		(layer "F.Cu")
		(net 519)
	)
	(segment
		(start 99.615 118.07663)
		(end 99.615 118.57)
		(width 0.19)
		(layer "F.Cu")
		(net 519)
	)
	(segment
		(start 96.17337 88.085)
		(end 96.585621 88.497251)
		(width 0.19)
		(layer "F.Cu")
		(net 519)
	)
	(segment
		(start 97.615 89.52663)
		(end 97.615 96.67663)
		(width 0.19)
		(layer "F.Cu")
		(net 519)
	)
	(segment
		(start 95.50163 88.085)
		(end 96.17337 88.085)
		(width 0.19)
		(layer "F.Cu")
		(net 519)
	)
	(segment
		(start 97.151306 89.062936)
		(end 97.235497 89.147127)
		(width 0.19)
		(layer "F.Cu")
		(net 519)
	)
	(segment
		(start 96.165 114.62663)
		(end 99.615 118.07663)
		(width 0.19)
		(layer "F.Cu")
		(net 519)
	)
	(segment
		(start 99.615 118.57)
		(end 99.485 118.7)
		(width 0.19)
		(layer "F.Cu")
		(net 519)
	)
	(segment
		(start 95.39 88.675)
		(end 95.26 88.545)
		(width 0.19)
		(layer "F.Cu")
		(net 519)
	)
	(segment
		(start 97.065532 75.415)
		(end 97.065532 75.685)
		(width 0.19)
		(layer "F.Cu")
		(net 519)
	)
	(segment
		(start 95.26 88.32663)
		(end 95.50163 88.085)
		(width 0.19)
		(layer "F.Cu")
		(net 519)
	)
	(segment
		(start 96.647575 89.227254)
		(end 96.868462 89.006366)
		(width 0.19)
		(layer "F.Cu")
		(net 519)
	)
	(segment
		(start 99.84 98.90163)
		(end 99.84 102.24837)
		(width 0.19)
		(layer "F.Cu")
		(net 519)
	)
	(segment
		(start 97.065532 75.685)
		(end 97.180532 75.8)
		(width 0.19)
		(layer "F.Cu")
		(net 519)
	)
	(segment
		(start 97.615 96.67663)
		(end 99.84 98.90163)
		(width 0.19)
		(layer "F.Cu")
		(net 519)
	)
	(segment
		(start 96.585621 88.723525)
		(end 96.364733 88.944412)
		(width 0.19)
		(layer "F.Cu")
		(net 519)
	)
	(segment
		(start 96.165 105.92337)
		(end 96.165 114.62663)
		(width 0.19)
		(layer "F.Cu")
		(net 519)
	)
	(segment
		(start 97.330532 75.15)
		(end 97.065532 75.415)
		(width 0.19)
		(layer "F.Cu")
		(net 519)
	)
	(segment
		(start 99.84 102.24837)
		(end 96.165 105.92337)
		(width 0.19)
		(layer "F.Cu")
		(net 519)
	)
	(segment
		(start 95.26 88.545)
		(end 95.26 88.32663)
		(width 0.19)
		(layer "F.Cu")
		(net 519)
	)
	(via
		(at 95.39 88.675)
		(size 0.45)
		(drill 0.1)
		(layers "F.Cu" "B.Cu")
		(net 519)
	)
	(via
		(at 97.180532 75.8)
		(size 0.45)
		(drill 0.1)
		(layers "F.Cu" "B.Cu")
		(net 519)
	)
	(via
		(at 99.485 118.7)
		(size 0.45)
		(drill 0.1)
		(layers "F.Cu" "B.Cu")
		(net 519)
	)
	(arc
		(start 96.421301 89.227254)
		(mid 96.534438 89.274117)
		(end 96.647575 89.227254)
		(width 0.19)
		(layer "F.Cu")
		(net 519)
	)
	(arc
		(start 96.585621 88.497251)
		(mid 96.632484 88.610388)
		(end 96.585621 88.723525)
		(width 0.19)
		(layer "F.Cu")
		(net 519)
	)
	(arc
		(start 96.364733 88.944412)
		(mid 96.31787 89.057549)
		(end 96.364733 89.170686)
		(width 0.19)
		(layer "F.Cu")
		(net 519)
	)
	(arc
		(start 96.868462 89.006366)
		(mid 96.981599 88.959503)
		(end 97.094736 89.006366)
		(width 0.19)
		(layer "F.Cu")
		(net 519)
	)
	(segment
		(start 99.129507 120.758867)
		(end 99.194561 120.69381)
		(width 0.19)
		(layer "B.Cu")
		(net 519)
	)
	(segment
		(start 95.99163 76.22)
		(end 96.98 76.22)
		(width 0.19)
		(layer "B.Cu")
		(net 519)
	)
	(segment
		(start 99.615 119.549627)
		(end 99.615 118.83)
		(width 0.19)
		(layer "B.Cu")
		(net 519)
	)
	(segment
		(start 94.48 121.775)
		(end 94.48 121.8)
		(width 0.19)
		(layer "B.Cu")
		(net 519)
	)
	(segment
		(start 93.985 83.32663)
		(end 94.435 82.87663)
		(width 0.19)
		(layer "B.Cu")
		(net 519)
	)
	(segment
		(start 99.615 118.83)
		(end 99.485 118.7)
		(width 0.19)
		(layer "B.Cu")
		(net 519)
	)
	(segment
		(start 94.085 81.87337)
		(end 94.085 80.97663)
		(width 0.19)
		(layer "B.Cu")
		(net 519)
	)
	(segment
		(start 94.435 85.42337)
		(end 93.985 84.97337)
		(width 0.19)
		(layer "B.Cu")
		(net 519)
	)
	(segment
		(start 97.180532 76.019468)
		(end 97.180532 75.8)
		(width 0.19)
		(layer "B.Cu")
		(net 519)
	)
	(segment
		(start 94.885 80.17663)
		(end 94.885 77.32663)
		(width 0.19)
		(layer "B.Cu")
		(net 519)
	)
	(segment
		(start 94.78 122.1)
		(end 97.78837 122.1)
		(width 0.19)
		(layer "B.Cu")
		(net 519)
	)
	(segment
		(start 99.615 120.27337)
		(end 99.615 119.549627)
		(width 0.19)
		(layer "B.Cu")
		(net 519)
	)
	(segment
		(start 99.555185 120.333184)
		(end 99.615 120.27337)
		(width 0.19)
		(layer "B.Cu")
		(net 519)
	)
	(segment
		(start 98.669888 120.559461)
		(end 98.869293 120.758866)
		(width 0.19)
		(layer "B.Cu")
		(net 519)
	)
	(segment
		(start 94.435 82.87663)
		(end 94.435 82.22337)
		(width 0.19)
		(layer "B.Cu")
		(net 519)
	)
	(segment
		(start 95.26 88.545)
		(end 95.26 88.09837)
		(width 0.19)
		(layer "B.Cu")
		(net 519)
	)
	(segment
		(start 93.985 84.97337)
		(end 93.985 83.32663)
		(width 0.19)
		(layer "B.Cu")
		(net 519)
	)
	(segment
		(start 97.78837 122.1)
		(end 98.544021 121.344349)
		(width 0.19)
		(layer "B.Cu")
		(net 519)
	)
	(segment
		(start 98.544022 121.084133)
		(end 98.344618 120.884729)
		(width 0.19)
		(layer "B.Cu")
		(net 519)
	)
	(segment
		(start 99.194561 120.69381)
		(end 99.555185 120.333184)
		(width 0.19)
		(layer "B.Cu")
		(net 519)
	)
	(segment
		(start 94.085 80.97663)
		(end 94.885 80.17663)
		(width 0.19)
		(layer "B.Cu")
		(net 519)
	)
	(segment
		(start 96.98 76.22)
		(end 97.180532 76.019468)
		(width 0.19)
		(layer "B.Cu")
		(net 519)
	)
	(segment
		(start 95.39 88.675)
		(end 95.26 88.545)
		(width 0.19)
		(layer "B.Cu")
		(net 519)
	)
	(segment
		(start 94.435 82.22337)
		(end 94.085 81.87337)
		(width 0.19)
		(layer "B.Cu")
		(net 519)
	)
	(segment
		(start 95.26 88.09837)
		(end 94.435 87.27337)
		(width 0.19)
		(layer "B.Cu")
		(net 519)
	)
	(segment
		(start 94.885 77.32663)
		(end 95.99163 76.22)
		(width 0.19)
		(layer "B.Cu")
		(net 519)
	)
	(segment
		(start 94.48 121.8)
		(end 94.78 122.1)
		(width 0.19)
		(layer "B.Cu")
		(net 519)
	)
	(segment
		(start 98.344617 120.624515)
		(end 98.409672 120.559461)
		(width 0.19)
		(layer "B.Cu")
		(net 519)
	)
	(segment
		(start 94.435 87.27337)
		(end 94.435 85.42337)
		(width 0.19)
		(layer "B.Cu")
		(net 519)
	)
	(arc
		(start 98.409672 120.559461)
		(mid 98.53978 120.505569)
		(end 98.669888 120.559461)
		(width 0.19)
		(layer "B.Cu")
		(net 519)
	)
	(arc
		(start 98.544021 121.344349)
		(mid 98.597914 121.214241)
		(end 98.544022 121.084133)
		(width 0.19)
		(layer "B.Cu")
		(net 519)
	)
	(arc
		(start 98.344618 120.884729)
		(mid 98.290726 120.754621)
		(end 98.344617 120.624515)
		(width 0.19)
		(layer "B.Cu")
		(net 519)
	)
	(arc
		(start 98.869293 120.758866)
		(mid 98.9994 120.812759)
		(end 99.129507 120.758867)
		(width 0.19)
		(layer "B.Cu")
		(net 519)
	)
	(segment
		(start 91.791631 122.469999)
		(end 93.22 122.469999)
		(width 0.19)
		(layer "B.Cu")
		(net 520)
	)
	(segment
		(start 87.50663 126.755)
		(end 91.791631 122.469999)
		(width 0.19)
		(layer "B.Cu")
		(net 520)
	)
	(segment
		(start 86.385532 126.755)
		(end 87.50663 126.755)
		(width 0.19)
		(layer "B.Cu")
		(net 520)
	)
	(segment
		(start 93.22 122.469999)
		(end 93.52 122.769999)
		(width 0.19)
		(layer "B.Cu")
		(net 520)
	)
	(segment
		(start 85.935532 127.205)
		(end 86.385532 126.755)
		(width 0.19)
		(layer "B.Cu")
		(net 520)
	)
	(segment
		(start 96.951 56.049)
		(end 97.27 55.73)
		(width 0.1)
		(layer "B.Cu")
		(net 521)
	)
	(segment
		(start 96.4 56.049)
		(end 96.951 56.049)
		(width 0.1)
		(layer "B.Cu")
		(net 521)
	)
	(segment
		(start 97.27 55.73)
		(end 97.27 54.5)
		(width 0.1)
		(layer "B.Cu")
		(net 521)
	)
	(via
		(at 204.5 85.6)
		(size 0.45)
		(drill 0.1)
		(layers "F.Cu" "B.Cu")
		(free yes)
		(net 522)
	)
	(via
		(at 204.25 85.1)
		(size 0.45)
		(drill 0.1)
		(layers "F.Cu" "B.Cu")
		(free yes)
		(net 522)
	)
	(via
		(at 203.65 85.1)
		(size 0.45)
		(drill 0.1)
		(layers "F.Cu" "B.Cu")
		(free yes)
		(net 522)
	)
	(via
		(at 202.9 85.1)
		(size 0.45)
		(drill 0.1)
		(layers "F.Cu" "B.Cu")
		(free yes)
		(net 522)
	)
	(via
		(at 205.1 85.6)
		(size 0.45)
		(drill 0.1)
		(layers "F.Cu" "B.Cu")
		(free yes)
		(net 522)
	)
	(via
		(at 203.9 85.6)
		(size 0.45)
		(drill 0.1)
		(layers "F.Cu" "B.Cu")
		(free yes)
		(net 522)
	)
	(via
		(at 202.15 85.1)
		(size 0.45)
		(drill 0.1)
		(layers "F.Cu" "B.Cu")
		(free yes)
		(net 522)
	)
	(via
		(at 204.85 85.1)
		(size 0.45)
		(drill 0.1)
		(layers "F.Cu" "B.Cu")
		(free yes)
		(net 522)
	)
	(segment
		(start 179.4 87.8)
		(end 180.368 87.8)
		(width 0.1)
		(layer "B.Cu")
		(net 522)
	)
	(segment
		(start 178.2 89.4)
		(end 178.4 89.2)
		(width 0.1)
		(layer "B.Cu")
		(net 522)
	)
	(segment
		(start 178.15 91.954)
		(end 177.554 91.954)
		(width 0.1)
		(layer "B.Cu")
		(net 522)
	)
	(segment
		(start 178.4 88.5)
		(end 178.8 88.1)
		(width 0.1)
		(layer "B.Cu")
		(net 522)
	)
	(segment
		(start 177.7 89.4)
		(end 178.2 89.4)
		(width 0.1)
		(layer "B.Cu")
		(net 522)
	)
	(segment
		(start 179.1 88.1)
		(end 179.4 87.8)
		(width 0.1)
		(layer "B.Cu")
		(net 522)
	)
	(segment
		(start 177.4 89.7)
		(end 177.7 89.4)
		(width 0.1)
		(layer "B.Cu")
		(net 522)
	)
	(segment
		(start 180.368 87.8)
		(end 180.464 87.704)
		(width 0.1)
		(layer "B.Cu")
		(net 522)
	)
	(segment
		(start 177.4 91.8)
		(end 177.4 89.7)
		(width 0.1)
		(layer "B.Cu")
		(net 522)
	)
	(segment
		(start 178.8 88.1)
		(end 179.1 88.1)
		(width 0.1)
		(layer "B.Cu")
		(net 522)
	)
	(segment
		(start 177.554 91.954)
		(end 177.4 91.8)
		(width 0.1)
		(layer "B.Cu")
		(net 522)
	)
	(segment
		(start 178.15 91.954)
		(end 178.15 92.84)
		(width 0.2)
		(layer "B.Cu")
		(net 522)
	)
	(segment
		(start 178.15 92.84)
		(end 177.89 93.1)
		(width 0.2)
		(layer "B.Cu")
		(net 522)
	)
	(segment
		(start 178.4 89.2)
		(end 178.4 88.5)
		(width 0.1)
		(layer "B.Cu")
		(net 522)
	)
	(segment
		(start 204.27 86.970856)
		(end 204.245 86.970856)
		(width 0.19)
		(layer "F.Cu")
		(net 523)
	)
	(segment
		(start 204.245 86.970856)
		(end 203.93 87.285856)
		(width 0.19)
		(layer "F.Cu")
		(net 523)
	)
	(segment
		(start 203.93 87.285856)
		(end 202.715 87.285856)
		(width 0.19)
		(layer "F.Cu")
		(net 523)
	)
	(segment
		(start 202.715 87.285856)
		(end 202.6 87.170856)
		(width 0.19)
		(layer "F.Cu")
		(net 523)
	)
	(via
		(at 202.6 87.170856)
		(size 0.45)
		(drill 0.1)
		(layers "F.Cu" "B.Cu")
		(net 523)
	)
	(via
		(at 134.330532 81.15)
		(size 0.45)
		(drill 0.1)
		(layers "F.Cu" "B.Cu")
		(net 523)
	)
	(segment
		(start 196.334177 87.95505)
		(end 196.334177 86.936682)
		(width 0.15)
		(layer "In7.Cu")
		(net 523)
	)
	(segment
		(start 194.934177 87.955052)
		(end 194.934177 86.936682)
		(width 0.15)
		(layer "In7.Cu")
		(net 523)
	)
	(segment
		(start 195.909177 86.936682)
		(end 195.909177 87.95505)
		(width 0.15)
		(layer "In7.Cu")
		(net 523)
	)
	(segment
		(start 135.043044 80.2625)
		(end 145.506956 80.2625)
		(width 0.15)
		(layer "In7.Cu")
		(net 523)
	)
	(segment
		(start 196.051677 88.09755)
		(end 196.191677 88.09755)
		(width 0.15)
		(layer "In7.Cu")
		(net 523)
	)
	(segment
		(start 196.751677 86.519182)
		(end 196.891677 86.519182)
		(width 0.15)
		(layer "In7.Cu")
		(net 523)
	)
	(segment
		(start 195.351677 86.519182)
		(end 195.491677 86.519182)
		(width 0.15)
		(layer "In7.Cu")
		(net 523)
	)
	(segment
		(start 149.627812 87.333356)
		(end 194.091677 87.333356)
		(width 0.15)
		(layer "In7.Cu")
		(net 523)
	)
	(segment
		(start 134.643032 80.662512)
		(end 135.043044 80.2625)
		(width 0.15)
		(layer "In7.Cu")
		(net 523)
	)
	(segment
		(start 197.451677 87.333356)
		(end 202.4375 87.333356)
		(width 0.15)
		(layer "In7.Cu")
		(net 523)
	)
	(segment
		(start 134.643032 80.8375)
		(end 134.643032 80.662512)
		(width 0.15)
		(layer "In7.Cu")
		(net 523)
	)
	(segment
		(start 134.330532 81.15)
		(end 134.643032 80.8375)
		(width 0.15)
		(layer "In7.Cu")
		(net 523)
	)
	(segment
		(start 194.509177 87.750856)
		(end 194.509177 87.955052)
		(width 0.15)
		(layer "In7.Cu")
		(net 523)
	)
	(segment
		(start 197.309177 86.936682)
		(end 197.309177 87.190856)
		(width 0.15)
		(layer "In7.Cu")
		(net 523)
	)
	(segment
		(start 202.4375 87.333356)
		(end 202.6 87.170856)
		(width 0.15)
		(layer "In7.Cu")
		(net 523)
	)
	(segment
		(start 145.506956 80.2625)
		(end 147.4375 82.193044)
		(width 0.15)
		(layer "In7.Cu")
		(net 523)
	)
	(segment
		(start 194.651677 88.097552)
		(end 194.791677 88.097552)
		(width 0.15)
		(layer "In7.Cu")
		(net 523)
	)
	(segment
		(start 147.4375 85.143044)
		(end 149.627812 87.333356)
		(width 0.15)
		(layer "In7.Cu")
		(net 523)
	)
	(segment
		(start 147.4375 82.193044)
		(end 147.4375 85.143044)
		(width 0.15)
		(layer "In7.Cu")
		(net 523)
	)
	(arc
		(start 196.191677 88.09755)
		(mid 196.29244 88.055813)
		(end 196.334177 87.95505)
		(width 0.15)
		(layer "In7.Cu")
		(net 523)
	)
	(arc
		(start 197.309177 87.190856)
		(mid 197.350914 87.291619)
		(end 197.451677 87.333356)
		(width 0.15)
		(layer "In7.Cu")
		(net 523)
	)
	(arc
		(start 195.491677 86.519182)
		(mid 195.786894 86.641465)
		(end 195.909177 86.936682)
		(width 0.15)
		(layer "In7.Cu")
		(net 523)
	)
	(arc
		(start 196.891677 86.519182)
		(mid 197.186894 86.641465)
		(end 197.309177 86.936682)
		(width 0.15)
		(layer "In7.Cu")
		(net 523)
	)
	(arc
		(start 194.509177 87.955052)
		(mid 194.550914 88.055815)
		(end 194.651677 88.097552)
		(width 0.15)
		(layer "In7.Cu")
		(net 523)
	)
	(arc
		(start 194.791677 88.097552)
		(mid 194.89244 88.055815)
		(end 194.934177 87.955052)
		(width 0.15)
		(layer "In7.Cu")
		(net 523)
	)
	(arc
		(start 194.934177 86.936682)
		(mid 195.05646 86.641465)
		(end 195.351677 86.519182)
		(width 0.15)
		(layer "In7.Cu")
		(net 523)
	)
	(arc
		(start 195.909177 87.95505)
		(mid 195.950914 88.055813)
		(end 196.051677 88.09755)
		(width 0.15)
		(layer "In7.Cu")
		(net 523)
	)
	(arc
		(start 196.334177 86.936682)
		(mid 196.45646 86.641465)
		(end 196.751677 86.519182)
		(width 0.15)
		(layer "In7.Cu")
		(net 523)
	)
	(arc
		(start 194.091677 87.333356)
		(mid 194.386894 87.455639)
		(end 194.509177 87.750856)
		(width 0.15)
		(layer "In7.Cu")
		(net 523)
	)
	(segment
		(start 94.48 59.5)
		(end 94.48 60.5)
		(width 0.1)
		(layer "F.Cu")
		(net 524)
	)
	(segment
		(start 95.4 60.4)
		(end 94.58 60.4)
		(width 0.1)
		(layer "F.Cu")
		(net 524)
	)
	(segment
		(start 94.58 60.4)
		(end 94.48 60.5)
		(width 0.1)
		(layer "F.Cu")
		(net 524)
	)
	(via
		(at 95.4 60.4)
		(size 0.45)
		(drill 0.1)
		(layers "F.Cu" "B.Cu")
		(net 524)
	)
	(segment
		(start 97.098 60.25)
		(end 95.55 60.25)
		(width 0.1)
		(layer "B.Cu")
		(net 524)
	)
	(segment
		(start 95.55 60.25)
		(end 95.4 60.4)
		(width 0.1)
		(layer "B.Cu")
		(net 524)
	)
	(via
		(at 209.6 76.2)
		(size 0.45)
		(drill 0.1)
		(layers "F.Cu" "B.Cu")
		(free yes)
		(net 525)
	)
	(via
		(at 209.6 77.4)
		(size 0.45)
		(drill 0.1)
		(layers "F.Cu" "B.Cu")
		(free yes)
		(net 525)
	)
	(via
		(at 209 76.2)
		(size 0.45)
		(drill 0.1)
		(layers "F.Cu" "B.Cu")
		(free yes)
		(net 525)
	)
	(via
		(at 209.6 75.6)
		(size 0.45)
		(drill 0.1)
		(layers "F.Cu" "B.Cu")
		(free yes)
		(net 525)
	)
	(via
		(at 209 75.6)
		(size 0.45)
		(drill 0.1)
		(layers "F.Cu" "B.Cu")
		(free yes)
		(net 525)
	)
	(via
		(at 209 76.8)
		(size 0.45)
		(drill 0.1)
		(layers "F.Cu" "B.Cu")
		(free yes)
		(net 525)
	)
	(via
		(at 209.6 76.8)
		(size 0.45)
		(drill 0.1)
		(layers "F.Cu" "B.Cu")
		(free yes)
		(net 525)
	)
	(via
		(at 209 77.4)
		(size 0.45)
		(drill 0.1)
		(layers "F.Cu" "B.Cu")
		(free yes)
		(net 525)
	)
	(segment
		(start 177.88 82.5)
		(end 178.145 82.235)
		(width 0.2)
		(layer "B.Cu")
		(net 525)
	)
	(segment
		(start 178.816 81.334)
		(end 179.65 80.5)
		(width 0.1)
		(layer "B.Cu")
		(net 525)
	)
	(segment
		(start 179.65 79.05)
		(end 179.85 78.85)
		(width 0.1)
		(layer "B.Cu")
		(net 525)
	)
	(segment
		(start 179.85 78.85)
		(end 180.09 78.85)
		(width 0.1)
		(layer "B.Cu")
		(net 525)
	)
	(segment
		(start 179.65 80.5)
		(end 179.65 79.05)
		(width 0.1)
		(layer "B.Cu")
		(net 525)
	)
	(segment
		(start 178.145 81.334)
		(end 178.816 81.334)
		(width 0.1)
		(layer "B.Cu")
		(net 525)
	)
	(segment
		(start 180.09 78.85)
		(end 180.765 78.175)
		(width 0.1)
		(layer "B.Cu")
		(net 525)
	)
	(segment
		(start 178.145 82.235)
		(end 178.145 81.334)
		(width 0.2)
		(layer "B.Cu")
		(net 525)
	)
	(via
		(at 168.5 56.01)
		(size 0.45)
		(drill 0.1)
		(layers "F.Cu" "B.Cu")
		(net 526)
	)
	(segment
		(start 168.5 56)
		(end 168.5 57.02)
		(width 0.1)
		(layer "B.Cu")
		(net 526)
	)
	(segment
		(start 213.52 132.72)
		(end 212.6 131.8)
		(width 0.1)
		(layer "F.Cu")
		(net 527)
	)
	(segment
		(start 212.6 131.8)
		(end 212.6 131)
		(width 0.1)
		(layer "F.Cu")
		(net 527)
	)
	(segment
		(start 213.52 133.8)
		(end 213.52 132.8)
		(width 0.1)
		(layer "F.Cu")
		(net 527)
	)
	(segment
		(start 212.6 131)
		(end 212.101 130.501)
		(width 0.1)
		(layer "F.Cu")
		(net 527)
	)
	(segment
		(start 213.52 132.8)
		(end 213.52 132.72)
		(width 0.1)
		(layer "F.Cu")
		(net 527)
	)
	(segment
		(start 212.101 130.501)
		(end 211.142 130.501)
		(width 0.1)
		(layer "F.Cu")
		(net 527)
	)
	(via
		(at 184.25 56)
		(size 0.45)
		(drill 0.1)
		(layers "F.Cu" "B.Cu")
		(net 528)
	)
	(segment
		(start 184.25 56)
		(end 184.25 57.02)
		(width 0.1)
		(layer "B.Cu")
		(net 528)
	)
	(via
		(at 179.75 56.05)
		(size 0.45)
		(drill 0.1)
		(layers "F.Cu" "B.Cu")
		(net 529)
	)
	(segment
		(start 179.75 56)
		(end 179.75 57.02)
		(width 0.1)
		(layer "B.Cu")
		(net 529)
	)
	(segment
		(start 191.376 140.1)
		(end 192.546 140.1)
		(width 0.1)
		(layer "F.Cu")
		(net 530)
	)
	(segment
		(start 199.4 97.84)
		(end 199.4 95.500999)
		(width 0.1)
		(layer "F.Cu")
		(net 531)
	)
	(segment
		(start 198.9 98.34)
		(end 199.4 97.84)
		(width 0.1)
		(layer "F.Cu")
		(net 531)
	)
	(segment
		(start 199.4 95.500999)
		(end 198.999001 95.1)
		(width 0.1)
		(layer "F.Cu")
		(net 531)
	)
	(segment
		(start 197.7 96.4)
		(end 197.7 95.201)
		(width 0.1)
		(layer "F.Cu")
		(net 532)
	)
	(segment
		(start 197.7 95.201)
		(end 197.599 95.1)
		(width 0.1)
		(layer "F.Cu")
		(net 532)
	)
	(via
		(at 194.2 101.1)
		(size 0.45)
		(drill 0.1)
		(layers "F.Cu" "B.Cu")
		(net 532)
	)
	(via
		(at 197.7 96.4)
		(size 0.45)
		(drill 0.1)
		(layers "F.Cu" "B.Cu")
		(net 532)
	)
	(segment
		(start 197.035 97)
		(end 197.035 98.365)
		(width 0.1)
		(layer "B.Cu")
		(net 532)
	)
	(segment
		(start 197.035 98.365)
		(end 196.6 98.8)
		(width 0.1)
		(layer "B.Cu")
		(net 532)
	)
	(segment
		(start 193.9 93)
		(end 193.9 90)
		(width 0.1)
		(layer "B.Cu")
		(net 532)
	)
	(segment
		(start 194.2 101.1)
		(end 194.2 101.448526)
		(width 0.1)
		(layer "B.Cu")
		(net 532)
	)
	(segment
		(start 193.299999 121.275739)
		(end 191.475738 123.1)
		(width 0.1)
		(layer "B.Cu")
		(net 532)
	)
	(segment
		(start 194.2 101.448526)
		(end 193.299999 102.348527)
		(width 0.1)
		(layer "B.Cu")
		(net 532)
	)
	(segment
		(start 196.6 98.8)
		(end 192.3 98.8)
		(width 0.1)
		(layer "B.Cu")
		(net 532)
	)
	(segment
		(start 191.5 95.4)
		(end 193.9 93)
		(width 0.1)
		(layer "B.Cu")
		(net 532)
	)
	(segment
		(start 189.3 123.1)
		(end 188.9 122.7)
		(width 0.1)
		(layer "B.Cu")
		(net 532)
	)
	(segment
		(start 193.9 90)
		(end 194.8 89.1)
		(width 0.1)
		(layer "B.Cu")
		(net 532)
	)
	(segment
		(start 194.8 89.1)
		(end 194.8 88.28)
		(width 0.1)
		(layer "B.Cu")
		(net 532)
	)
	(segment
		(start 188.9 122.7)
		(end 188.9 122.18)
		(width 0.1)
		(layer "B.Cu")
		(net 532)
	)
	(segment
		(start 192.3 98.8)
		(end 191.5 98)
		(width 0.1)
		(layer "B.Cu")
		(net 532)
	)
	(segment
		(start 191.475738 123.1)
		(end 189.3 123.1)
		(width 0.1)
		(layer "B.Cu")
		(net 532)
	)
	(segment
		(start 191.5 98)
		(end 191.5 95.4)
		(width 0.1)
		(layer "B.Cu")
		(net 532)
	)
	(segment
		(start 193.299999 102.348527)
		(end 193.299999 121.275739)
		(width 0.1)
		(layer "B.Cu")
		(net 532)
	)
	(segment
		(start 197.669 96.366)
		(end 197.035 97)
		(width 0.1)
		(layer "B.Cu")
		(net 532)
	)
	(segment
		(start 194.2 101.1)
		(end 197.7 97.6)
		(width 0.1)
		(layer "In5.Cu")
		(net 532)
	)
	(segment
		(start 197.7 97.6)
		(end 197.7 96.4)
		(width 0.1)
		(layer "In5.Cu")
		(net 532)
	)
	(segment
		(start 196.35 86.4)
		(end 196.35 87.34)
		(width 0.1)
		(layer "F.Cu")
		(net 533)
	)
	(segment
		(start 196.35 87.34)
		(end 196.17 87.52)
		(width 0.1)
		(layer "F.Cu")
		(net 533)
	)
	(segment
		(start 197.38 86.4)
		(end 197.38 87.35)
		(width 0.1)
		(layer "F.Cu")
		(net 534)
	)
	(segment
		(start 197.38 87.35)
		(end 197.55 87.52)
		(width 0.1)
		(layer "F.Cu")
		(net 534)
	)
	(segment
		(start 221.105 73.599951)
		(end 221.26 73.444951)
		(width 0.1)
		(layer "F.Cu")
		(net 535)
	)
	(segment
		(start 220.08 73.599951)
		(end 221.105 73.599951)
		(width 0.1)
		(layer "F.Cu")
		(net 535)
	)
	(segment
		(start 222.705 73.1)
		(end 222.66 73.145)
		(width 0.1)
		(layer "F.Cu")
		(net 536)
	)
	(segment
		(start 222.66 73.145)
		(end 222.66 73.444951)
		(width 0.1)
		(layer "F.Cu")
		(net 536)
	)
	(segment
		(start 223.5 73.1)
		(end 222.705 73.1)
		(width 0.1)
		(layer "F.Cu")
		(net 536)
	)
	(via
		(at 223.5 73.1)
		(size 0.45)
		(drill 0.1)
		(layers "F.Cu" "B.Cu")
		(net 536)
	)
	(segment
		(start 223.5 76.6)
		(end 223.5 73.1)
		(width 0.1)
		(layer "B.Cu")
		(net 536)
	)
	(segment
		(start 222.735 77.365)
		(end 223.5 76.6)
		(width 0.1)
		(layer "B.Cu")
		(net 536)
	)
	(segment
		(start 221.9 77.365)
		(end 222.735 77.365)
		(width 0.1)
		(layer "B.Cu")
		(net 536)
	)
	(segment
		(start 221.7 76.4)
		(end 221.8 76.3)
		(width 0.1)
		(layer "F.Cu")
		(net 537)
	)
	(segment
		(start 222.83 75.27)
		(end 222.83 74.869951)
		(width 0.1)
		(layer "F.Cu")
		(net 537)
	)
	(segment
		(start 221.8 76.3)
		(end 222.83 75.27)
		(width 0.1)
		(layer "F.Cu")
		(net 537)
	)
	(segment
		(start 220.6 75.3)
		(end 221.6 76.3)
		(width 0.1)
		(layer "F.Cu")
		(net 537)
	)
	(segment
		(start 214.8 74.1)
		(end 216.5 74.1)
		(width 0.1)
		(layer "F.Cu")
		(net 537)
	)
	(segment
		(start 219.65 81.2)
		(end 219.65 78.45)
		(width 0.1)
		(layer "F.Cu")
		(net 537)
	)
	(segment
		(start 221.6 76.3)
		(end 221.6 76.5)
		(width 0.1)
		(layer "F.Cu")
		(net 537)
	)
	(segment
		(start 221.6 76.5)
		(end 221.7 76.4)
		(width 0.1)
		(layer "F.Cu")
		(net 537)
	)
	(segment
		(start 221.6 76.3)
		(end 221.7 76.4)
		(width 0.1)
		(layer "F.Cu")
		(net 537)
	)
	(segment
		(start 214.5 74.4)
		(end 214.8 74.1)
		(width 0.1)
		(layer "F.Cu")
		(net 537)
	)
	(segment
		(start 219.65 78.45)
		(end 221.6 76.5)
		(width 0.1)
		(layer "F.Cu")
		(net 537)
	)
	(segment
		(start 216.5 74.1)
		(end 217.7 75.3)
		(width 0.1)
		(layer "F.Cu")
		(net 537)
	)
	(segment
		(start 221.6 76.3)
		(end 221.8 76.3)
		(width 0.1)
		(layer "F.Cu")
		(net 537)
	)
	(segment
		(start 217.7 75.3)
		(end 220.6 75.3)
		(width 0.1)
		(layer "F.Cu")
		(net 537)
	)
	(via
		(at 219.65 81.2)
		(size 0.45)
		(drill 0.1)
		(layers "F.Cu" "B.Cu")
		(net 537)
	)
	(via
		(at 214.5 74.4)
		(size 0.45)
		(drill 0.1)
		(layers "F.Cu" "B.Cu")
		(net 537)
	)
	(segment
		(start 214.45 75.202)
		(end 214.45 74.45)
		(width 0.1)
		(layer "B.Cu")
		(net 537)
	)
	(segment
		(start 214.45 74.45)
		(end 214.5 74.4)
		(width 0.1)
		(layer "B.Cu")
		(net 537)
	)
	(segment
		(start 219.675 80.24)
		(end 219.675 81.175)
		(width 0.1)
		(layer "B.Cu")
		(net 537)
	)
	(segment
		(start 219.675 81.175)
		(end 219.65 81.2)
		(width 0.1)
		(layer "B.Cu")
		(net 537)
	)
	(segment
		(start 221.09 74.699951)
		(end 221.26 74.869951)
		(width 0.1)
		(layer "F.Cu")
		(net 538)
	)
	(segment
		(start 220.08 74.699951)
		(end 221.09 74.699951)
		(width 0.1)
		(layer "F.Cu")
		(net 538)
	)
	(segment
		(start 223.98 54.75)
		(end 225.3 54.75)
		(width 0.1)
		(layer "B.Cu")
		(net 539)
	)
	(segment
		(start 223.98 56.25)
		(end 225.27 56.25)
		(width 0.1)
		(layer "B.Cu")
		(net 540)
	)
	(segment
		(start 225.27 56.25)
		(end 225.28 56.26)
		(width 0.1)
		(layer "B.Cu")
		(net 540)
	)
	(segment
		(start 62.8 85.52)
		(end 62.8 84.67)
		(width 0.1)
		(layer "B.Cu")
		(net 541)
	)
	(segment
		(start 62.2 84.07)
		(end 62.2 83.92)
		(width 0.1)
		(layer "B.Cu")
		(net 541)
	)
	(segment
		(start 62.8 84.67)
		(end 62.2 84.07)
		(width 0.1)
		(layer "B.Cu")
		(net 541)
	)
	(segment
		(start 61.6 85.52)
		(end 61.6 85)
		(width 0.1)
		(layer "B.Cu")
		(net 542)
	)
	(segment
		(start 61.4 83.16)
		(end 62.05 82.51)
		(width 0.1)
		(layer "B.Cu")
		(net 542)
	)
	(segment
		(start 61.4 84.8)
		(end 61.4 83.16)
		(width 0.1)
		(layer "B.Cu")
		(net 542)
	)
	(segment
		(start 61.6 85)
		(end 61.4 84.8)
		(width 0.1)
		(layer "B.Cu")
		(net 542)
	)
	(segment
		(start 62.05 82.51)
		(end 62.2 82.51)
		(width 0.1)
		(layer "B.Cu")
		(net 542)
	)
	(segment
		(start 191.386 149.7)
		(end 192.546 149.7)
		(width 0.1)
		(layer "F.Cu")
		(net 543)
	)
	(segment
		(start 114.17 116.59)
		(end 115.29 116.59)
		(width 0.1)
		(layer "B.Cu")
		(net 544)
	)
	(segment
		(start 115.29 116.59)
		(end 115.3 116.58)
		(width 0.1)
		(layer "B.Cu")
		(net 544)
	)
	(segment
		(start 110.015 140.06)
		(end 110.015 138.93)
		(width 0.1)
		(layer "B.Cu")
		(net 545)
	)
	(segment
		(start 110.015 138.93)
		(end 109.995 138.91)
		(width 0.1)
		(layer "B.Cu")
		(net 545)
	)
	(segment
		(start 108.555 140.07)
		(end 108.555 138.91)
		(width 0.1)
		(layer "B.Cu")
		(net 546)
	)
	(segment
		(start 133.2 56)
		(end 133.2 57.12)
		(width 0.1)
		(layer "B.Cu")
		(net 547)
	)
	(segment
		(start 133.2 57.12)
		(end 134.6 58.52)
		(width 0.1)
		(layer "B.Cu")
		(net 547)
	)
	(segment
		(start 140.4 56.8)
		(end 141.3 57.7)
		(width 0.1)
		(layer "B.Cu")
		(net 548)
	)
	(segment
		(start 134.7 56)
		(end 134.8 56)
		(width 0.1)
		(layer "B.Cu")
		(net 548)
	)
	(segment
		(start 141.3 57.7)
		(end 141.3 60.62)
		(width 0.1)
		(layer "B.Cu")
		(net 548)
	)
	(segment
		(start 135.6 56.8)
		(end 140.4 56.8)
		(width 0.1)
		(layer "B.Cu")
		(net 548)
	)
	(segment
		(start 134.8 56)
		(end 135.6 56.8)
		(width 0.1)
		(layer "B.Cu")
		(net 548)
	)
	(segment
		(start 68.750532 56.54)
		(end 67.791532 56.54)
		(width 0.1)
		(layer "F.Cu")
		(net 549)
	)
	(segment
		(start 67.791532 56.54)
		(end 67.500532 56.249)
		(width 0.1)
		(layer "F.Cu")
		(net 549)
	)
	(segment
		(start 70.75 55.098)
		(end 68.792532 55.098)
		(width 0.1)
		(layer "F.Cu")
		(net 550)
	)
	(segment
		(start 68.792532 55.098)
		(end 68.750532 55.14)
		(width 0.1)
		(layer "F.Cu")
		(net 550)
	)
	(segment
		(start 110.695532 82.915)
		(end 110.695532 83.485)
		(width 0.19)
		(layer "F.Cu")
		(net 552)
	)
	(segment
		(start 110.695532 83.485)
		(end 110.580532 83.6)
		(width 0.19)
		(layer "F.Cu")
		(net 552)
	)
	(segment
		(start 110.430532 82.65)
		(end 110.695532 82.915)
		(width 0.19)
		(layer "F.Cu")
		(net 552)
	)
	(via
		(at 110.580532 83.6)
		(size 0.45)
		(drill 0.1)
		(layers "F.Cu" "B.Cu")
		(net 552)
	)
	(segment
		(start 108.583476 99.684)
		(end 106.831 97.931524)
		(width 0.19)
		(layer "B.Cu")
		(net 552)
	)
	(segment
		(start 110.695532 83.715)
		(end 110.580532 83.6)
		(width 0.19)
		(layer "B.Cu")
		(net 552)
	)
	(segment
		(start 111.02337 88.115)
		(end 111.415 87.72337)
		(width 0.19)
		(layer "B.Cu")
		(net 552)
	)
	(segment
		(start 111.415 87.72337)
		(end 111.415 85.27663)
		(width 0.19)
		(layer "B.Cu")
		(net 552)
	)
	(segment
		(start 111.415 85.27663)
		(end 110.695532 84.557162)
		(width 0.19)
		(layer "B.Cu")
		(net 552)
	)
	(segment
		(start 110.695532 84.557162)
		(end 110.695532 83.715)
		(width 0.19)
		(layer "B.Cu")
		(net 552)
	)
	(segment
		(start 106.831 91.40737)
		(end 110.12337 88.115)
		(width 0.19)
		(layer "B.Cu")
		(net 552)
	)
	(segment
		(start 110.12337 88.115)
		(end 111.02337 88.115)
		(width 0.19)
		(layer "B.Cu")
		(net 552)
	)
	(segment
		(start 112.995 99.684)
		(end 108.583476 99.684)
		(width 0.19)
		(layer "B.Cu")
		(net 552)
	)
	(segment
		(start 113.06 99.749)
		(end 112.995 99.684)
		(width 0.19)
		(layer "B.Cu")
		(net 552)
	)
	(segment
		(start 113.685 99.749)
		(end 113.06 99.749)
		(width 0.19)
		(layer "B.Cu")
		(net 552)
	)
	(segment
		(start 106.831 97.931524)
		(end 106.831 91.40737)
		(width 0.19)
		(layer "B.Cu")
		(net 552)
	)
	(segment
		(start 212.115631 91.572856)
		(end 212.099631 91.556856)
		(width 0.19)
		(layer "F.Cu")
		(net 553)
	)
	(segment
		(start 207.255 92.470856)
		(end 207.23 92.470856)
		(width 0.19)
		(layer "F.Cu")
		(net 553)
	)
	(segment
		(start 208.90163 91.86)
		(end 208.605774 92.155856)
		(width 0.19)
		(layer "F.Cu")
		(net 553)
	)
	(segment
		(start 211.60163 91.86)
		(end 208.90163 91.86)
		(width 0.19)
		(layer "F.Cu")
		(net 553)
	)
	(segment
		(start 212.565632 91.572856)
		(end 212.115631 91.572856)
		(width 0.19)
		(layer "F.Cu")
		(net 553)
	)
	(segment
		(start 208.605774 92.155856)
		(end 207.57 92.155856)
		(width 0.19)
		(layer "F.Cu")
		(net 553)
	)
	(segment
		(start 207.57 92.155856)
		(end 207.255 92.470856)
		(width 0.19)
		(layer "F.Cu")
		(net 553)
	)
	(segment
		(start 212.099631 91.556856)
		(end 211.904774 91.556856)
		(width 0.19)
		(layer "F.Cu")
		(net 553)
	)
	(segment
		(start 211.904774 91.556856)
		(end 211.60163 91.86)
		(width 0.19)
		(layer "F.Cu")
		(net 553)
	)
	(segment
		(start 94.630532 81.15)
		(end 94.65 81.15)
		(width 0.1)
		(layer "F.Cu")
		(net 554)
	)
	(via
		(at 94.65 81.15)
		(size 0.45)
		(drill 0.1)
		(layers "F.Cu" "B.Cu")
		(net 554)
	)
	(via
		(at 80.65 96.05)
		(size 0.45)
		(drill 0.1)
		(layers "F.Cu" "B.Cu")
		(net 554)
	)
	(segment
		(start 80.855532 95.455)
		(end 80.855532 95.844468)
		(width 0.1)
		(layer "B.Cu")
		(net 554)
	)
	(segment
		(start 80.855532 95.844468)
		(end 80.65 96.05)
		(width 0.1)
		(layer "B.Cu")
		(net 554)
	)
	(segment
		(start 84.665532 94.265532)
		(end 84.665532 92.915)
		(width 0.1)
		(layer "In5.Cu")
		(net 554)
	)
	(segment
		(start 82.15 96.05)
		(end 83.275 97.175)
		(width 0.1)
		(layer "In5.Cu")
		(net 554)
	)
	(segment
		(start 92.7 85.9)
		(end 94.1 84.5)
		(width 0.1)
		(layer "In5.Cu")
		(net 554)
	)
	(segment
		(start 86.45 98.1)
		(end 86.45 96.05)
		(width 0.1)
		(layer "In5.Cu")
		(net 554)
	)
	(segment
		(start 94.600001 83.1)
		(end 94.600001 82.7)
		(width 0.1)
		(layer "In5.Cu")
		(net 554)
	)
	(segment
		(start 94.1 82.199999)
		(end 94.1 81.7)
		(width 0.1)
		(layer "In5.Cu")
		(net 554)
	)
	(segment
		(start 84.665532 92.915)
		(end 85.880532 91.7)
		(width 0.1)
		(layer "In5.Cu")
		(net 554)
	)
	(segment
		(start 83.275 97.175)
		(end 83.975 97.175)
		(width 0.1)
		(layer "In5.Cu")
		(net 554)
	)
	(segment
		(start 85.880532 91.7)
		(end 87.3 91.7)
		(width 0.1)
		(layer "In5.Cu")
		(net 554)
	)
	(segment
		(start 83.975 97.175)
		(end 85.2 98.4)
		(width 0.1)
		(layer "In5.Cu")
		(net 554)
	)
	(segment
		(start 86.45 96.05)
		(end 84.665532 94.265532)
		(width 0.1)
		(layer "In5.Cu")
		(net 554)
	)
	(segment
		(start 85.2 98.4)
		(end 86.15 98.4)
		(width 0.1)
		(layer "In5.Cu")
		(net 554)
	)
	(segment
		(start 80.65 96.05)
		(end 82.15 96.05)
		(width 0.1)
		(layer "In5.Cu")
		(net 554)
	)
	(segment
		(start 94.600001 82.7)
		(end 94.1 82.199999)
		(width 0.1)
		(layer "In5.Cu")
		(net 554)
	)
	(segment
		(start 92.7 86.3)
		(end 92.7 85.9)
		(width 0.1)
		(layer "In5.Cu")
		(net 554)
	)
	(segment
		(start 94.1 84.5)
		(end 94.1 83.600001)
		(width 0.1)
		(layer "In5.Cu")
		(net 554)
	)
	(segment
		(start 94.1 83.600001)
		(end 94.600001 83.1)
		(width 0.1)
		(layer "In5.Cu")
		(net 554)
	)
	(segment
		(start 86.15 98.4)
		(end 86.45 98.1)
		(width 0.1)
		(layer "In5.Cu")
		(net 554)
	)
	(segment
		(start 87.3 91.7)
		(end 92.7 86.3)
		(width 0.1)
		(layer "In5.Cu")
		(net 554)
	)
	(segment
		(start 94.1 81.7)
		(end 94.65 81.15)
		(width 0.1)
		(layer "In5.Cu")
		(net 554)
	)
	(segment
		(start 207.255 91.470856)
		(end 207.23 91.470856)
		(width 0.19)
		(layer "F.Cu")
		(net 557)
	)
	(segment
		(start 208.74837 91.49)
		(end 208.452514 91.785856)
		(width 0.19)
		(layer "F.Cu")
		(net 557)
	)
	(segment
		(start 212.565632 91.170856)
		(end 212.115631 91.170856)
		(width 0.19)
		(layer "F.Cu")
		(net 557)
	)
	(segment
		(start 207.57 91.785856)
		(end 207.255 91.470856)
		(width 0.19)
		(layer "F.Cu")
		(net 557)
	)
	(segment
		(start 211.44837 91.49)
		(end 208.74837 91.49)
		(width 0.19)
		(layer "F.Cu")
		(net 557)
	)
	(segment
		(start 212.115631 91.170856)
		(end 212.099631 91.186856)
		(width 0.19)
		(layer "F.Cu")
		(net 557)
	)
	(segment
		(start 211.751514 91.186856)
		(end 211.44837 91.49)
		(width 0.19)
		(layer "F.Cu")
		(net 557)
	)
	(segment
		(start 212.099631 91.186856)
		(end 211.751514 91.186856)
		(width 0.19)
		(layer "F.Cu")
		(net 557)
	)
	(segment
		(start 208.452514 91.785856)
		(end 207.57 91.785856)
		(width 0.19)
		(layer "F.Cu")
		(net 557)
	)
	(segment
		(start 148.28 119.2)
		(end 150.27 119.2)
		(width 0.1)
		(layer "F.Cu")
		(net 561)
	)
	(segment
		(start 132.905 135.29)
		(end 132.905 134.105)
		(width 0.1)
		(layer "F.Cu")
		(net 561)
	)
	(segment
		(start 150.27 119.2)
		(end 150.28 119.21)
		(width 0.1)
		(layer "F.Cu")
		(net 561)
	)
	(segment
		(start 132.905 134.105)
		(end 132.8 134)
		(width 0.1)
		(layer "F.Cu")
		(net 561)
	)
	(segment
		(start 150.28 119.21)
		(end 150.32 119.25)
		(width 0.1)
		(layer "F.Cu")
		(net 561)
	)
	(segment
		(start 150.32 119.25)
		(end 151.231 119.25)
		(width 0.1)
		(layer "F.Cu")
		(net 561)
	)
	(via
		(at 132.8 134)
		(size 0.45)
		(drill 0.1)
		(layers "F.Cu" "B.Cu")
		(net 561)
	)
	(via
		(at 150.28 119.21)
		(size 0.45)
		(drill 0.1)
		(layers "F.Cu" "B.Cu")
		(net 561)
	)
	(via
		(at 80.855532 117.045)
		(size 0.45)
		(drill 0.1)
		(layers "F.Cu" "B.Cu")
		(net 561)
	)
	(segment
		(start 81.3 117.3)
		(end 81.3 118.9)
		(width 0.1)
		(layer "In7.Cu")
		(net 561)
	)
	(segment
		(start 132.9 134.1)
		(end 132.8 134)
		(width 0.1)
		(layer "In7.Cu")
		(net 561)
	)
	(segment
		(start 150.28 119.21)
		(end 150.22 119.27)
		(width 0.1)
		(layer "In7.Cu")
		(net 561)
	)
	(segment
		(start 81.3 118.9)
		(end 82.8 120.4)
		(width 0.1)
		(layer "In7.Cu")
		(net 561)
	)
	(segment
		(start 146.73 119.27)
		(end 142.482842 123.517158)
		(width 0.1)
		(layer "In7.Cu")
		(net 561)
	)
	(segment
		(start 132.317159 125.882843)
		(end 132.317159 133.517159)
		(width 0.1)
		(layer "In7.Cu")
		(net 561)
	)
	(segment
		(start 81.045 117.045)
		(end 81.3 117.3)
		(width 0.1)
		(layer "In7.Cu")
		(net 561)
	)
	(segment
		(start 132.9 135)
		(end 132.9 134.1)
		(width 0.1)
		(layer "In7.Cu")
		(net 561)
	)
	(segment
		(start 80.855532 117.045)
		(end 81.045 117.045)
		(width 0.1)
		(layer "In7.Cu")
		(net 561)
	)
	(segment
		(start 134.682844 123.517158)
		(end 132.317159 125.882843)
		(width 0.1)
		(layer "In7.Cu")
		(net 561)
	)
	(segment
		(start 131.800002 136.099998)
		(end 132.9 135)
		(width 0.1)
		(layer "In7.Cu")
		(net 561)
	)
	(segment
		(start 132.317159 133.517159)
		(end 132.8 134)
		(width 0.1)
		(layer "In7.Cu")
		(net 561)
	)
	(segment
		(start 87.4 124.55)
		(end 101.049998 138.199998)
		(width 0.1)
		(layer "In7.Cu")
		(net 561)
	)
	(segment
		(start 142.482842 123.517158)
		(end 134.682844 123.517158)
		(width 0.1)
		(layer "In7.Cu")
		(net 561)
	)
	(segment
		(start 119.724264 136.099998)
		(end 131.800002 136.099998)
		(width 0.1)
		(layer "In7.Cu")
		(net 561)
	)
	(segment
		(start 117.624264 138.199998)
		(end 119.724264 136.099998)
		(width 0.1)
		(layer "In7.Cu")
		(net 561)
	)
	(segment
		(start 150.22 119.27)
		(end 146.73 119.27)
		(width 0.1)
		(layer "In7.Cu")
		(net 561)
	)
	(segment
		(start 87.4 122.5)
		(end 87.4 124.55)
		(width 0.1)
		(layer "In7.Cu")
		(net 561)
	)
	(segment
		(start 101.049998 138.199998)
		(end 117.624264 138.199998)
		(width 0.1)
		(layer "In7.Cu")
		(net 561)
	)
	(segment
		(start 85.3 120.4)
		(end 87.4 122.5)
		(width 0.1)
		(layer "In7.Cu")
		(net 561)
	)
	(segment
		(start 82.8 120.4)
		(end 85.3 120.4)
		(width 0.1)
		(layer "In7.Cu")
		(net 561)
	)
	(segment
		(start 91.380532 85.1)
		(end 90.830532 85.65)
		(width 0.1)
		(layer "F.Cu")
		(net 563)
	)
	(segment
		(start 91.4 85.1)
		(end 91.380532 85.1)
		(width 0.1)
		(layer "F.Cu")
		(net 563)
	)
	(via
		(at 91.4 85.1)
		(size 0.45)
		(drill 0.1)
		(layers "F.Cu" "B.Cu")
		(net 563)
	)
	(segment
		(start 111.330532 85.65)
		(end 111.065532 85.915)
		(width 0.19)
		(layer "F.Cu")
		(net 564)
	)
	(segment
		(start 111.065532 90.585)
		(end 111.180532 90.7)
		(width 0.19)
		(layer "F.Cu")
		(net 564)
	)
	(segment
		(start 111.065532 85.915)
		(end 111.065532 90.585)
		(width 0.19)
		(layer "F.Cu")
		(net 564)
	)
	(via
		(at 111.180532 90.7)
		(size 0.45)
		(drill 0.1)
		(layers "F.Cu" "B.Cu")
		(net 564)
	)
	(segment
		(start 113.685 96.248)
		(end 113.06 96.248)
		(width 0.19)
		(layer "B.Cu")
		(net 564)
	)
	(segment
		(start 111.77513 96.3135)
		(end 111.065532 95.603902)
		(width 0.19)
		(layer "B.Cu")
		(net 564)
	)
	(segment
		(start 112.9945 96.3135)
		(end 111.77513 96.3135)
		(width 0.19)
		(layer "B.Cu")
		(net 564)
	)
	(segment
		(start 111.065532 93.308907)
		(end 111.065532 90.815)
		(width 0.19)
		(layer "B.Cu")
		(net 564)
	)
	(segment
		(start 113.06 96.248)
		(end 112.9945 96.3135)
		(width 0.19)
		(layer "B.Cu")
		(net 564)
	)
	(segment
		(start 111.578049 93.908907)
		(end 111.578049 93.788907)
		(width 0.19)
		(layer "B.Cu")
		(net 564)
	)
	(segment
		(start 111.338049 93.548907)
		(end 111.305532 93.548907)
		(width 0.19)
		(layer "B.Cu")
		(net 564)
	)
	(segment
		(start 111.065532 95.603902)
		(end 111.065532 94.388907)
		(width 0.19)
		(layer "B.Cu")
		(net 564)
	)
	(segment
		(start 111.065532 90.815)
		(end 111.180532 90.7)
		(width 0.19)
		(layer "B.Cu")
		(net 564)
	)
	(segment
		(start 111.305532 94.148907)
		(end 111.338049 94.148907)
		(width 0.19)
		(layer "B.Cu")
		(net 564)
	)
	(arc
		(start 111.305532 93.548907)
		(mid 111.135826 93.478613)
		(end 111.065532 93.308907)
		(width 0.19)
		(layer "B.Cu")
		(net 564)
	)
	(arc
		(start 111.338049 94.148907)
		(mid 111.507755 94.078613)
		(end 111.578049 93.908907)
		(width 0.19)
		(layer "B.Cu")
		(net 564)
	)
	(arc
		(start 111.578049 93.788907)
		(mid 111.507755 93.619201)
		(end 111.338049 93.548907)
		(width 0.19)
		(layer "B.Cu")
		(net 564)
	)
	(arc
		(start 111.065532 94.388907)
		(mid 111.135826 94.219201)
		(end 111.305532 94.148907)
		(width 0.19)
		(layer "B.Cu")
		(net 564)
	)
	(segment
		(start 91.4 77.6)
		(end 91.4 77.15)
		(width 0.1)
		(layer "F.Cu")
		(net 565)
	)
	(segment
		(start 92.230532 77.05)
		(end 92.630532 76.65)
		(width 0.1)
		(layer "F.Cu")
		(net 565)
	)
	(segment
		(start 91.39 77.61)
		(end 91.4 77.6)
		(width 0.1)
		(layer "F.Cu")
		(net 565)
	)
	(segment
		(start 91.5 77.05)
		(end 92.230532 77.05)
		(width 0.1)
		(layer "F.Cu")
		(net 565)
	)
	(segment
		(start 91.4 77.15)
		(end 91.5 77.05)
		(width 0.1)
		(layer "F.Cu")
		(net 565)
	)
	(via
		(at 91.39 77.61)
		(size 0.45)
		(drill 0.1)
		(layers "F.Cu" "B.Cu")
		(net 565)
	)
	(via
		(at 80.855532 91.645)
		(size 0.45)
		(drill 0.1)
		(layers "F.Cu" "B.Cu")
		(net 565)
	)
	(segment
		(start 88.575 82.975)
		(end 88.575 84.325)
		(width 0.1)
		(layer "In4.Cu")
		(net 565)
	)
	(segment
		(start 91.45 80.1)
		(end 88.575 82.975)
		(width 0.1)
		(layer "In4.Cu")
		(net 565)
	)
	(segment
		(start 88.575 84.325)
		(end 86.311532 86.588468)
		(width 0.1)
		(layer "In4.Cu")
		(net 565)
	)
	(segment
		(start 85.420532 88.35)
		(end 83.870532 89.9)
		(width 0.1)
		(layer "In4.Cu")
		(net 565)
	)
	(segment
		(start 81.8 89.9)
		(end 80.855532 90.844468)
		(width 0.1)
		(layer "In4.Cu")
		(net 565)
	)
	(segment
		(start 80.855532 90.844468)
		(end 80.855532 91.645)
		(width 0.1)
		(layer "In4.Cu")
		(net 565)
	)
	(segment
		(start 91.4 77.62)
		(end 91.4 77.95)
		(width 0.1)
		(layer "In4.Cu")
		(net 565)
	)
	(segment
		(start 91.45 78)
		(end 91.45 80.1)
		(width 0.1)
		(layer "In4.Cu")
		(net 565)
	)
	(segment
		(start 91.39 77.61)
		(end 91.4 77.62)
		(width 0.1)
		(layer "In4.Cu")
		(net 565)
	)
	(segment
		(start 86.311532 88.088468)
		(end 86.05 88.35)
		(width 0.1)
		(layer "In4.Cu")
		(net 565)
	)
	(segment
		(start 83.870532 89.9)
		(end 81.8 89.9)
		(width 0.1)
		(layer "In4.Cu")
		(net 565)
	)
	(segment
		(start 91.4 77.95)
		(end 91.45 78)
		(width 0.1)
		(layer "In4.Cu")
		(net 565)
	)
	(segment
		(start 86.05 88.35)
		(end 85.420532 88.35)
		(width 0.1)
		(layer "In4.Cu")
		(net 565)
	)
	(segment
		(start 86.311532 86.588468)
		(end 86.311532 88.088468)
		(width 0.1)
		(layer "In4.Cu")
		(net 565)
	)
	(via
		(at 125.130532 70.65)
		(size 0.45)
		(drill 0.1)
		(layers "F.Cu" "B.Cu")
		(net 566)
	)
	(segment
		(start 125.130532 70.65)
		(end 125.4 70.380532)
		(width 0.1)
		(layer "B.Cu")
		(net 566)
	)
	(segment
		(start 125.4 70.380532)
		(end 125.4 69.4)
		(width 0.1)
		(layer "B.Cu")
		(net 566)
	)
	(segment
		(start 171.24 132.64)
		(end 170.9 132.3)
		(width 0.1)
		(layer "F.Cu")
		(net 567)
	)
	(segment
		(start 182.508579 125.181421)
		(end 182.465 125.225)
		(width 0.2)
		(layer "F.Cu")
		(net 567)
	)
	(segment
		(start 182.453525 124.897019)
		(end 182.491706 124.897019)
		(width 0.2)
		(layer "F.Cu")
		(net 567)
	)
	(segment
		(start 182.491706 124.897019)
		(end 182.508579 124.913892)
		(width 0.2)
		(layer "F.Cu")
		(net 567)
	)
	(segment
		(start 170.9 132.3)
		(end 170.9 131.4)
		(width 0.1)
		(layer "F.Cu")
		(net 567)
	)
	(segment
		(start 170.9 131.4)
		(end 171.06 131.24)
		(width 0.1)
		(layer "F.Cu")
		(net 567)
	)
	(segment
		(start 171.254468 132.64)
		(end 171.24 132.64)
		(width 0.1)
		(layer "F.Cu")
		(net 567)
	)
	(segment
		(start 182.465 125.225)
		(end 182.465 126.06)
		(width 0.2)
		(layer "F.Cu")
		(net 567)
	)
	(segment
		(start 182.508579 124.913892)
		(end 182.508579 125.181421)
		(width 0.2)
		(layer "F.Cu")
		(net 567)
	)
	(segment
		(start 171.06 131.24)
		(end 171.874468 131.24)
		(width 0.1)
		(layer "F.Cu")
		(net 567)
	)
	(via
		(at 182.508579 124.897019)
		(size 0.45)
		(drill 0.1)
		(layers "F.Cu" "B.Cu")
		(remove_unused_layers yes)
		(keep_end_layers yes)
		(zone_layer_connections)
		(net 567)
	)
	(via
		(at 177.65 130.88)
		(size 0.45)
		(drill 0.1)
		(layers "F.Cu" "B.Cu")
		(net 567)
	)
	(segment
		(start 182.5 128.47)
		(end 182.5 124.994038)
		(width 0.2)
		(layer "In5.Cu")
		(net 567)
	)
	(segment
		(start 182.597019 124.897019)
		(end 182.491706 124.897019)
		(width 0.2)
		(layer "In5.Cu")
		(net 567)
	)
	(segment
		(start 180.12 130.85)
		(end 182.5 128.47)
		(width 0.2)
		(layer "In5.Cu")
		(net 567)
	)
	(segment
		(start 177.68 130.85)
		(end 180.12 130.85)
		(width 0.2)
		(layer "In5.Cu")
		(net 567)
	)
	(segment
		(start 182.5 124.994038)
		(end 182.597019 124.897019)
		(width 0.2)
		(layer "In5.Cu")
		(net 567)
	)
	(segment
		(start 177.65 130.88)
		(end 177.68 130.85)
		(width 0.2)
		(layer "In5.Cu")
		(net 567)
	)
	(via
		(at 80.2 91)
		(size 0.45)
		(drill 0.1)
		(layers "F.Cu" "B.Cu")
		(net 569)
	)
	(via
		(at 93.530532 73.65)
		(size 0.45)
		(drill 0.1)
		(layers "F.Cu" "B.Cu")
		(net 569)
	)
	(segment
		(start 80.825 90.375)
		(end 80.2 91)
		(width 0.1)
		(layer "B.Cu")
		(net 569)
	)
	(segment
		(start 80.855532 90.375)
		(end 80.825 90.375)
		(width 0.1)
		(layer "B.Cu")
		(net 569)
	)
	(segment
		(start 95.775 75.85)
		(end 95.775 75.55)
		(width 0.1)
		(layer "In4.Cu")
		(net 569)
	)
	(segment
		(start 83.55 90.8)
		(end 85.7 88.65)
		(width 0.1)
		(layer "In4.Cu")
		(net 569)
	)
	(segment
		(start 80.62 92.02)
		(end 81.08 92.02)
		(width 0.1)
		(layer "In4.Cu")
		(net 569)
	)
	(segment
		(start 96.3 73.1)
		(end 95.225 73.1)
		(width 0.1)
		(layer "In4.Cu")
		(net 569)
	)
	(segment
		(start 96.875 73.675)
		(end 96.3 73.1)
		(width 0.1)
		(layer "In4.Cu")
		(net 569)
	)
	(segment
		(start 82.3 90.8)
		(end 83.55 90.8)
		(width 0.1)
		(layer "In4.Cu")
		(net 569)
	)
	(segment
		(start 91.725 79.9)
		(end 95.775 75.85)
		(width 0.1)
		(layer "In4.Cu")
		(net 569)
	)
	(segment
		(start 86.1 88.65)
		(end 86.6 88.15)
		(width 0.1)
		(layer "In4.Cu")
		(net 569)
	)
	(segment
		(start 88.8 84.8)
		(end 88.8 83.1)
		(width 0.1)
		(layer "In4.Cu")
		(net 569)
	)
	(segment
		(start 96.875 74.45)
		(end 96.875 73.675)
		(width 0.1)
		(layer "In4.Cu")
		(net 569)
	)
	(segment
		(start 86.6 87)
		(end 88.8 84.8)
		(width 0.1)
		(layer "In4.Cu")
		(net 569)
	)
	(segment
		(start 88.8 83.1)
		(end 91.725 80.175)
		(width 0.1)
		(layer "In4.Cu")
		(net 569)
	)
	(segment
		(start 95.225 73.1)
		(end 94.675 73.65)
		(width 0.1)
		(layer "In4.Cu")
		(net 569)
	)
	(segment
		(start 91.725 80.175)
		(end 91.725 79.9)
		(width 0.1)
		(layer "In4.Cu")
		(net 569)
	)
	(segment
		(start 95.775 75.55)
		(end 96.875 74.45)
		(width 0.1)
		(layer "In4.Cu")
		(net 569)
	)
	(segment
		(start 85.7 88.65)
		(end 86.1 88.65)
		(width 0.1)
		(layer "In4.Cu")
		(net 569)
	)
	(segment
		(start 81.08 92.02)
		(end 82.3 90.8)
		(width 0.1)
		(layer "In4.Cu")
		(net 569)
	)
	(segment
		(start 80.2 91.6)
		(end 80.62 92.02)
		(width 0.1)
		(layer "In4.Cu")
		(net 569)
	)
	(segment
		(start 80.2 91)
		(end 80.2 91.6)
		(width 0.1)
		(layer "In4.Cu")
		(net 569)
	)
	(segment
		(start 86.6 88.15)
		(end 86.6 87)
		(width 0.1)
		(layer "In4.Cu")
		(net 569)
	)
	(segment
		(start 94.675 73.65)
		(end 93.530532 73.65)
		(width 0.1)
		(layer "In4.Cu")
		(net 569)
	)
	(segment
		(start 85.135532 93.385)
		(end 86.275 93.385)
		(width 0.1)
		(layer "B.Cu")
		(net 570)
	)
	(segment
		(start 86.3 93.36)
		(end 86.275 93.385)
		(width 0.19)
		(layer "B.Cu")
		(net 570)
	)
	(segment
		(start 94.085 97.82337)
		(end 89.62163 93.36)
		(width 0.19)
		(layer "B.Cu")
		(net 570)
	)
	(segment
		(start 95.180001 103.095)
		(end 94.865001 102.78)
		(width 0.19)
		(layer "B.Cu")
		(net 570)
	)
	(segment
		(start 95.180001 103.12)
		(end 95.180001 103.095)
		(width 0.19)
		(layer "B.Cu")
		(net 570)
	)
	(segment
		(start 94.865001 102.78)
		(end 94.865001 102.353371)
		(width 0.19)
		(layer "B.Cu")
		(net 570)
	)
	(segment
		(start 94.865001 102.353371)
		(end 94.085 101.57337)
		(width 0.19)
		(layer "B.Cu")
		(net 570)
	)
	(segment
		(start 89.62163 93.36)
		(end 86.3 93.36)
		(width 0.19)
		(layer "B.Cu")
		(net 570)
	)
	(segment
		(start 84.665532 92.915)
		(end 85.135532 93.385)
		(width 0.1)
		(layer "B.Cu")
		(net 570)
	)
	(segment
		(start 94.085 101.57337)
		(end 94.085 97.82337)
		(width 0.19)
		(layer "B.Cu")
		(net 570)
	)
	(segment
		(start 68 119)
		(end 70.010532 119)
		(width 0.1)
		(layer "B.Cu")
		(net 571)
	)
	(segment
		(start 70.010532 119)
		(end 70.695532 118.315)
		(width 0.1)
		(layer "B.Cu")
		(net 571)
	)
	(segment
		(start 66.5 120.5)
		(end 68 119)
		(width 0.1)
		(layer "B.Cu")
		(net 571)
	)
	(segment
		(start 63.5 120.5)
		(end 66.5 120.5)
		(width 0.1)
		(layer "B.Cu")
		(net 571)
	)
	(segment
		(start 82.565 78.42663)
		(end 82.565 80.654468)
		(width 0.19)
		(layer "F.Cu")
		(net 572)
	)
	(segment
		(start 81.1 76.28)
		(end 81.1 76.305)
		(width 0.19)
		(layer "F.Cu")
		(net 572)
	)
	(segment
		(start 81.1 76.305)
		(end 81.415 76.62)
		(width 0.19)
		(layer "F.Cu")
		(net 572)
	)
	(segment
		(start 81.415 77.27663)
		(end 82.565 78.42663)
		(width 0.19)
		(layer "F.Cu")
		(net 572)
	)
	(segment
		(start 82.565 80.654468)
		(end 83.395532 81.485)
		(width 0.19)
		(layer "F.Cu")
		(net 572)
	)
	(segment
		(start 81.415 76.62)
		(end 81.415 77.27663)
		(width 0.19)
		(layer "F.Cu")
		(net 572)
	)
	(via
		(at 83.395532 81.485)
		(size 0.45)
		(drill 0.1)
		(layers "F.Cu" "B.Cu")
		(net 572)
	)
	(segment
		(start 92.4 85)
		(end 92.4 83.8)
		(width 0.1)
		(layer "F.Cu")
		(net 574)
	)
	(segment
		(start 92.2 85.2)
		(end 92.4 85)
		(width 0.1)
		(layer "F.Cu")
		(net 574)
	)
	(segment
		(start 90.2 87.1)
		(end 90.3 87)
		(width 0.1)
		(layer "F.Cu")
		(net 574)
	)
	(segment
		(start 92.2 86.2)
		(end 92.2 85.2)
		(width 0.1)
		(layer "F.Cu")
		(net 574)
	)
	(segment
		(start 102.380532 83.6)
		(end 103.330532 82.65)
		(width 0.1)
		(layer "F.Cu")
		(net 574)
	)
	(segment
		(start 90.3 87)
		(end 91.4 87)
		(width 0.1)
		(layer "F.Cu")
		(net 574)
	)
	(segment
		(start 91.4 87)
		(end 92.2 86.2)
		(width 0.1)
		(layer "F.Cu")
		(net 574)
	)
	(segment
		(start 92.6 83.6)
		(end 102.380532 83.6)
		(width 0.1)
		(layer "F.Cu")
		(net 574)
	)
	(segment
		(start 92.4 83.8)
		(end 92.6 83.6)
		(width 0.1)
		(layer "F.Cu")
		(net 574)
	)
	(segment
		(start 89.55 87.1)
		(end 90.2 87.1)
		(width 0.1)
		(layer "F.Cu")
		(net 574)
	)
	(via
		(at 89.55 87.1)
		(size 0.45)
		(drill 0.1)
		(layers "F.Cu" "B.Cu")
		(net 574)
	)
	(segment
		(start 80.35 105.109468)
		(end 80.855532 105.615)
		(width 0.1)
		(layer "B.Cu")
		(net 574)
	)
	(segment
		(start 82.7 90.25)
		(end 82.7 100.95)
		(width 0.1)
		(layer "B.Cu")
		(net 574)
	)
	(segment
		(start 80.5 101.1)
		(end 80.35 101.25)
		(width 0.1)
		(layer "B.Cu")
		(net 574)
	)
	(segment
		(start 82.55 101.1)
		(end 80.5 101.1)
		(width 0.1)
		(layer "B.Cu")
		(net 574)
	)
	(segment
		(start 80.35 101.25)
		(end 80.35 105.109468)
		(width 0.1)
		(layer "B.Cu")
		(net 574)
	)
	(segment
		(start 88.1 89.85)
		(end 83.1 89.85)
		(width 0.1)
		(layer "B.Cu")
		(net 574)
	)
	(segment
		(start 89.55 88.4)
		(end 88.1 89.85)
		(width 0.1)
		(layer "B.Cu")
		(net 574)
	)
	(segment
		(start 82.7 100.95)
		(end 82.55 101.1)
		(width 0.1)
		(layer "B.Cu")
		(net 574)
	)
	(segment
		(start 89.55 87.1)
		(end 89.55 88.4)
		(width 0.1)
		(layer "B.Cu")
		(net 574)
	)
	(segment
		(start 83.1 89.85)
		(end 82.7 90.25)
		(width 0.1)
		(layer "B.Cu")
		(net 574)
	)
	(segment
		(start 203.93 87.655856)
		(end 202.715 87.655856)
		(width 0.19)
		(layer "F.Cu")
		(net 575)
	)
	(segment
		(start 202.715 87.655856)
		(end 202.6 87.770856)
		(width 0.19)
		(layer "F.Cu")
		(net 575)
	)
	(segment
		(start 204.27 87.970856)
		(end 204.245 87.970856)
		(width 0.19)
		(layer "F.Cu")
		(net 575)
	)
	(segment
		(start 204.245 87.970856)
		(end 203.93 87.655856)
		(width 0.19)
		(layer "F.Cu")
		(net 575)
	)
	(via
		(at 135.230532 81.15)
		(size 0.45)
		(drill 0.1)
		(layers "F.Cu" "B.Cu")
		(net 575)
	)
	(via
		(at 202.6 87.770856)
		(size 0.45)
		(drill 0.1)
		(layers "F.Cu" "B.Cu")
		(net 575)
	)
	(segment
		(start 145.393044 80.5375)
		(end 147.1625 82.306956)
		(width 0.15)
		(layer "In7.Cu")
		(net 575)
	)
	(segment
		(start 134.918032 80.8375)
		(end 134.918032 80.776424)
		(width 0.15)
		(layer "In7.Cu")
		(net 575)
	)
	(segment
		(start 195.209177 87.955052)
		(end 195.209177 86.936682)
		(width 0.15)
		(layer "In7.Cu")
		(net 575)
	)
	(segment
		(start 134.918032 80.776424)
		(end 135.156956 80.5375)
		(width 0.15)
		(layer "In7.Cu")
		(net 575)
	)
	(segment
		(start 195.634177 86.936682)
		(end 195.634177 87.95505)
		(width 0.15)
		(layer "In7.Cu")
		(net 575)
	)
	(segment
		(start 147.1625 85.256956)
		(end 149.5139 87.608356)
		(width 0.15)
		(layer "In7.Cu")
		(net 575)
	)
	(segment
		(start 195.351677 86.794182)
		(end 195.491677 86.794182)
		(width 0.15)
		(layer "In7.Cu")
		(net 575)
	)
	(segment
		(start 137.379846 80.902751)
		(end 137.459846 80.902751)
		(width 0.15)
		(layer "In7.Cu")
		(net 575)
	)
	(segment
		(start 137.779846 80.5375)
		(end 145.393044 80.5375)
		(width 0.15)
		(layer "In7.Cu")
		(net 575)
	)
	(segment
		(start 197.451677 87.608356)
		(end 202.4375 87.608356)
		(width 0.15)
		(layer "In7.Cu")
		(net 575)
	)
	(segment
		(start 197.034177 86.936682)
		(end 197.034177 87.190856)
		(width 0.15)
		(layer "In7.Cu")
		(net 575)
	)
	(segment
		(start 196.051677 88.37255)
		(end 196.191677 88.37255)
		(width 0.15)
		(layer "In7.Cu")
		(net 575)
	)
	(segment
		(start 147.1625 82.306956)
		(end 147.1625 85.256956)
		(width 0.15)
		(layer "In7.Cu")
		(net 575)
	)
	(segment
		(start 194.234177 87.750856)
		(end 194.234177 87.955052)
		(width 0.15)
		(layer "In7.Cu")
		(net 575)
	)
	(segment
		(start 196.609177 87.95505)
		(end 196.609177 86.936682)
		(width 0.15)
		(layer "In7.Cu")
		(net 575)
	)
	(segment
		(start 137.619846 80.742751)
		(end 137.619846 80.6975)
		(width 0.15)
		(layer "In7.Cu")
		(net 575)
	)
	(segment
		(start 149.5139 87.608356)
		(end 194.091677 87.608356)
		(width 0.15)
		(layer "In7.Cu")
		(net 575)
	)
	(segment
		(start 137.219846 80.6975)
		(end 137.219846 80.742751)
		(width 0.15)
		(layer "In7.Cu")
		(net 575)
	)
	(segment
		(start 202.4375 87.608356)
		(end 202.6 87.770856)
		(width 0.15)
		(layer "In7.Cu")
		(net 575)
	)
	(segment
		(start 135.230532 81.15)
		(end 134.918032 80.8375)
		(width 0.15)
		(layer "In7.Cu")
		(net 575)
	)
	(segment
		(start 135.156956 80.5375)
		(end 137.059846 80.5375)
		(width 0.15)
		(layer "In7.Cu")
		(net 575)
	)
	(segment
		(start 194.651677 88.372552)
		(end 194.791677 88.372552)
		(width 0.15)
		(layer "In7.Cu")
		(net 575)
	)
	(segment
		(start 196.751677 86.794182)
		(end 196.891677 86.794182)
		(width 0.15)
		(layer "In7.Cu")
		(net 575)
	)
	(arc
		(start 195.209177 86.936682)
		(mid 195.250914 86.835919)
		(end 195.351677 86.794182)
		(width 0.15)
		(layer "In7.Cu")
		(net 575)
	)
	(arc
		(start 137.459846 80.902751)
		(mid 137.572983 80.855888)
		(end 137.619846 80.742751)
		(width 0.15)
		(layer "In7.Cu")
		(net 575)
	)
	(arc
		(start 137.059846 80.5375)
		(mid 137.172983 80.584363)
		(end 137.219846 80.6975)
		(width 0.15)
		(layer "In7.Cu")
		(net 575)
	)
	(arc
		(start 196.609177 86.936682)
		(mid 196.650914 86.835919)
		(end 196.751677 86.794182)
		(width 0.15)
		(layer "In7.Cu")
		(net 575)
	)
	(arc
		(start 195.634177 87.95505)
		(mid 195.75646 88.250267)
		(end 196.051677 88.37255)
		(width 0.15)
		(layer "In7.Cu")
		(net 575)
	)
	(arc
		(start 194.234177 87.955052)
		(mid 194.35646 88.250269)
		(end 194.651677 88.372552)
		(width 0.15)
		(layer "In7.Cu")
		(net 575)
	)
	(arc
		(start 194.791677 88.372552)
		(mid 195.086894 88.250269)
		(end 195.209177 87.955052)
		(width 0.15)
		(layer "In7.Cu")
		(net 575)
	)
	(arc
		(start 137.219846 80.742751)
		(mid 137.266709 80.855888)
		(end 137.379846 80.902751)
		(width 0.15)
		(layer "In7.Cu")
		(net 575)
	)
	(arc
		(start 137.619846 80.6975)
		(mid 137.666709 80.584363)
		(end 137.779846 80.5375)
		(width 0.15)
		(layer "In7.Cu")
		(net 575)
	)
	(arc
		(start 194.091677 87.608356)
		(mid 194.19244 87.650093)
		(end 194.234177 87.750856)
		(width 0.15)
		(layer "In7.Cu")
		(net 575)
	)
	(arc
		(start 197.034177 87.190856)
		(mid 197.15646 87.486073)
		(end 197.451677 87.608356)
		(width 0.15)
		(layer "In7.Cu")
		(net 575)
	)
	(arc
		(start 196.191677 88.37255)
		(mid 196.486894 88.250267)
		(end 196.609177 87.95505)
		(width 0.15)
		(layer "In7.Cu")
		(net 575)
	)
	(arc
		(start 196.891677 86.794182)
		(mid 196.99244 86.835919)
		(end 197.034177 86.936682)
		(width 0.15)
		(layer "In7.Cu")
		(net 575)
	)
	(arc
		(start 195.491677 86.794182)
		(mid 195.59244 86.835919)
		(end 195.634177 86.936682)
		(width 0.15)
		(layer "In7.Cu")
		(net 575)
	)
	(segment
		(start 182.94 143.975)
		(end 183.47 143.975)
		(width 0.2)
		(layer "F.Cu")
		(net 578)
	)
	(segment
		(start 183.47 143.975)
		(end 184.039468 144.544468)
		(width 0.2)
		(layer "F.Cu")
		(net 578)
	)
	(segment
		(start 99.330532 70.65)
		(end 99.35 70.65)
		(width 0.1)
		(layer "F.Cu")
		(net 580)
	)
	(segment
		(start 150.3 99.6)
		(end 148.6 101.3)
		(width 0.1)
		(layer "F.Cu")
		(net 580)
	)
	(segment
		(start 151.8 99.6)
		(end 150.3 99.6)
		(width 0.1)
		(layer "F.Cu")
		(net 580)
	)
	(via
		(at 99.35 70.65)
		(size 0.45)
		(drill 0.1)
		(layers "F.Cu" "B.Cu")
		(net 580)
	)
	(via
		(at 148.6 101.3)
		(size 0.45)
		(drill 0.1)
		(layers "F.Cu" "B.Cu")
		(net 580)
	)
	(segment
		(start 103.9 71.9)
		(end 105.9 71.9)
		(width 0.1)
		(layer "B.Cu")
		(net 580)
	)
	(segment
		(start 99 70.3)
		(end 99 68.8)
		(width 0.1)
		(layer "B.Cu")
		(net 580)
	)
	(segment
		(start 101.2 68.5)
		(end 101.5 68.8)
		(width 0.1)
		(layer "B.Cu")
		(net 580)
	)
	(segment
		(start 120.9 76.5)
		(end 120.9 80.8)
		(width 0.1)
		(layer "B.Cu")
		(net 580)
	)
	(segment
		(start 115.6 71.5)
		(end 116.8 72.7)
		(width 0.1)
		(layer "B.Cu")
		(net 580)
	)
	(segment
		(start 141.8 98.65)
		(end 144.45 101.3)
		(width 0.1)
		(layer "B.Cu")
		(net 580)
	)
	(segment
		(start 105.9 71.9)
		(end 106.3 71.5)
		(width 0.1)
		(layer "B.Cu")
		(net 580)
	)
	(segment
		(start 137.4 98.8)
		(end 137.7 99.1)
		(width 0.1)
		(layer "B.Cu")
		(net 580)
	)
	(segment
		(start 137.7 99.1)
		(end 139.7 99.1)
		(width 0.1)
		(layer "B.Cu")
		(net 580)
	)
	(segment
		(start 99 68.8)
		(end 99.3 68.5)
		(width 0.1)
		(layer "B.Cu")
		(net 580)
	)
	(segment
		(start 99.3 68.5)
		(end 101.2 68.5)
		(width 0.1)
		(layer "B.Cu")
		(net 580)
	)
	(segment
		(start 101.5 68.8)
		(end 101.5 69.5)
		(width 0.1)
		(layer "B.Cu")
		(net 580)
	)
	(segment
		(start 139.7 99.1)
		(end 140.15 98.65)
		(width 0.1)
		(layer "B.Cu")
		(net 580)
	)
	(segment
		(start 120.3 74.7)
		(end 120.3 75.9)
		(width 0.1)
		(layer "B.Cu")
		(net 580)
	)
	(segment
		(start 126.8 87.4)
		(end 127.9 88.5)
		(width 0.1)
		(layer "B.Cu")
		(net 580)
	)
	(segment
		(start 99.35 70.65)
		(end 99 70.3)
		(width 0.1)
		(layer "B.Cu")
		(net 580)
	)
	(segment
		(start 127.9 88.5)
		(end 128.8 88.5)
		(width 0.1)
		(layer "B.Cu")
		(net 580)
	)
	(segment
		(start 118.3 72.7)
		(end 120.3 74.7)
		(width 0.1)
		(layer "B.Cu")
		(net 580)
	)
	(segment
		(start 137.4 97.9)
		(end 137.4 98.8)
		(width 0.1)
		(layer "B.Cu")
		(net 580)
	)
	(segment
		(start 129.7 90.2)
		(end 137.4 97.9)
		(width 0.1)
		(layer "B.Cu")
		(net 580)
	)
	(segment
		(start 126.8 86.7)
		(end 126.8 87.4)
		(width 0.1)
		(layer "B.Cu")
		(net 580)
	)
	(segment
		(start 106.3 71.5)
		(end 115.6 71.5)
		(width 0.1)
		(layer "B.Cu")
		(net 580)
	)
	(segment
		(start 128.8 88.5)
		(end 129.7 89.4)
		(width 0.1)
		(layer "B.Cu")
		(net 580)
	)
	(segment
		(start 129.7 89.4)
		(end 129.7 90.2)
		(width 0.1)
		(layer "B.Cu")
		(net 580)
	)
	(segment
		(start 101.5 69.5)
		(end 103.9 71.9)
		(width 0.1)
		(layer "B.Cu")
		(net 580)
	)
	(segment
		(start 144.45 101.3)
		(end 148.6 101.3)
		(width 0.1)
		(layer "B.Cu")
		(net 580)
	)
	(segment
		(start 140.15 98.65)
		(end 141.8 98.65)
		(width 0.1)
		(layer "B.Cu")
		(net 580)
	)
	(segment
		(start 116.8 72.7)
		(end 118.3 72.7)
		(width 0.1)
		(layer "B.Cu")
		(net 580)
	)
	(segment
		(start 120.9 80.8)
		(end 126.8 86.7)
		(width 0.1)
		(layer "B.Cu")
		(net 580)
	)
	(segment
		(start 120.3 75.9)
		(end 120.9 76.5)
		(width 0.1)
		(layer "B.Cu")
		(net 580)
	)
	(segment
		(start 212.097986 87.586356)
		(end 212.100131 87.586356)
		(width 0.19)
		(layer "F.Cu")
		(net 583)
	)
	(segment
		(start 212.115631 87.570856)
		(end 212.565632 87.570856)
		(width 0.19)
		(layer "F.Cu")
		(net 583)
	)
	(segment
		(start 211.797486 87.285856)
		(end 212.097986 87.586356)
		(width 0.19)
		(layer "F.Cu")
		(net 583)
	)
	(segment
		(start 205.255 86.970856)
		(end 205.57 87.285856)
		(width 0.19)
		(layer "F.Cu")
		(net 583)
	)
	(segment
		(start 205.23 86.970856)
		(end 205.255 86.970856)
		(width 0.19)
		(layer "F.Cu")
		(net 583)
	)
	(segment
		(start 212.100131 87.586356)
		(end 212.115631 87.570856)
		(width 0.19)
		(layer "F.Cu")
		(net 583)
	)
	(segment
		(start 205.57 87.285856)
		(end 211.797486 87.285856)
		(width 0.19)
		(layer "F.Cu")
		(net 583)
	)
	(segment
		(start 116.430532 78.15)
		(end 116.695532 78.415)
		(width 0.19)
		(layer "F.Cu")
		(net 584)
	)
	(segment
		(start 116.695532 78.985)
		(end 116.580532 79.1)
		(width 0.19)
		(layer "F.Cu")
		(net 584)
	)
	(segment
		(start 116.695532 78.415)
		(end 116.695532 78.985)
		(width 0.19)
		(layer "F.Cu")
		(net 584)
	)
	(via
		(at 115.187868 100.012132)
		(size 0.45)
		(drill 0.1)
		(layers "F.Cu" "B.Cu")
		(net 584)
	)
	(via
		(at 116.580532 79.1)
		(size 0.45)
		(drill 0.1)
		(layers "F.Cu" "B.Cu")
		(net 584)
	)
	(segment
		(start 115.655 103.76)
		(end 115.387647 103.76)
		(width 0.19)
		(layer "B.Cu")
		(net 584)
	)
	(segment
		(start 115.815 108.02337)
		(end 115.52387 108.3145)
		(width 0.19)
		(layer "B.Cu")
		(net 584)
	)
	(segment
		(start 115.350502 100.012132)
		(end 115.815 100.47663)
		(width 0.19)
		(layer "B.Cu")
		(net 584)
	)
	(segment
		(start 114.3745 108.3145)
		(end 114.31 108.25)
		(width 0.19)
		(layer "B.Cu")
		(net 584)
	)
	(segment
		(start 115.815 100.47663)
		(end 115.815 103.6)
		(width 0.19)
		(layer "B.Cu")
		(net 584)
	)
	(segment
		(start 115.815 104.32)
		(end 115.815 108.02337)
		(width 0.19)
		(layer "B.Cu")
		(net 584)
	)
	(segment
		(start 115.387647 104.16)
		(end 115.655 104.16)
		(width 0.19)
		(layer "B.Cu")
		(net 584)
	)
	(segment
		(start 115.187868 100.012132)
		(end 115.350502 100.012132)
		(width 0.19)
		(layer "B.Cu")
		(net 584)
	)
	(segment
		(start 115.227647 103.92)
		(end 115.227647 104)
		(width 0.19)
		(layer "B.Cu")
		(net 584)
	)
	(segment
		(start 115.52387 108.3145)
		(end 114.3745 108.3145)
		(width 0.19)
		(layer "B.Cu")
		(net 584)
	)
	(segment
		(start 114.31 108.25)
		(end 113.685 108.25)
		(width 0.19)
		(layer "B.Cu")
		(net 584)
	)
	(arc
		(start 115.655 104.16)
		(mid 115.768137 104.206863)
		(end 115.815 104.32)
		(width 0.19)
		(layer "B.Cu")
		(net 584)
	)
	(arc
		(start 115.227647 104)
		(mid 115.27451 104.113137)
		(end 115.387647 104.16)
		(width 0.19)
		(layer "B.Cu")
		(net 584)
	)
	(arc
		(start 115.815 103.6)
		(mid 115.768137 103.713137)
		(end 115.655 103.76)
		(width 0.19)
		(layer "B.Cu")
		(net 584)
	)
	(arc
		(start 115.387647 103.76)
		(mid 115.27451 103.806863)
		(end 115.227647 103.92)
		(width 0.19)
		(layer "B.Cu")
		(net 584)
	)
	(segment
		(start 126.7375 75.443044)
		(end 127.8375 76.543044)
		(width 0.15)
		(layer "In5.Cu")
		(net 584)
	)
	(segment
		(start 119.7375 88.656956)
		(end 117.6375 90.756956)
		(width 0.15)
		(layer "In5.Cu")
		(net 584)
	)
	(segment
		(start 115.417677 100.012132)
		(end 115.187868 100.012132)
		(width 0.15)
		(layer "In5.Cu")
		(net 584)
	)
	(segment
		(start 122.256956 83.6375)
		(end 121.556956 83.6375)
		(width 0.15)
		(layer "In5.Cu")
		(net 584)
	)
	(segment
		(start 121.556956 83.6375)
		(end 119.7375 85.456956)
		(width 0.15)
		(layer "In5.Cu")
		(net 584)
	)
	(segment
		(start 117.8625 74.043044)
		(end 119.043044 72.8625)
		(width 0.15)
		(layer "In5.Cu")
		(net 584)
	)
	(segment
		(start 117.9625 77.043044)
		(end 117.9625 76.056956)
		(width 0.15)
		(layer "In5.Cu")
		(net 584)
	)
	(segment
		(start 117.6375 90.756956)
		(end 117.6375 95.843044)
		(width 0.15)
		(layer "In5.Cu")
		(net 584)
	)
	(segment
		(start 119.043044 72.8625)
		(end 125.556956 72.8625)
		(width 0.15)
		(layer "In5.Cu")
		(net 584)
	)
	(segment
		(start 116.743032 78.262512)
		(end 117.9625 77.043044)
		(width 0.15)
		(layer "In5.Cu")
		(net 584)
	)
	(segment
		(start 116.743032 78.9375)
		(end 116.743032 78.262512)
		(width 0.15)
		(layer "In5.Cu")
		(net 584)
	)
	(segment
		(start 117.4625 75.556956)
		(end 117.4625 74.943044)
		(width 0.15)
		(layer "In5.Cu")
		(net 584)
	)
	(segment
		(start 124.2375 81.656956)
		(end 122.256956 83.6375)
		(width 0.15)
		(layer "In5.Cu")
		(net 584)
	)
	(segment
		(start 125.656956 79.9375)
		(end 125.056956 79.9375)
		(width 0.15)
		(layer "In5.Cu")
		(net 584)
	)
	(segment
		(start 125.056956 79.9375)
		(end 124.2375 80.756956)
		(width 0.15)
		(layer "In5.Cu")
		(net 584)
	)
	(segment
		(start 119.7375 85.456956)
		(end 119.7375 88.656956)
		(width 0.15)
		(layer "In5.Cu")
		(net 584)
	)
	(segment
		(start 115.743045 100.3375)
		(end 115.417677 100.012132)
		(width 0.15)
		(layer "In5.Cu")
		(net 584)
	)
	(segment
		(start 118.5375 96.743044)
		(end 118.5375 99.656956)
		(width 0.15)
		(layer "In5.Cu")
		(net 584)
	)
	(segment
		(start 124.2375 80.756956)
		(end 124.2375 81.656956)
		(width 0.15)
		(layer "In5.Cu")
		(net 584)
	)
	(segment
		(start 117.6375 95.843044)
		(end 118.5375 96.743044)
		(width 0.15)
		(layer "In5.Cu")
		(net 584)
	)
	(segment
		(start 127.8375 77.756956)
		(end 125.656956 79.9375)
		(width 0.15)
		(layer "In5.Cu")
		(net 584)
	)
	(segment
		(start 117.4625 74.943044)
		(end 117.8625 74.543044)
		(width 0.15)
		(layer "In5.Cu")
		(net 584)
	)
	(segment
		(start 118.5375 99.656956)
		(end 117.856956 100.3375)
		(width 0.15)
		(layer "In5.Cu")
		(net 584)
	)
	(segment
		(start 127.8375 76.543044)
		(end 127.8375 77.756956)
		(width 0.15)
		(layer "In5.Cu")
		(net 584)
	)
	(segment
		(start 117.8625 74.543044)
		(end 117.8625 74.043044)
		(width 0.15)
		(layer "In5.Cu")
		(net 584)
	)
	(segment
		(start 126.7375 74.043044)
		(end 126.7375 75.443044)
		(width 0.15)
		(layer "In5.Cu")
		(net 584)
	)
	(segment
		(start 117.9625 76.056956)
		(end 117.4625 75.556956)
		(width 0.15)
		(layer "In5.Cu")
		(net 584)
	)
	(segment
		(start 117.856956 100.3375)
		(end 115.743045 100.3375)
		(width 0.15)
		(layer "In5.Cu")
		(net 584)
	)
	(segment
		(start 116.580532 79.1)
		(end 116.743032 78.9375)
		(width 0.15)
		(layer "In5.Cu")
		(net 584)
	)
	(segment
		(start 125.556956 72.8625)
		(end 126.7375 74.043044)
		(width 0.15)
		(layer "In5.Cu")
		(net 584)
	)
	(segment
		(start 179.949468 139.93)
		(end 179.949468 141.034468)
		(width 0.2)
		(layer "F.Cu")
		(net 585)
	)
	(segment
		(start 179.949468 141.034468)
		(end 179.975 141.06)
		(width 0.2)
		(layer "F.Cu")
		(net 585)
	)
	(via
		(at 138.9 98.25)
		(size 0.45)
		(drill 0.1)
		(layers "F.Cu" "B.Cu")
		(net 589)
	)
	(via
		(at 132.530532 81.15)
		(size 0.45)
		(drill 0.1)
		(layers "F.Cu" "B.Cu")
		(net 589)
	)
	(via
		(at 125.7 115.5)
		(size 0.45)
		(drill 0.1)
		(layers "F.Cu" "B.Cu")
		(net 589)
	)
	(segment
		(start 131.645532 82.035)
		(end 129.52663 82.035)
		(width 0.19)
		(layer "B.Cu")
		(net 589)
	)
	(segment
		(start 129.52663 82.035)
		(end 129.035 82.52663)
		(width 0.19)
		(layer "B.Cu")
		(net 589)
	)
	(segment
		(start 130.635 88.67337)
		(end 138.785 96.82337)
		(width 0.19)
		(layer "B.Cu")
		(net 589)
	)
	(segment
		(start 114.873501 132.26)
		(end 114.938501 132.195)
		(width 0.19)
		(layer "B.Cu")
		(net 589)
	)
	(segment
		(start 122.57663 116.985)
		(end 124.17663 115.385)
		(width 0.19)
		(layer "B.Cu")
		(net 589)
	)
	(segment
		(start 117.135 118.92663)
		(end 119.07663 116.985)
		(width 0.19)
		(layer "B.Cu")
		(net 589)
	)
	(segment
		(start 132.530532 81.15)
		(end 131.645532 82.035)
		(width 0.19)
		(layer "B.Cu")
		(net 589)
	)
	(segment
		(start 114.938501 132.195)
		(end 115.46663 132.195)
		(width 0.19)
		(layer "B.Cu")
		(net 589)
	)
	(segment
		(start 124.17663 115.385)
		(end 125.585 115.385)
		(width 0.19)
		(layer "B.Cu")
		(net 589)
	)
	(segment
		(start 125.585 115.385)
		(end 125.7 115.5)
		(width 0.19)
		(layer "B.Cu")
		(net 589)
	)
	(segment
		(start 138.785 96.82337)
		(end 138.785 98.135)
		(width 0.19)
		(layer "B.Cu")
		(net 589)
	)
	(segment
		(start 130.635 85.02337)
		(end 130.635 88.67337)
		(width 0.19)
		(layer "B.Cu")
		(net 589)
	)
	(segment
		(start 115.46663 132.195)
		(end 117.135 130.52663)
		(width 0.19)
		(layer "B.Cu")
		(net 589)
	)
	(segment
		(start 117.135 130.52663)
		(end 117.135 118.92663)
		(width 0.19)
		(layer "B.Cu")
		(net 589)
	)
	(segment
		(start 138.785 98.135)
		(end 138.9 98.25)
		(width 0.19)
		(layer "B.Cu")
		(net 589)
	)
	(segment
		(start 129.035 82.52663)
		(end 129.035 83.42337)
		(width 0.19)
		(layer "B.Cu")
		(net 589)
	)
	(segment
		(start 119.07663 116.985)
		(end 122.57663 116.985)
		(width 0.19)
		(layer "B.Cu")
		(net 589)
	)
	(segment
		(start 129.035 83.42337)
		(end 130.635 85.02337)
		(width 0.19)
		(layer "B.Cu")
		(net 589)
	)
	(segment
		(start 113.711 132.26)
		(end 114.873501 132.26)
		(width 0.19)
		(layer "B.Cu")
		(net 589)
	)
	(segment
		(start 138.7375 101.456956)
		(end 138.7375 98.4125)
		(width 0.15)
		(layer "In7.Cu")
		(net 589)
	)
	(segment
		(start 138.7375 98.4125)
		(end 138.9 98.25)
		(width 0.15)
		(layer "In7.Cu")
		(net 589)
	)
	(segment
		(start 130.4375 109.756956)
		(end 138.7375 101.456956)
		(width 0.15)
		(layer "In7.Cu")
		(net 589)
	)
	(segment
		(start 125.7 115.5)
		(end 125.8625 115.3375)
		(width 0.15)
		(layer "In7.Cu")
		(net 589)
	)
	(segment
		(start 127.356956 115.3375)
		(end 127.976956 114.7175)
		(width 0.15)
		(layer "In7.Cu")
		(net 589)
	)
	(segment
		(start 125.8625 115.3375)
		(end 127.356956 115.3375)
		(width 0.15)
		(layer "In7.Cu")
		(net 589)
	)
	(segment
		(start 128.956956 114.7175)
		(end 130.4375 113.236956)
		(width 0.15)
		(layer "In7.Cu")
		(net 589)
	)
	(segment
		(start 130.4375 113.236956)
		(end 130.4375 109.756956)
		(width 0.15)
		(layer "In7.Cu")
		(net 589)
	)
	(segment
		(start 127.976956 114.7175)
		(end 128.956956 114.7175)
		(width 0.15)
		(layer "In7.Cu")
		(net 589)
	)
	(segment
		(start 86.715 86.97663)
		(end 85.85337 86.115)
		(width 0.19)
		(layer "F.Cu")
		(net 591)
	)
	(segment
		(start 88.325 91.11)
		(end 87.54837 91.11)
		(width 0.19)
		(layer "F.Cu")
		(net 591)
	)
	(segment
		(start 86.715 90.27663)
		(end 86.715 86.97663)
		(width 0.19)
		(layer "F.Cu")
		(net 591)
	)
	(segment
		(start 85.85337 86.115)
		(end 83.845532 86.115)
		(width 0.19)
		(layer "F.Cu")
		(net 591)
	)
	(segment
		(start 83.845532 86.115)
		(end 83.395532 86.565)
		(width 0.19)
		(layer "F.Cu")
		(net 591)
	)
	(segment
		(start 87.54837 91.11)
		(end 86.715 90.27663)
		(width 0.19)
		(layer "F.Cu")
		(net 591)
	)
	(segment
		(start 88.615 91.4)
		(end 88.325 91.11)
		(width 0.19)
		(layer "F.Cu")
		(net 591)
	)
	(segment
		(start 88.64 91.4)
		(end 88.615 91.4)
		(width 0.19)
		(layer "F.Cu")
		(net 591)
	)
	(via
		(at 83.395532 86.565)
		(size 0.45)
		(drill 0.1)
		(layers "F.Cu" "B.Cu")
		(net 591)
	)
	(segment
		(start 117.065532 78.415)
		(end 117.065532 78.985)
		(width 0.19)
		(layer "F.Cu")
		(net 592)
	)
	(segment
		(start 117.330532 78.15)
		(end 117.065532 78.415)
		(width 0.19)
		(layer "F.Cu")
		(net 592)
	)
	(segment
		(start 117.065532 78.985)
		(end 117.180532 79.1)
		(width 0.19)
		(layer "F.Cu")
		(net 592)
	)
	(via
		(at 115.612132 99.587868)
		(size 0.45)
		(drill 0.1)
		(layers "F.Cu" "B.Cu")
		(net 592)
	)
	(via
		(at 117.180532 79.1)
		(size 0.45)
		(drill 0.1)
		(layers "F.Cu" "B.Cu")
		(net 592)
	)
	(segment
		(start 116.185 108.17663)
		(end 116.185 100.32337)
		(width 0.19)
		(layer "B.Cu")
		(net 592)
	)
	(segment
		(start 116.185 100.32337)
		(end 115.612132 99.750502)
		(width 0.19)
		(layer "B.Cu")
		(net 592)
	)
	(segment
		(start 114.31 108.749)
		(end 114.3745 108.6845)
		(width 0.19)
		(layer "B.Cu")
		(net 592)
	)
	(segment
		(start 115.612132 99.750502)
		(end 115.612132 99.587868)
		(width 0.19)
		(layer "B.Cu")
		(net 592)
	)
	(segment
		(start 114.3745 108.6845)
		(end 115.67713 108.6845)
		(width 0.19)
		(layer "B.Cu")
		(net 592)
	)
	(segment
		(start 113.685 108.749)
		(end 114.31 108.749)
		(width 0.19)
		(layer "B.Cu")
		(net 592)
	)
	(segment
		(start 115.67713 108.6845)
		(end 116.185 108.17663)
		(width 0.19)
		(layer "B.Cu")
		(net 592)
	)
	(segment
		(start 119.156956 73.1375)
		(end 122.308465 73.1375)
		(width 0.15)
		(layer "In5.Cu")
		(net 592)
	)
	(segment
		(start 118.2625 99.543044)
		(end 117.743044 100.0625)
		(width 0.15)
		(layer "In5.Cu")
		(net 592)
	)
	(segment
		(start 118.1375 74.656956)
		(end 118.1375 74.156956)
		(width 0.15)
		(layer "In5.Cu")
		(net 592)
	)
	(segment
		(start 117.018032 78.376424)
		(end 118.2375 77.156956)
		(width 0.15)
		(layer "In5.Cu")
		(net 592)
	)
	(segment
		(start 123.9625 80.643044)
		(end 123.9625 81.543044)
		(width 0.15)
		(layer "In5.Cu")
		(net 592)
	)
	(segment
		(start 127.5625 76.656956)
		(end 127.5625 77.643044)
		(width 0.15)
		(layer "In5.Cu")
		(net 592)
	)
	(segment
		(start 123.828465 73.1375)
		(end 125.443044 73.1375)
		(width 0.15)
		(layer "In5.Cu")
		(net 592)
	)
	(segment
		(start 122.143044 83.3625)
		(end 121.443044 83.3625)
		(width 0.15)
		(layer "In5.Cu")
		(net 592)
	)
	(segment
		(start 127.5625 77.643044)
		(end 125.543044 79.6625)
		(width 0.15)
		(layer "In5.Cu")
		(net 592)
	)
	(segment
		(start 125.443044 73.1375)
		(end 126.4625 74.156956)
		(width 0.15)
		(layer "In5.Cu")
		(net 592)
	)
	(segment
		(start 126.4625 75.556956)
		(end 127.5625 76.656956)
		(width 0.15)
		(layer "In5.Cu")
		(net 592)
	)
	(segment
		(start 118.1375 74.156956)
		(end 119.156956 73.1375)
		(width 0.15)
		(layer "In5.Cu")
		(net 592)
	)
	(segment
		(start 117.7375 75.056956)
		(end 118.1375 74.656956)
		(width 0.15)
		(layer "In5.Cu")
		(net 592)
	)
	(segment
		(start 117.180532 79.1)
		(end 117.018032 78.9375)
		(width 0.15)
		(layer "In5.Cu")
		(net 592)
	)
	(segment
		(start 117.018032 78.9375)
		(end 117.018032 78.376424)
		(width 0.15)
		(layer "In5.Cu")
		(net 592)
	)
	(segment
		(start 118.2375 77.156956)
		(end 118.2375 75.943044)
		(width 0.15)
		(layer "In5.Cu")
		(net 592)
	)
	(segment
		(start 125.543044 79.6625)
		(end 124.943044 79.6625)
		(width 0.15)
		(layer "In5.Cu")
		(net 592)
	)
	(segment
		(start 117.7375 75.443044)
		(end 117.7375 75.056956)
		(width 0.15)
		(layer "In5.Cu")
		(net 592)
	)
	(segment
		(start 119.4625 88.543044)
		(end 117.3625 90.643044)
		(width 0.15)
		(layer "In5.Cu")
		(net 592)
	)
	(segment
		(start 115.856955 100.0625)
		(end 115.612132 99.817677)
		(width 0.15)
		(layer "In5.Cu")
		(net 592)
	)
	(segment
		(start 123.9625 81.543044)
		(end 122.143044 83.3625)
		(width 0.15)
		(layer "In5.Cu")
		(net 592)
	)
	(segment
		(start 123.668465 73.508588)
		(end 123.668465 73.2975)
		(width 0.15)
		(layer "In5.Cu")
		(net 592)
	)
	(segment
		(start 117.3625 95.956956)
		(end 118.2625 96.856956)
		(width 0.15)
		(layer "In5.Cu")
		(net 592)
	)
	(segment
		(start 117.743044 100.0625)
		(end 115.856955 100.0625)
		(width 0.15)
		(layer "In5.Cu")
		(net 592)
	)
	(segment
		(start 119.4625 85.343044)
		(end 119.4625 88.543044)
		(width 0.15)
		(layer "In5.Cu")
		(net 592)
	)
	(segment
		(start 115.612132 99.817677)
		(end 115.612132 99.587868)
		(width 0.15)
		(layer "In5.Cu")
		(net 592)
	)
	(segment
		(start 123.268465 73.2975)
		(end 123.268465 73.508588)
		(width 0.15)
		(layer "In5.Cu")
		(net 592)
	)
	(segment
		(start 122.468465 73.2975)
		(end 122.468465 73.508588)
		(width 0.15)
		(layer "In5.Cu")
		(net 592)
	)
	(segment
		(start 118.2375 75.943044)
		(end 117.7375 75.443044)
		(width 0.15)
		(layer "In5.Cu")
		(net 592)
	)
	(segment
		(start 117.3625 90.643044)
		(end 117.3625 95.956956)
		(width 0.15)
		(layer "In5.Cu")
		(net 592)
	)
	(segment
		(start 121.443044 83.3625)
		(end 119.4625 85.343044)
		(width 0.15)
		(layer "In5.Cu")
		(net 592)
	)
	(segment
		(start 122.868465 73.508588)
		(end 122.868465 73.2975)
		(width 0.15)
		(layer "In5.Cu")
		(net 592)
	)
	(segment
		(start 126.4625 74.156956)
		(end 126.4625 75.556956)
		(width 0.15)
		(layer "In5.Cu")
		(net 592)
	)
	(segment
		(start 123.028465 73.1375)
		(end 123.108465 73.1375)
		(width 0.15)
		(layer "In5.Cu")
		(net 592)
	)
	(segment
		(start 122.628465 73.668588)
		(end 122.708465 73.668588)
		(width 0.15)
		(layer "In5.Cu")
		(net 592)
	)
	(segment
		(start 123.428465 73.668588)
		(end 123.508465 73.668588)
		(width 0.15)
		(layer "In5.Cu")
		(net 592)
	)
	(segment
		(start 118.2625 96.856956)
		(end 118.2625 99.543044)
		(width 0.15)
		(layer "In5.Cu")
		(net 592)
	)
	(segment
		(start 124.943044 79.6625)
		(end 123.9625 80.643044)
		(width 0.15)
		(layer "In5.Cu")
		(net 592)
	)
	(arc
		(start 123.268465 73.508588)
		(mid 123.315328 73.621725)
		(end 123.428465 73.668588)
		(width 0.15)
		(layer "In5.Cu")
		(net 592)
	)
	(arc
		(start 123.668465 73.2975)
		(mid 123.715328 73.184363)
		(end 123.828465 73.1375)
		(width 0.15)
		(layer "In5.Cu")
		(net 592)
	)
	(arc
		(start 122.868465 73.2975)
		(mid 122.915328 73.184363)
		(end 123.028465 73.1375)
		(width 0.15)
		(layer "In5.Cu")
		(net 592)
	)
	(arc
		(start 122.708465 73.668588)
		(mid 122.821602 73.621725)
		(end 122.868465 73.508588)
		(width 0.15)
		(layer "In5.Cu")
		(net 592)
	)
	(arc
		(start 122.308465 73.1375)
		(mid 122.421602 73.184363)
		(end 122.468465 73.2975)
		(width 0.15)
		(layer "In5.Cu")
		(net 592)
	)
	(arc
		(start 122.468465 73.508588)
		(mid 122.515328 73.621725)
		(end 122.628465 73.668588)
		(width 0.15)
		(layer "In5.Cu")
		(net 592)
	)
	(arc
		(start 123.508465 73.668588)
		(mid 123.621602 73.621725)
		(end 123.668465 73.508588)
		(width 0.15)
		(layer "In5.Cu")
		(net 592)
	)
	(arc
		(start 123.108465 73.1375)
		(mid 123.221602 73.184363)
		(end 123.268465 73.2975)
		(width 0.15)
		(layer "In5.Cu")
		(net 592)
	)
	(segment
		(start 90.62 94.5)
		(end 90.595 94.5)
		(width 0.19)
		(layer "F.Cu")
		(net 593)
	)
	(segment
		(start 82.935 91.87337)
		(end 82.935 90.17663)
		(width 0.19)
		(layer "F.Cu")
		(net 593)
	)
	(segment
		(start 83.17663 89.935)
		(end 83.72663 89.935)
		(width 0.19)
		(layer "F.Cu")
		(net 593)
	)
	(segment
		(start 84.235 88.77337)
		(end 83.74663 88.285)
		(width 0.19)
		(layer "F.Cu")
		(net 593)
	)
	(segment
		(start 82.935 90.17663)
		(end 83.17663 89.935)
		(width 0.19)
		(layer "F.Cu")
		(net 593)
	)
	(segment
		(start 83.72663 89.935)
		(end 84.235 89.42663)
		(width 0.19)
		(layer "F.Cu")
		(net 593)
	)
	(segment
		(start 84.235 89.42663)
		(end 84.235 88.77337)
		(width 0.19)
		(layer "F.Cu")
		(net 593)
	)
	(segment
		(start 84.235 94.37337)
		(end 84.235 92.52337)
		(width 0.19)
		(layer "F.Cu")
		(net 593)
	)
	(segment
		(start 83.74663 88.285)
		(end 82.575532 88.285)
		(width 0.19)
		(layer "F.Cu")
		(net 593)
	)
	(segment
		(start 90.28 94.815)
		(end 85.4 94.815)
		(width 0.19)
		(layer "F.Cu")
		(net 593)
	)
	(segment
		(start 85.25 94.665)
		(end 84.52663 94.665)
		(width 0.19)
		(layer "F.Cu")
		(net 593)
	)
	(segment
		(start 84.52663 94.665)
		(end 84.235 94.37337)
		(width 0.19)
		(layer "F.Cu")
		(net 593)
	)
	(segment
		(start 83.12663 92.065)
		(end 82.935 91.87337)
		(width 0.19)
		(layer "F.Cu")
		(net 593)
	)
	(segment
		(start 84.235 92.52337)
		(end 83.77663 92.065)
		(width 0.19)
		(layer "F.Cu")
		(net 593)
	)
	(segment
		(start 85.4 94.815)
		(end 85.25 94.665)
		(width 0.19)
		(layer "F.Cu")
		(net 593)
	)
	(segment
		(start 83.77663 92.065)
		(end 83.12663 92.065)
		(width 0.19)
		(layer "F.Cu")
		(net 593)
	)
	(segment
		(start 82.575532 88.285)
		(end 82.125532 87.835)
		(width 0.19)
		(layer "F.Cu")
		(net 593)
	)
	(segment
		(start 90.595 94.5)
		(end 90.28 94.815)
		(width 0.19)
		(layer "F.Cu")
		(net 593)
	)
	(via
		(at 82.125532 87.835)
		(size 0.45)
		(drill 0.1)
		(layers "F.Cu" "B.Cu")
		(net 593)
	)
	(segment
		(start 206.245 88.470856)
		(end 205.93 88.785856)
		(width 0.19)
		(layer "F.Cu")
		(net 596)
	)
	(segment
		(start 206.27 88.470856)
		(end 206.245 88.470856)
		(width 0.19)
		(layer "F.Cu")
		(net 596)
	)
	(segment
		(start 203.315 88.785856)
		(end 203.2 88.670856)
		(width 0.19)
		(layer "F.Cu")
		(net 596)
	)
	(segment
		(start 205.93 88.785856)
		(end 203.315 88.785856)
		(width 0.19)
		(layer "F.Cu")
		(net 596)
	)
	(via
		(at 203.2 88.670856)
		(size 0.45)
		(drill 0.1)
		(layers "F.Cu" "B.Cu")
		(net 596)
	)
	(via
		(at 134.330532 84.15)
		(size 0.45)
		(drill 0.1)
		(layers "F.Cu" "B.Cu")
		(net 596)
	)
	(segment
		(start 202.385079 88.833356)
		(end 203.0375 88.833356)
		(width 0.15)
		(layer "In7.Cu")
		(net 596)
	)
	(segment
		(start 135.143044 83.1625)
		(end 145.406956 83.1625)
		(width 0.15)
		(layer "In7.Cu")
		(net 596)
	)
	(segment
		(start 199.867579 89.638534)
		(end 199.867579 88.303196)
		(width 0.15)
		(layer "In7.Cu")
		(net 596)
	)
	(segment
		(start 146.2875 84.043044)
		(end 146.2875 86.943044)
		(width 0.15)
		(layer "In7.Cu")
		(net 596)
	)
	(segment
		(start 200.842579 88.303196)
		(end 200.842579 89.638516)
		(width 0.15)
		(layer "In7.Cu")
		(net 596)
	)
	(segment
		(start 134.643032 83.8375)
		(end 134.643032 83.662512)
		(width 0.15)
		(layer "In7.Cu")
		(net 596)
	)
	(segment
		(start 201.267579 89.638516)
		(end 201.267579 88.653192)
		(width 0.15)
		(layer "In7.Cu")
		(net 596)
	)
	(segment
		(start 202.242579 88.653192)
		(end 202.242579 88.690856)
		(width 0.15)
		(layer "In7.Cu")
		(net 596)
	)
	(segment
		(start 148.177812 88.833356)
		(end 199.025079 88.833356)
		(width 0.15)
		(layer "In7.Cu")
		(net 596)
	)
	(segment
		(start 200.285079 87.885696)
		(end 200.425079 87.885696)
		(width 0.15)
		(layer "In7.Cu")
		(net 596)
	)
	(segment
		(start 134.330532 84.15)
		(end 134.643032 83.8375)
		(width 0.15)
		(layer "In7.Cu")
		(net 596)
	)
	(segment
		(start 146.2875 86.943044)
		(end 148.177812 88.833356)
		(width 0.15)
		(layer "In7.Cu")
		(net 596)
	)
	(segment
		(start 199.585079 89.781034)
		(end 199.725079 89.781034)
		(width 0.15)
		(layer "In7.Cu")
		(net 596)
	)
	(segment
		(start 200.985079 89.781016)
		(end 201.125079 89.781016)
		(width 0.15)
		(layer "In7.Cu")
		(net 596)
	)
	(segment
		(start 201.685079 88.235692)
		(end 201.825079 88.235692)
		(width 0.15)
		(layer "In7.Cu")
		(net 596)
	)
	(segment
		(start 134.643032 83.662512)
		(end 135.143044 83.1625)
		(width 0.15)
		(layer "In7.Cu")
		(net 596)
	)
	(segment
		(start 145.406956 83.1625)
		(end 146.2875 84.043044)
		(width 0.15)
		(layer "In7.Cu")
		(net 596)
	)
	(segment
		(start 203.0375 88.833356)
		(end 203.2 88.670856)
		(width 0.15)
		(layer "In7.Cu")
		(net 596)
	)
	(segment
		(start 199.442579 89.250856)
		(end 199.442579 89.638534)
		(width 0.15)
		(layer "In7.Cu")
		(net 596)
	)
	(arc
		(start 202.242579 88.690856)
		(mid 202.284316 88.791619)
		(end 202.385079 88.833356)
		(width 0.15)
		(layer "In7.Cu")
		(net 596)
	)
	(arc
		(start 199.025079 88.833356)
		(mid 199.320296 88.955639)
		(end 199.442579 89.250856)
		(width 0.15)
		(layer "In7.Cu")
		(net 596)
	)
	(arc
		(start 201.125079 89.781016)
		(mid 201.225842 89.739279)
		(end 201.267579 89.638516)
		(width 0.15)
		(layer "In7.Cu")
		(net 596)
	)
	(arc
		(start 199.867579 88.303196)
		(mid 199.989862 88.007979)
		(end 200.285079 87.885696)
		(width 0.15)
		(layer "In7.Cu")
		(net 596)
	)
	(arc
		(start 201.267579 88.653192)
		(mid 201.389862 88.357975)
		(end 201.685079 88.235692)
		(width 0.15)
		(layer "In7.Cu")
		(net 596)
	)
	(arc
		(start 201.825079 88.235692)
		(mid 202.120296 88.357975)
		(end 202.242579 88.653192)
		(width 0.15)
		(layer "In7.Cu")
		(net 596)
	)
	(arc
		(start 200.425079 87.885696)
		(mid 200.720296 88.007979)
		(end 200.842579 88.303196)
		(width 0.15)
		(layer "In7.Cu")
		(net 596)
	)
	(arc
		(start 199.725079 89.781034)
		(mid 199.825842 89.739297)
		(end 199.867579 89.638534)
		(width 0.15)
		(layer "In7.Cu")
		(net 596)
	)
	(arc
		(start 200.842579 89.638516)
		(mid 200.884316 89.739279)
		(end 200.985079 89.781016)
		(width 0.15)
		(layer "In7.Cu")
		(net 596)
	)
	(arc
		(start 199.442579 89.638534)
		(mid 199.484316 89.739297)
		(end 199.585079 89.781034)
		(width 0.15)
		(layer "In7.Cu")
		(net 596)
	)
	(segment
		(start 206.27 89.470856)
		(end 206.245 89.470856)
		(width 0.19)
		(layer "F.Cu")
		(net 597)
	)
	(segment
		(start 205.93 89.155856)
		(end 203.315 89.155856)
		(width 0.19)
		(layer "F.Cu")
		(net 597)
	)
	(segment
		(start 203.315 89.155856)
		(end 203.2 89.270856)
		(width 0.19)
		(layer "F.Cu")
		(net 597)
	)
	(segment
		(start 206.245 89.470856)
		(end 205.93 89.155856)
		(width 0.19)
		(layer "F.Cu")
		(net 597)
	)
	(via
		(at 135.230532 84.15)
		(size 0.45)
		(drill 0.1)
		(layers "F.Cu" "B.Cu")
		(net 597)
	)
	(via
		(at 203.2 89.270856)
		(size 0.45)
		(drill 0.1)
		(layers "F.Cu" "B.Cu")
		(net 597)
	)
	(segment
		(start 146.0125 87.056956)
		(end 148.0639 89.108356)
		(width 0.15)
		(layer "In7.Cu")
		(net 597)
	)
	(segment
		(start 200.142579 89.638534)
		(end 200.142579 88.303196)
		(width 0.15)
		(layer "In7.Cu")
		(net 597)
	)
	(segment
		(start 199.167579 89.250856)
		(end 199.167579 89.638534)
		(width 0.15)
		(layer "In7.Cu")
		(net 597)
	)
	(segment
		(start 201.542579 89.638516)
		(end 201.542579 88.653192)
		(width 0.15)
		(layer "In7.Cu")
		(net 597)
	)
	(segment
		(start 201.967579 88.653192)
		(end 201.967579 88.690856)
		(width 0.15)
		(layer "In7.Cu")
		(net 597)
	)
	(segment
		(start 137.898654 83.4375)
		(end 145.293044 83.4375)
		(width 0.15)
		(layer "In7.Cu")
		(net 597)
	)
	(segment
		(start 202.385079 89.108356)
		(end 203.0375 89.108356)
		(width 0.15)
		(layer "In7.Cu")
		(net 597)
	)
	(segment
		(start 134.918032 83.776424)
		(end 135.256956 83.4375)
		(width 0.15)
		(layer "In7.Cu")
		(net 597)
	)
	(segment
		(start 145.293044 83.4375)
		(end 146.0125 84.156956)
		(width 0.15)
		(layer "In7.Cu")
		(net 597)
	)
	(segment
		(start 135.230532 84.15)
		(end 134.918032 83.8375)
		(width 0.15)
		(layer "In7.Cu")
		(net 597)
	)
	(segment
		(start 137.448654 83.819757)
		(end 137.538654 83.819757)
		(width 0.15)
		(layer "In7.Cu")
		(net 597)
	)
	(segment
		(start 200.567579 88.303196)
		(end 200.567579 89.638516)
		(width 0.15)
		(layer "In7.Cu")
		(net 597)
	)
	(segment
		(start 200.285079 88.160696)
		(end 200.425079 88.160696)
		(width 0.15)
		(layer "In7.Cu")
		(net 597)
	)
	(segment
		(start 137.718654 83.639757)
		(end 137.718654 83.6175)
		(width 0.15)
		(layer "In7.Cu")
		(net 597)
	)
	(segment
		(start 146.0125 84.156956)
		(end 146.0125 87.056956)
		(width 0.15)
		(layer "In7.Cu")
		(net 597)
	)
	(segment
		(start 200.985079 90.056016)
		(end 201.125079 90.056016)
		(width 0.15)
		(layer "In7.Cu")
		(net 597)
	)
	(segment
		(start 134.918032 83.8375)
		(end 134.918032 83.776424)
		(width 0.15)
		(layer "In7.Cu")
		(net 597)
	)
	(segment
		(start 137.268654 83.6175)
		(end 137.268654 83.639757)
		(width 0.15)
		(layer "In7.Cu")
		(net 597)
	)
	(segment
		(start 135.256956 83.4375)
		(end 137.088654 83.4375)
		(width 0.15)
		(layer "In7.Cu")
		(net 597)
	)
	(segment
		(start 201.685079 88.510692)
		(end 201.825079 88.510692)
		(width 0.15)
		(layer "In7.Cu")
		(net 597)
	)
	(segment
		(start 203.0375 89.108356)
		(end 203.2 89.270856)
		(width 0.15)
		(layer "In7.Cu")
		(net 597)
	)
	(segment
		(start 199.585079 90.056034)
		(end 199.725079 90.056034)
		(width 0.15)
		(layer "In7.Cu")
		(net 597)
	)
	(segment
		(start 148.0639 89.108356)
		(end 199.025079 89.108356)
		(width 0.15)
		(layer "In7.Cu")
		(net 597)
	)
	(arc
		(start 199.725079 90.056034)
		(mid 200.020296 89.933751)
		(end 200.142579 89.638534)
		(width 0.15)
		(layer "In7.Cu")
		(net 597)
	)
	(arc
		(start 199.025079 89.108356)
		(mid 199.125842 89.150093)
		(end 199.167579 89.250856)
		(width 0.15)
		(layer "In7.Cu")
		(net 597)
	)
	(arc
		(start 137.268654 83.639757)
		(mid 137.321375 83.767036)
		(end 137.448654 83.819757)
		(width 0.15)
		(layer "In7.Cu")
		(net 597)
	)
	(arc
		(start 200.142579 88.303196)
		(mid 200.184316 88.202433)
		(end 200.285079 88.160696)
		(width 0.15)
		(layer "In7.Cu")
		(net 597)
	)
	(arc
		(start 200.425079 88.160696)
		(mid 200.525842 88.202433)
		(end 200.567579 88.303196)
		(width 0.15)
		(layer "In7.Cu")
		(net 597)
	)
	(arc
		(start 201.825079 88.510692)
		(mid 201.925842 88.552429)
		(end 201.967579 88.653192)
		(width 0.15)
		(layer "In7.Cu")
		(net 597)
	)
	(arc
		(start 137.538654 83.819757)
		(mid 137.665933 83.767036)
		(end 137.718654 83.639757)
		(width 0.15)
		(layer "In7.Cu")
		(net 597)
	)
	(arc
		(start 201.967579 88.690856)
		(mid 202.089862 88.986073)
		(end 202.385079 89.108356)
		(width 0.15)
		(layer "In7.Cu")
		(net 597)
	)
	(arc
		(start 200.567579 89.638516)
		(mid 200.689862 89.933733)
		(end 200.985079 90.056016)
		(width 0.15)
		(layer "In7.Cu")
		(net 597)
	)
	(arc
		(start 201.542579 88.653192)
		(mid 201.584316 88.552429)
		(end 201.685079 88.510692)
		(width 0.15)
		(layer "In7.Cu")
		(net 597)
	)
	(arc
		(start 137.718654 83.6175)
		(mid 137.771375 83.490221)
		(end 137.898654 83.4375)
		(width 0.15)
		(layer "In7.Cu")
		(net 597)
	)
	(arc
		(start 137.088654 83.4375)
		(mid 137.215933 83.490221)
		(end 137.268654 83.6175)
		(width 0.15)
		(layer "In7.Cu")
		(net 597)
	)
	(arc
		(start 201.125079 90.056016)
		(mid 201.420296 89.933733)
		(end 201.542579 89.638516)
		(width 0.15)
		(layer "In7.Cu")
		(net 597)
	)
	(arc
		(start 199.167579 89.638534)
		(mid 199.289862 89.933751)
		(end 199.585079 90.056034)
		(width 0.15)
		(layer "In7.Cu")
		(net 597)
	)
	(segment
		(start 118.695532 83.485)
		(end 118.580532 83.6)
		(width 0.19)
		(layer "F.Cu")
		(net 598)
	)
	(segment
		(start 118.695532 82.915)
		(end 118.695532 83.485)
		(width 0.19)
		(layer "F.Cu")
		(net 598)
	)
	(segment
		(start 118.430532 82.65)
		(end 118.695532 82.915)
		(width 0.19)
		(layer "F.Cu")
		(net 598)
	)
	(segment
		(start 210.1925 104.9725)
		(end 209.115 104.9725)
		(width 0.19)
		(layer "F.Cu")
		(net 598)
	)
	(segment
		(start 210.495 105.275)
		(end 210.1925 104.9725)
		(width 0.19)
		(layer "F.Cu")
		(net 598)
	)
	(segment
		(start 210.52 105.275)
		(end 210.495 105.275)
		(width 0.19)
		(layer "F.Cu")
		(net 598)
	)
	(segment
		(start 209.115 104.9725)
		(end 209 105.0875)
		(width 0.19)
		(layer "F.Cu")
		(net 598)
	)
	(via
		(at 118.580532 83.6)
		(size 0.45)
		(drill 0.1)
		(layers "F.Cu" "B.Cu")
		(net 598)
	)
	(via
		(at 209 105.0875)
		(size 0.45)
		(drill 0.1)
		(layers "F.Cu" "B.Cu")
		(net 598)
	)
	(segment
		(start 117.044759 65.760785)
		(end 114.7625 68.043044)
		(width 0.15)
		(layer "In7.Cu")
		(net 598)
	)
	(segment
		(start 115.4825 74.456956)
		(end 116.863044 75.8375)
		(width 0.15)
		(layer "In7.Cu")
		(net 598)
	)
	(segment
		(start 209.1625 104.925)
		(end 212.069456 104.925)
		(width 0.15)
		(layer "In7.Cu")
		(net 598)
	)
	(segment
		(start 188.194456 80.2)
		(end 184.794456 80.2)
		(width 0.15)
		(layer "In7.Cu")
		(net 598)
	)
	(segment
		(start 216.3375 93.943044)
		(end 215.9375 93.543044)
		(width 0.15)
		(layer "In7.Cu")
		(net 598)
	)
	(segment
		(start 209 105.0875)
		(end 209.1625 104.925)
		(width 0.15)
		(layer "In7.Cu")
		(net 598)
	)
	(segment
		(start 215.9375 93.543044)
		(end 215.9375 91.543044)
		(width 0.15)
		(layer "In7.Cu")
		(net 598)
	)
	(segment
		(start 118.743032 79.812512)
		(end 118.743032 83.4375)
		(width 0.15)
		(layer "In7.Cu")
		(net 598)
	)
	(segment
		(start 189.656956 81.6625)
		(end 188.194456 80.2)
		(width 0.15)
		(layer "In7.Cu")
		(net 598)
	)
	(segment
		(start 146.1375 75.943044)
		(end 146.1375 75.043044)
		(width 0.15)
		(layer "In7.Cu")
		(net 598)
	)
	(segment
		(start 115.4825 73.126956)
		(end 115.4825 74.456956)
		(width 0.15)
		(layer "In7.Cu")
		(net 598)
	)
	(segment
		(start 214.4375 99.156956)
		(end 216.3375 97.256956)
		(width 0.15)
		(layer "In7.Cu")
		(net 598)
	)
	(segment
		(start 200.943044 83.8625)
		(end 199.256956 83.8625)
		(width 0.15)
		(layer "In7.Cu")
		(net 598)
	)
	(segment
		(start 118.743032 83.4375)
		(end 118.580532 83.6)
		(width 0.15)
		(layer "In7.Cu")
		(net 598)
	)
	(segment
		(start 141.956956 74.2625)
		(end 141.5375 73.843044)
		(width 0.15)
		(layer "In7.Cu")
		(net 598)
	)
	(segment
		(start 216.3375 97.256956)
		(end 216.3375 93.943044)
		(width 0.15)
		(layer "In7.Cu")
		(net 598)
	)
	(segment
		(start 197.056956 81.6625)
		(end 189.656956 81.6625)
		(width 0.15)
		(layer "In7.Cu")
		(net 598)
	)
	(segment
		(start 214.4375 102.556956)
		(end 214.4375 99.156956)
		(width 0.15)
		(layer "In7.Cu")
		(net 598)
	)
	(segment
		(start 201.743044 83.0625)
		(end 200.943044 83.8625)
		(width 0.15)
		(layer "In7.Cu")
		(net 598)
	)
	(segment
		(start 184.794456 80.2)
		(end 181.756956 77.1625)
		(width 0.15)
		(layer "In7.Cu")
		(net 598)
	)
	(segment
		(start 141.5375 73.843044)
		(end 141.5375 71.49859)
		(width 0.15)
		(layer "In7.Cu")
		(net 598)
	)
	(segment
		(start 199.256956 83.8625)
		(end 197.056956 81.6625)
		(width 0.15)
		(layer "In7.Cu")
		(net 598)
	)
	(segment
		(start 114.7625 72.406956)
		(end 115.4825 73.126956)
		(width 0.15)
		(layer "In7.Cu")
		(net 598)
	)
	(segment
		(start 118.143044 75.8375)
		(end 119.9625 77.656956)
		(width 0.15)
		(layer "In7.Cu")
		(net 598)
	)
	(segment
		(start 212.069456 104.925)
		(end 214.4375 102.556956)
		(width 0.15)
		(layer "In7.Cu")
		(net 598)
	)
	(segment
		(start 181.756956 77.1625)
		(end 147.356956 77.1625)
		(width 0.15)
		(layer "In7.Cu")
		(net 598)
	)
	(segment
		(start 119.9625 77.656956)
		(end 119.9625 78.593044)
		(width 0.15)
		(layer "In7.Cu")
		(net 598)
	)
	(segment
		(start 135.799695 65.760785)
		(end 117.044759 65.760785)
		(width 0.15)
		(layer "In7.Cu")
		(net 598)
	)
	(segment
		(start 116.863044 75.8375)
		(end 118.143044 75.8375)
		(width 0.15)
		(layer "In7.Cu")
		(net 598)
	)
	(segment
		(start 119.9625 78.593044)
		(end 118.743032 79.812512)
		(width 0.15)
		(layer "In7.Cu")
		(net 598)
	)
	(segment
		(start 145.356956 74.2625)
		(end 141.956956 74.2625)
		(width 0.15)
		(layer "In7.Cu")
		(net 598)
	)
	(segment
		(start 147.356956 77.1625)
		(end 146.1375 75.943044)
		(width 0.15)
		(layer "In7.Cu")
		(net 598)
	)
	(segment
		(start 146.1375 75.043044)
		(end 145.356956 74.2625)
		(width 0.15)
		(layer "In7.Cu")
		(net 598)
	)
	(segment
		(start 207.456956 83.0625)
		(end 201.743044 83.0625)
		(width 0.15)
		(layer "In7.Cu")
		(net 598)
	)
	(segment
		(start 141.5375 71.49859)
		(end 135.799695 65.760785)
		(width 0.15)
		(layer "In7.Cu")
		(net 598)
	)
	(segment
		(start 215.9375 91.543044)
		(end 207.456956 83.0625)
		(width 0.15)
		(layer "In7.Cu")
		(net 598)
	)
	(segment
		(start 114.7625 68.043044)
		(end 114.7625 72.406956)
		(width 0.15)
		(layer "In7.Cu")
		(net 598)
	)
	(segment
		(start 75.000002 98.324264)
		(end 75.000002 95.950002)
		(width 0.1)
		(layer "F.Cu")
		(net 600)
	)
	(segment
		(start 87.6 118)
		(end 87.269669 118)
		(width 0.1)
		(layer "F.Cu")
		(net 600)
	)
	(segment
		(start 137.9 79)
		(end 140.6 79)
		(width 0.1)
		(layer "F.Cu")
		(net 600)
	)
	(segment
		(start 75.475736 98.799998)
		(end 75.000002 98.324264)
		(width 0.1)
		(layer "F.Cu")
		(net 600)
	)
	(segment
		(start 130.6 79.1)
		(end 130.3 78.8)
		(width 0.1)
		(layer "F.Cu")
		(net 600)
	)
	(segment
		(start 82.600001 116.150001)
		(end 82.600001 111.700001)
		(width 0.1)
		(layer "F.Cu")
		(net 600)
	)
	(segment
		(start 78.575736 101.299998)
		(end 76.075736 98.799998)
		(width 0.1)
		(layer "F.Cu")
		(net 600)
	)
	(segment
		(start 134.3 79.1)
		(end 134.8 78.6)
		(width 0.1)
		(layer "F.Cu")
		(net 600)
	)
	(segment
		(start 75.000002 95.950002)
		(end 74.5 95.45)
		(width 0.1)
		(layer "F.Cu")
		(net 600)
	)
	(segment
		(start 141.530532 81.15)
		(end 140.9 80.519468)
		(width 0.1)
		(layer "F.Cu")
		(net 600)
	)
	(segment
		(start 88.1 118.5)
		(end 87.6 118)
		(width 0.1)
		(layer "F.Cu")
		(net 600)
	)
	(segment
		(start 140.9 80.519468)
		(end 140.9 79.3)
		(width 0.1)
		(layer "F.Cu")
		(net 600)
	)
	(segment
		(start 134.9 77.7)
		(end 134.8 77.8)
		(width 0.1)
		(layer "F.Cu")
		(net 600)
	)
	(segment
		(start 137.430532 78.530532)
		(end 137.9 79)
		(width 0.1)
		(layer "F.Cu")
		(net 600)
	)
	(segment
		(start 87.269669 118)
		(end 85.769669 116.5)
		(width 0.1)
		(layer "F.Cu")
		(net 600)
	)
	(segment
		(start 82.3 111.4)
		(end 81.7 111.4)
		(width 0.1)
		(layer "F.Cu")
		(net 600)
	)
	(segment
		(start 80.475736 110.2)
		(end 80.100001 109.824265)
		(width 0.1)
		(layer "F.Cu")
		(net 600)
	)
	(segment
		(start 130.6 79.1)
		(end 134.3 79.1)
		(width 0.1)
		(layer "F.Cu")
		(net 600)
	)
	(segment
		(start 82.95 116.5)
		(end 85.769669 116.5)
		(width 0.1)
		(layer "F.Cu")
		(net 600)
	)
	(segment
		(start 76.075736 98.799998)
		(end 75.475736 98.799998)
		(width 0.1)
		(layer "F.Cu")
		(net 600)
	)
	(segment
		(start 82.600001 111.700001)
		(end 82.3 111.4)
		(width 0.1)
		(layer "F.Cu")
		(net 600)
	)
	(segment
		(start 137.430532 78.530532)
		(end 137.430532 77.830532)
		(width 0.1)
		(layer "F.Cu")
		(net 600)
	)
	(segment
		(start 81.7 111.4)
		(end 81.4 111.1)
		(width 0.1)
		(layer "F.Cu")
		(net 600)
	)
	(segment
		(start 82.95 116.5)
		(end 82.600001 116.150001)
		(width 0.1)
		(layer "F.Cu")
		(net 600)
	)
	(segment
		(start 140.6 79)
		(end 140.9 79.3)
		(width 0.1)
		(layer "F.Cu")
		(net 600)
	)
	(segment
		(start 80.100001 101.624263)
		(end 79.775736 101.299998)
		(width 0.1)
		(layer "F.Cu")
		(net 600)
	)
	(segment
		(start 134.8 77.8)
		(end 134.8 78.6)
		(width 0.1)
		(layer "F.Cu")
		(net 600)
	)
	(segment
		(start 80.100001 109.824265)
		(end 80.100001 101.624263)
		(width 0.1)
		(layer "F.Cu")
		(net 600)
	)
	(segment
		(start 88.1 118.525)
		(end 88.1 118.5)
		(width 0.1)
		(layer "F.Cu")
		(net 600)
	)
	(segment
		(start 80.9 110.2)
		(end 80.475736 110.2)
		(width 0.1)
		(layer "F.Cu")
		(net 600)
	)
	(segment
		(start 81.4 110.7)
		(end 80.9 110.2)
		(width 0.1)
		(layer "F.Cu")
		(net 600)
	)
	(segment
		(start 137.430532 77.830532)
		(end 137.3 77.7)
		(width 0.1)
		(layer "F.Cu")
		(net 600)
	)
	(segment
		(start 137.3 77.7)
		(end 134.9 77.7)
		(width 0.1)
		(layer "F.Cu")
		(net 600)
	)
	(segment
		(start 79.775736 101.299998)
		(end 78.575736 101.299998)
		(width 0.1)
		(layer "F.Cu")
		(net 600)
	)
	(segment
		(start 81.4 111.1)
		(end 81.4 110.7)
		(width 0.1)
		(layer "F.Cu")
		(net 600)
	)
	(via
		(at 112 109)
		(size 0.45)
		(drill 0.1)
		(layers "F.Cu" "B.Cu")
		(net 600)
	)
	(via
		(at 130.3 78.8)
		(size 0.45)
		(drill 0.1)
		(layers "F.Cu" "B.Cu")
		(net 600)
	)
	(via
		(at 123.1 91.2)
		(size 0.45)
		(drill 0.1)
		(layers "F.Cu" "B.Cu")
		(net 600)
	)
	(via
		(at 88.1 118.525)
		(size 0.45)
		(drill 0.1)
		(layers "F.Cu" "B.Cu")
		(net 600)
	)
	(via
		(at 74.5 95.45)
		(size 0.45)
		(drill 0.1)
		(layers "F.Cu" "B.Cu")
		(net 600)
	)
	(segment
		(start 130.3 78.8)
		(end 131 79.5)
		(width 0.1)
		(layer "In5.Cu")
		(net 600)
	)
	(segment
		(start 131.2 82.325)
		(end 130.975 82.55)
		(width 0.1)
		(layer "In5.Cu")
		(net 600)
	)
	(segment
		(start 131 80.1)
		(end 131.2 80.3)
		(width 0.1)
		(layer "In5.Cu")
		(net 600)
	)
	(segment
		(start 111.5 109)
		(end 112 109)
		(width 0.1)
		(layer "In5.Cu")
		(net 600)
	)
	(segment
		(start 97.75 117.05)
		(end 99.8 117.05)
		(width 0.1)
		(layer "In5.Cu")
		(net 600)
	)
	(segment
		(start 130.975 82.55)
		(end 130.975 83.669468)
		(width 0.1)
		(layer "In5.Cu")
		(net 600)
	)
	(segment
		(start 105.6 108.1)
		(end 110.6 108.1)
		(width 0.1)
		(layer "In5.Cu")
		(net 600)
	)
	(segment
		(start 101.25 112.95)
		(end 103.7 110.5)
		(width 0.1)
		(layer "In5.Cu")
		(net 600)
	)
	(segment
		(start 131.2 80.3)
		(end 131.2 82.325)
		(width 0.1)
		(layer "In5.Cu")
		(net 600)
	)
	(segment
		(start 88.1 118.525)
		(end 88.325 118.75)
		(width 0.1)
		(layer "In5.Cu")
		(net 600)
	)
	(segment
		(start 130.975 83.669468)
		(end 131.805532 84.5)
		(width 0.1)
		(layer "In5.Cu")
		(net 600)
	)
	(segment
		(start 110.6 108.1)
		(end 111.5 109)
		(width 0.1)
		(layer "In5.Cu")
		(net 600)
	)
	(segment
		(start 88.325 118.75)
		(end 96.05 118.75)
		(width 0.1)
		(layer "In5.Cu")
		(net 600)
	)
	(segment
		(start 101.25 115.6)
		(end 101.25 112.95)
		(width 0.1)
		(layer "In5.Cu")
		(net 600)
	)
	(segment
		(start 99.8 117.05)
		(end 101.25 115.6)
		(width 0.1)
		(layer "In5.Cu")
		(net 600)
	)
	(segment
		(start 131.805532 85.794468)
		(end 126.4 91.2)
		(width 0.1)
		(layer "In5.Cu")
		(net 600)
	)
	(segment
		(start 103.7 110)
		(end 105.6 108.1)
		(width 0.1)
		(layer "In5.Cu")
		(net 600)
	)
	(segment
		(start 126.4 91.2)
		(end 123.1 91.2)
		(width 0.1)
		(layer "In5.Cu")
		(net 600)
	)
	(segment
		(start 131.805532 84.5)
		(end 131.805532 85.794468)
		(width 0.1)
		(layer "In5.Cu")
		(net 600)
	)
	(segment
		(start 96.05 118.75)
		(end 97.75 117.05)
		(width 0.1)
		(layer "In5.Cu")
		(net 600)
	)
	(segment
		(start 103.7 110.5)
		(end 103.7 110)
		(width 0.1)
		(layer "In5.Cu")
		(net 600)
	)
	(segment
		(start 131 79.5)
		(end 131 80.1)
		(width 0.1)
		(layer "In5.Cu")
		(net 600)
	)
	(segment
		(start 112 109)
		(end 113 108)
		(width 0.1)
		(layer "In7.Cu")
		(net 600)
	)
	(segment
		(start 115.4 108)
		(end 120.9 102.5)
		(width 0.1)
		(layer "In7.Cu")
		(net 600)
	)
	(segment
		(start 120.9 92.4)
		(end 122.1 91.2)
		(width 0.1)
		(layer "In7.Cu")
		(net 600)
	)
	(segment
		(start 120.9 102.5)
		(end 120.9 92.4)
		(width 0.1)
		(layer "In7.Cu")
		(net 600)
	)
	(segment
		(start 113 108)
		(end 115.4 108)
		(width 0.1)
		(layer "In7.Cu")
		(net 600)
	)
	(segment
		(start 122.1 91.2)
		(end 123.1 91.2)
		(width 0.1)
		(layer "In7.Cu")
		(net 600)
	)
	(segment
		(start 130.530532 69.969468)
		(end 131 69.5)
		(width 0.1)
		(layer "F.Cu")
		(net 601)
	)
	(segment
		(start 131 69.5)
		(end 134 69.5)
		(width 0.1)
		(layer "F.Cu")
		(net 601)
	)
	(segment
		(start 130.530532 70.65)
		(end 130.530532 69.969468)
		(width 0.1)
		(layer "F.Cu")
		(net 601)
	)
	(via
		(at 134 69.5)
		(size 0.45)
		(drill 0.1)
		(layers "F.Cu" "B.Cu")
		(net 601)
	)
	(segment
		(start 133 69.5)
		(end 134 69.5)
		(width 0.1)
		(layer "B.Cu")
		(net 601)
	)
	(segment
		(start 91.115 97.87663)
		(end 91.115 98.517039)
		(width 0.19)
		(layer "B.Cu")
		(net 603)
	)
	(segment
		(start 86.385532 96.275)
		(end 87.748408 96.275)
		(width 0.19)
		(layer "B.Cu")
		(net 603)
	)
	(segment
		(start 90.234202 97.381207)
		(end 90.257184 97.358224)
		(width 0.19)
		(layer "B.Cu")
		(net 603)
	)
	(segment
		(start 92.995002 104.680001)
		(end 92.680003 104.995)
		(width 0.19)
		(layer "B.Cu")
		(net 603)
	)
	(segment
		(start 90.681449 97.443079)
		(end 91.115 97.87663)
		(width 0.19)
		(layer "B.Cu")
		(net 603)
	)
	(segment
		(start 90.596595 97.358224)
		(end 90.681449 97.443079)
		(width 0.19)
		(layer "B.Cu")
		(net 603)
	)
	(segment
		(start 89.832921 96.933962)
		(end 89.809938 96.956944)
		(width 0.19)
		(layer "B.Cu")
		(net 603)
	)
	(segment
		(start 92.995002 102.556632)
		(end 92.995002 104.680001)
		(width 0.19)
		(layer "B.Cu")
		(net 603)
	)
	(segment
		(start 87.748408 96.275)
		(end 87.758408 96.285)
		(width 0.19)
		(layer "B.Cu")
		(net 603)
	)
	(segment
		(start 85.935532 96.725)
		(end 86.385532 96.275)
		(width 0.19)
		(layer "B.Cu")
		(net 603)
	)
	(segment
		(start 89.52337 96.285)
		(end 89.832921 96.594551)
		(width 0.19)
		(layer "B.Cu")
		(net 603)
	)
	(segment
		(start 92.680003 104.995)
		(end 92.680003 105.02)
		(width 0.19)
		(layer "B.Cu")
		(net 603)
	)
	(segment
		(start 91.115 98.517039)
		(end 91.115 100.67663)
		(width 0.19)
		(layer "B.Cu")
		(net 603)
	)
	(segment
		(start 91.115 100.67663)
		(end 92.995002 102.556632)
		(width 0.19)
		(layer "B.Cu")
		(net 603)
	)
	(segment
		(start 87.758408 96.285)
		(end 89.52337 96.285)
		(width 0.19)
		(layer "B.Cu")
		(net 603)
	)
	(segment
		(start 89.809938 97.296355)
		(end 89.89479 97.381207)
		(width 0.19)
		(layer "B.Cu")
		(net 603)
	)
	(arc
		(start 89.809938 96.956944)
		(mid 89.739644 97.126649)
		(end 89.809938 97.296355)
		(width 0.19)
		(layer "B.Cu")
		(net 603)
	)
	(arc
		(start 90.257184 97.358224)
		(mid 90.426889 97.28793)
		(end 90.596595 97.358224)
		(width 0.19)
		(layer "B.Cu")
		(net 603)
	)
	(arc
		(start 89.89479 97.381207)
		(mid 90.064496 97.451502)
		(end 90.234202 97.381207)
		(width 0.19)
		(layer "B.Cu")
		(net 603)
	)
	(arc
		(start 89.832921 96.594551)
		(mid 89.903215 96.764257)
		(end 89.832921 96.933962)
		(width 0.19)
		(layer "B.Cu")
		(net 603)
	)
	(segment
		(start 84.2 65.4)
		(end 84.2 60.8)
		(width 0.1)
		(layer "F.Cu")
		(net 605)
	)
	(segment
		(start 86.6 67.8)
		(end 84.2 65.4)
		(width 0.1)
		(layer "F.Cu")
		(net 605)
	)
	(segment
		(start 84.2 60.8)
		(end 83.648 60.248)
		(width 0.1)
		(layer "F.Cu")
		(net 605)
	)
	(segment
		(start 134.830532 69.9)
		(end 134.5 69.9)
		(width 0.1)
		(layer "F.Cu")
		(net 605)
	)
	(segment
		(start 135.030532 70.1)
		(end 134.830532 69.9)
		(width 0.1)
		(layer "F.Cu")
		(net 605)
	)
	(segment
		(start 89.3 67.8)
		(end 86.6 67.8)
		(width 0.1)
		(layer "F.Cu")
		(net 605)
	)
	(segment
		(start 83.648 60.248)
		(end 82.86 60.248)
		(width 0.1)
		(layer "F.Cu")
		(net 605)
	)
	(segment
		(start 135.030532 70.65)
		(end 135.030532 70.1)
		(width 0.1)
		(layer "F.Cu")
		(net 605)
	)
	(via
		(at 134.5 69.9)
		(size 0.45)
		(drill 0.1)
		(layers "F.Cu" "B.Cu")
		(net 605)
	)
	(via
		(at 89.3 67.8)
		(size 0.45)
		(drill 0.1)
		(layers "F.Cu" "B.Cu")
		(net 605)
	)
	(segment
		(start 89.3 67.8)
		(end 90.1 67.8)
		(width 0.1)
		(layer "B.Cu")
		(net 605)
	)
	(segment
		(start 130.383256 70.399)
		(end 134.001 70.399)
		(width 0.1)
		(layer "In2.Cu")
		(net 605)
	)
	(segment
		(start 115.399 68.499)
		(end 115.4 68.5)
		(width 0.1)
		(layer "In2.Cu")
		(net 605)
	)
	(segment
		(start 90.3 70)
		(end 103.1 70)
		(width 0.1)
		(layer "In2.Cu")
		(net 605)
	)
	(segment
		(start 103.1 70)
		(end 103.901 69.199)
		(width 0.1)
		(layer "In2.Cu")
		(net 605)
	)
	(segment
		(start 114.916744 68.499)
		(end 115.399 68.499)
		(width 0.1)
		(layer "In2.Cu")
		(net 605)
	)
	(segment
		(start 89.3 69)
		(end 90.3 70)
		(width 0.1)
		(layer "In2.Cu")
		(net 605)
	)
	(segment
		(start 106.183256 69.999)
		(end 113.416744 69.999)
		(width 0.1)
		(layer "In2.Cu")
		(net 605)
	)
	(segment
		(start 115.4 68.5)
		(end 118.6 68.5)
		(width 0.1)
		(layer "In2.Cu")
		(net 605)
	)
	(segment
		(start 123.783256 69.999)
		(end 129.983256 69.999)
		(width 0.1)
		(layer "In2.Cu")
		(net 605)
	)
	(segment
		(start 105.383256 69.199)
		(end 106.183256 69.999)
		(width 0.1)
		(layer "In2.Cu")
		(net 605)
	)
	(segment
		(start 129.983256 69.999)
		(end 130.383256 70.399)
		(width 0.1)
		(layer "In2.Cu")
		(net 605)
	)
	(segment
		(start 89.3 67.8)
		(end 89.3 69)
		(width 0.1)
		(layer "In2.Cu")
		(net 605)
	)
	(segment
		(start 134.001 70.399)
		(end 134.5 69.9)
		(width 0.1)
		(layer "In2.Cu")
		(net 605)
	)
	(segment
		(start 118.6 68.5)
		(end 119.7 69.6)
		(width 0.1)
		(layer "In2.Cu")
		(net 605)
	)
	(segment
		(start 119.7 69.6)
		(end 123.384256 69.6)
		(width 0.1)
		(layer "In2.Cu")
		(net 605)
	)
	(segment
		(start 113.416744 69.999)
		(end 114.916744 68.499)
		(width 0.1)
		(layer "In2.Cu")
		(net 605)
	)
	(segment
		(start 103.901 69.199)
		(end 105.383256 69.199)
		(width 0.1)
		(layer "In2.Cu")
		(net 605)
	)
	(segment
		(start 123.384256 69.6)
		(end 123.783256 69.999)
		(width 0.1)
		(layer "In2.Cu")
		(net 605)
	)
	(via
		(at 141.530532 75.15)
		(size 0.45)
		(drill 0.1)
		(layers "F.Cu" "B.Cu")
		(net 606)
	)
	(segment
		(start 142.8 72.18)
		(end 142.32 72.18)
		(width 0.1)
		(layer "B.Cu")
		(net 606)
	)
	(segment
		(start 141.530532 72.969468)
		(end 141.530532 75.15)
		(width 0.1)
		(layer "B.Cu")
		(net 606)
	)
	(segment
		(start 142.32 72.18)
		(end 141.530532 72.969468)
		(width 0.1)
		(layer "B.Cu")
		(net 606)
	)
	(segment
		(start 213.805 94.92)
		(end 213.805 94.895)
		(width 0.19)
		(layer "F.Cu")
		(net 607)
	)
	(segment
		(start 214.17663 94.085)
		(end 214.649632 93.611998)
		(width 0.19)
		(layer "F.Cu")
		(net 607)
	)
	(segment
		(start 213.4875 94.5775)
		(end 213.4875 94.27413)
		(width 0.19)
		(layer "F.Cu")
		(net 607)
	)
	(segment
		(start 214.649632 93.611998)
		(end 214.649632 93.136857)
		(width 0.19)
		(layer "F.Cu")
		(net 607)
	)
	(segment
		(start 214.649632 93.136857)
		(end 214.665632 93.120857)
		(width 0.19)
		(layer "F.Cu")
		(net 607)
	)
	(segment
		(start 213.805 94.895)
		(end 213.4875 94.5775)
		(width 0.19)
		(layer "F.Cu")
		(net 607)
	)
	(segment
		(start 213.67663 94.085)
		(end 214.17663 94.085)
		(width 0.19)
		(layer "F.Cu")
		(net 607)
	)
	(segment
		(start 213.4875 94.27413)
		(end 213.67663 94.085)
		(width 0.19)
		(layer "F.Cu")
		(net 607)
	)
	(segment
		(start 214.665632 93.120857)
		(end 214.665632 92.670856)
		(width 0.19)
		(layer "F.Cu")
		(net 607)
	)
	(via
		(at 213.8 94.9)
		(size 0.45)
		(drill 0.1)
		(layers "F.Cu" "B.Cu")
		(net 607)
	)
	(segment
		(start 213.8 94.92)
		(end 213.8 94.9)
		(width 0.19)
		(layer "B.Cu")
		(net 607)
	)
	(via
		(at 142.230532 73.65)
		(size 0.45)
		(drill 0.1)
		(layers "F.Cu" "B.Cu")
		(net 609)
	)
	(segment
		(start 142.230532 73.96)
		(end 142.680532 74.41)
		(width 0.1)
		(layer "B.Cu")
		(net 609)
	)
	(segment
		(start 142.230532 73.65)
		(end 142.230532 73.96)
		(width 0.1)
		(layer "B.Cu")
		(net 609)
	)
	(segment
		(start 204.39 96.79)
		(end 203.45 95.85)
		(width 0.1)
		(layer "F.Cu")
		(net 610)
	)
	(segment
		(start 210.5 55)
		(end 210.5 55.698)
		(width 0.2)
		(layer "F.Cu")
		(net 610)
	)
	(segment
		(start 205.31 97.71)
		(end 204.39 96.79)
		(width 0.1)
		(layer "F.Cu")
		(net 610)
	)
	(segment
		(start 202.64 110.3)
		(end 203.872 110.3)
		(width 0.1)
		(layer "F.Cu")
		(net 610)
	)
	(segment
		(start 206.38 108.45)
		(end 206.38 103.1)
		(width 0.1)
		(layer "F.Cu")
		(net 610)
	)
	(segment
		(start 210.5 55.698)
		(end 210.651 55.849)
		(width 0.2)
		(layer "F.Cu")
		(net 610)
	)
	(segment
		(start 202.44 110.1)
		(end 202.64 110.3)
		(width 0.1)
		(layer "F.Cu")
		(net 610)
	)
	(segment
		(start 213.91 57.16)
		(end 212.599 55.849)
		(width 0.2)
		(layer "F.Cu")
		(net 610)
	)
	(segment
		(start 93.474 60.454)
		(end 93.52 60.5)
		(width 0.1)
		(layer "F.Cu")
		(net 610)
	)
	(segment
		(start 216.73 57.16)
		(end 213.91 57.16)
		(width 0.2)
		(layer "F.Cu")
		(net 610)
	)
	(segment
		(start 205.31 102.03)
		(end 205.31 97.71)
		(width 0.1)
		(layer "F.Cu")
		(net 610)
	)
	(segment
		(start 201.6 110.1)
		(end 202.44 110.1)
		(width 0.1)
		(layer "F.Cu")
		(net 610)
	)
	(segment
		(start 203.872 110.3)
		(end 204.53 110.3)
		(width 0.1)
		(layer "F.Cu")
		(net 610)
	)
	(segment
		(start 217.05 56.202001)
		(end 217.047999 56.202001)
		(width 0.2)
		(layer "F.Cu")
		(net 610)
	)
	(segment
		(start 212.599 55.849)
		(end 211.25 55.849)
		(width 0.2)
		(layer "F.Cu")
		(net 610)
	)
	(segment
		(start 93.52 59.5)
		(end 93 59.5)
		(width 0.1)
		(layer "F.Cu")
		(net 610)
	)
	(segment
		(start 210.651 55.849)
		(end 211.25 55.849)
		(width 0.2)
		(layer "F.Cu")
		(net 610)
	)
	(segment
		(start 93.52 60.5)
		(end 93.52 58.5)
		(width 0.1)
		(layer "F.Cu")
		(net 610)
	)
	(segment
		(start 92.1 60.454)
		(end 93.474 60.454)
		(width 0.1)
		(layer "F.Cu")
		(net 610)
	)
	(segment
		(start 204.53 110.3)
		(end 206.38 108.45)
		(width 0.1)
		(layer "F.Cu")
		(net 610)
	)
	(segment
		(start 217.047999 56.202001)
		(end 216.73 56.52)
		(width 0.2)
		(layer "F.Cu")
		(net 610)
	)
	(segment
		(start 216.73 56.52)
		(end 216.73 57.16)
		(width 0.2)
		(layer "F.Cu")
		(net 610)
	)
	(segment
		(start 206.38 103.1)
		(end 205.31 102.03)
		(width 0.1)
		(layer "F.Cu")
		(net 610)
	)
	(segment
		(start 203.45 95.85)
		(end 203.45 95.5)
		(width 0.1)
		(layer "F.Cu")
		(net 610)
	)
	(via
		(at 93 59.5)
		(size 0.45)
		(drill 0.1)
		(layers "F.Cu" "B.Cu")
		(net 610)
	)
	(via
		(at 210.5 55)
		(size 0.45)
		(drill 0.1)
		(layers "F.Cu" "B.Cu")
		(net 610)
	)
	(via
		(at 92.1 60.454)
		(size 0.45)
		(drill 0.1)
		(layers "F.Cu" "B.Cu")
		(net 610)
	)
	(via
		(at 216.73 57.16)
		(size 0.45)
		(drill 0.1)
		(layers "F.Cu" "B.Cu")
		(net 610)
	)
	(via
		(at 203.45 95.5)
		(size 0.45)
		(drill 0.1)
		(layers "F.Cu" "B.Cu")
		(net 610)
	)
	(segment
		(start 161.8 55.1)
		(end 210 55.1)
		(width 0.1)
		(layer "In5.Cu")
		(net 610)
	)
	(segment
		(start 160.3 56.6)
		(end 161.8 55.1)
		(width 0.1)
		(layer "In5.Cu")
		(net 610)
	)
	(segment
		(start 93 60.4)
		(end 93.5 60.9)
		(width 0.1)
		(layer "In5.Cu")
		(net 610)
	)
	(segment
		(start 195.51 90.59)
		(end 191.85 86.93)
		(width 0.1)
		(layer "In5.Cu")
		(net 610)
	)
	(segment
		(start 199.01 58.98)
		(end 214.91 58.98)
		(width 0.1)
		(layer "In5.Cu")
		(net 610)
	)
	(segment
		(start 196.69 90.59)
		(end 195.51 90.59)
		(width 0.1)
		(layer "In5.Cu")
		(net 610)
	)
	(segment
		(start 100 60.6)
		(end 107.63 60.6)
		(width 0.1)
		(layer "In5.Cu")
		(net 610)
	)
	(segment
		(start 198.29 60.77)
		(end 198.68 60.38)
		(width 0.1)
		(layer "In5.Cu")
		(net 610)
	)
	(segment
		(start 210 55.1)
		(end 210.1 55)
		(width 0.1)
		(layer "In5.Cu")
		(net 610)
	)
	(segment
		(start 99.7 60.9)
		(end 100 60.6)
		(width 0.1)
		(layer "In5.Cu")
		(net 610)
	)
	(segment
		(start 93 59.5)
		(end 93 60.4)
		(width 0.1)
		(layer "In5.Cu")
		(net 610)
	)
	(segment
		(start 198.68 60.38)
		(end 198.68 59.31)
		(width 0.1)
		(layer "In5.Cu")
		(net 610)
	)
	(segment
		(start 191.85 82.01)
		(end 192.540416 81.319584)
		(width 0.1)
		(layer "In5.Cu")
		(net 610)
	)
	(segment
		(start 198.68 59.31)
		(end 199.01 58.98)
		(width 0.1)
		(layer "In5.Cu")
		(net 610)
	)
	(segment
		(start 197.16 60.77)
		(end 198.29 60.77)
		(width 0.1)
		(layer "In5.Cu")
		(net 610)
	)
	(segment
		(start 154.4 67)
		(end 160.3 61.1)
		(width 0.1)
		(layer "In5.Cu")
		(net 610)
	)
	(segment
		(start 191.85 86.93)
		(end 191.85 82.01)
		(width 0.1)
		(layer "In5.Cu")
		(net 610)
	)
	(segment
		(start 193.030416 78.719584)
		(end 193.030416 72.319584)
		(width 0.1)
		(layer "In5.Cu")
		(net 610)
	)
	(segment
		(start 160.3 61.1)
		(end 160.3 56.6)
		(width 0.1)
		(layer "In5.Cu")
		(net 610)
	)
	(segment
		(start 108.52 59.71)
		(end 147.21 59.71)
		(width 0.1)
		(layer "In5.Cu")
		(net 610)
	)
	(segment
		(start 201.6 95.5)
		(end 196.69 90.59)
		(width 0.1)
		(layer "In5.Cu")
		(net 610)
	)
	(segment
		(start 150.8 67)
		(end 154.4 67)
		(width 0.1)
		(layer "In5.Cu")
		(net 610)
	)
	(segment
		(start 192.540416 81.319584)
		(end 192.540416 79.209584)
		(width 0.1)
		(layer "In5.Cu")
		(net 610)
	)
	(segment
		(start 194.980416 70.369584)
		(end 194.980416 62.949584)
		(width 0.1)
		(layer "In5.Cu")
		(net 610)
	)
	(segment
		(start 214.91 58.98)
		(end 216.73 57.16)
		(width 0.1)
		(layer "In5.Cu")
		(net 610)
	)
	(segment
		(start 203.45 95.5)
		(end 201.6 95.5)
		(width 0.1)
		(layer "In5.Cu")
		(net 610)
	)
	(segment
		(start 148.8 62.95)
		(end 148.8 65)
		(width 0.1)
		(layer "In5.Cu")
		(net 610)
	)
	(segment
		(start 193.030416 72.319584)
		(end 194.980416 70.369584)
		(width 0.1)
		(layer "In5.Cu")
		(net 610)
	)
	(segment
		(start 148.8 65)
		(end 150.8 67)
		(width 0.1)
		(layer "In5.Cu")
		(net 610)
	)
	(segment
		(start 147.21 59.71)
		(end 148.14 60.64)
		(width 0.1)
		(layer "In5.Cu")
		(net 610)
	)
	(segment
		(start 192.540416 79.209584)
		(end 193.030416 78.719584)
		(width 0.1)
		(layer "In5.Cu")
		(net 610)
	)
	(segment
		(start 148.14 60.64)
		(end 148.14 62.29)
		(width 0.1)
		(layer "In5.Cu")
		(net 610)
	)
	(segment
		(start 148.14 62.29)
		(end 148.8 62.95)
		(width 0.1)
		(layer "In5.Cu")
		(net 610)
	)
	(segment
		(start 194.980416 62.949584)
		(end 197.16 60.77)
		(width 0.1)
		(layer "In5.Cu")
		(net 610)
	)
	(segment
		(start 210.1 55)
		(end 210.5 55)
		(width 0.1)
		(layer "In5.Cu")
		(net 610)
	)
	(segment
		(start 93.5 60.9)
		(end 99.7 60.9)
		(width 0.1)
		(layer "In5.Cu")
		(net 610)
	)
	(segment
		(start 107.63 60.6)
		(end 108.52 59.71)
		(width 0.1)
		(layer "In5.Cu")
		(net 610)
	)
	(segment
		(start 212.100631 88.787856)
		(end 208 88.787856)
		(width 0.19)
		(layer "F.Cu")
		(net 612)
	)
	(segment
		(start 207.57 88.785856)
		(end 207.255 88.470856)
		(width 0.19)
		(layer "F.Cu")
		(net 612)
	)
	(segment
		(start 207.255 88.470856)
		(end 207.23 88.470856)
		(width 0.19)
		(layer "F.Cu")
		(net 612)
	)
	(segment
		(start 212.115631 88.772856)
		(end 212.100631 88.787856)
		(width 0.19)
		(layer "F.Cu")
		(net 612)
	)
	(segment
		(start 208 88.787856)
		(end 207.998 88.785856)
		(width 0.19)
		(layer "F.Cu")
		(net 612)
	)
	(segment
		(start 212.565632 88.772856)
		(end 212.115631 88.772856)
		(width 0.19)
		(layer "F.Cu")
		(net 612)
	)
	(segment
		(start 207.998 88.785856)
		(end 207.57 88.785856)
		(width 0.19)
		(layer "F.Cu")
		(net 612)
	)
	(segment
		(start 204.245 89.970856)
		(end 203.93 90.285856)
		(width 0.19)
		(layer "F.Cu")
		(net 615)
	)
	(segment
		(start 202.715 90.285856)
		(end 202.6 90.170856)
		(width 0.19)
		(layer "F.Cu")
		(net 615)
	)
	(segment
		(start 203.93 90.285856)
		(end 202.715 90.285856)
		(width 0.19)
		(layer "F.Cu")
		(net 615)
	)
	(segment
		(start 204.27 89.970856)
		(end 204.245 89.970856)
		(width 0.19)
		(layer "F.Cu")
		(net 615)
	)
	(via
		(at 202.6 90.170856)
		(size 0.45)
		(drill 0.1)
		(layers "F.Cu" "B.Cu")
		(net 615)
	)
	(via
		(at 134.130532 85.65)
		(size 0.45)
		(drill 0.1)
		(layers "F.Cu" "B.Cu")
		(net 615)
	)
	(segment
		(start 133.818032 86.123576)
		(end 134.056956 86.3625)
		(width 0.15)
		(layer "In7.Cu")
		(net 615)
	)
	(segment
		(start 135.87 86.3625)
		(end 138.256956 86.3625)
		(width 0.15)
		(layer "In7.Cu")
		(net 615)
	)
	(segment
		(start 199.033168 91.298031)
		(end 199.173168 91.298031)
		(width 0.15)
		(layer "In7.Cu")
		(net 615)
	)
	(segment
		(start 202.4375 90.333356)
		(end 202.6 90.170856)
		(width 0.15)
		(layer "In7.Cu")
		(net 615)
	)
	(segment
		(start 142.227812 90.333356)
		(end 194.273168 90.333356)
		(width 0.15)
		(layer "In7.Cu")
		(net 615)
	)
	(segment
		(start 134.130532 85.65)
		(end 133.818032 85.9625)
		(width 0.15)
		(layer "In7.Cu")
		(net 615)
	)
	(segment
		(start 194.415668 90.190856)
		(end 194.415668 89.786199)
		(width 0.15)
		(layer "In7.Cu")
		(net 615)
	)
	(segment
		(start 195.390668 89.786199)
		(end 195.390668 91.155549)
		(width 0.15)
		(layer "In7.Cu")
		(net 615)
	)
	(segment
		(start 197.633168 90.333356)
		(end 197.773168 90.333356)
		(width 0.15)
		(layer "In7.Cu")
		(net 615)
	)
	(segment
		(start 199.733168 90.333356)
		(end 202.4375 90.333356)
		(width 0.15)
		(layer "In7.Cu")
		(net 615)
	)
	(segment
		(start 196.933168 91.298049)
		(end 197.073168 91.298049)
		(width 0.15)
		(layer "In7.Cu")
		(net 615)
	)
	(segment
		(start 135.71 86.15734)
		(end 135.71 86.2025)
		(width 0.15)
		(layer "In7.Cu")
		(net 615)
	)
	(segment
		(start 196.790668 90.750856)
		(end 196.790668 91.155549)
		(width 0.15)
		(layer "In7.Cu")
		(net 615)
	)
	(segment
		(start 135.47 85.99734)
		(end 135.55 85.99734)
		(width 0.15)
		(layer "In7.Cu")
		(net 615)
	)
	(segment
		(start 198.333168 89.7687)
		(end 198.473168 89.7687)
		(width 0.15)
		(layer "In7.Cu")
		(net 615)
	)
	(segment
		(start 138.256956 86.3625)
		(end 142.227812 90.333356)
		(width 0.15)
		(layer "In7.Cu")
		(net 615)
	)
	(segment
		(start 198.890668 90.1862)
		(end 198.890668 91.155531)
		(width 0.15)
		(layer "In7.Cu")
		(net 615)
	)
	(segment
		(start 196.233168 90.333356)
		(end 196.373168 90.333356)
		(width 0.15)
		(layer "In7.Cu")
		(net 615)
	)
	(segment
		(start 134.056956 86.3625)
		(end 135.15 86.3625)
		(width 0.15)
		(layer "In7.Cu")
		(net 615)
	)
	(segment
		(start 195.533168 91.298049)
		(end 195.673168 91.298049)
		(width 0.15)
		(layer "In7.Cu")
		(net 615)
	)
	(segment
		(start 199.315668 91.155531)
		(end 199.315668 90.750856)
		(width 0.15)
		(layer "In7.Cu")
		(net 615)
	)
	(segment
		(start 135.31 86.2025)
		(end 135.31 86.15734)
		(width 0.15)
		(layer "In7.Cu")
		(net 615)
	)
	(segment
		(start 197.915668 90.190856)
		(end 197.915668 90.1862)
		(width 0.15)
		(layer "In7.Cu")
		(net 615)
	)
	(segment
		(start 197.215668 91.155549)
		(end 197.215668 90.750856)
		(width 0.15)
		(layer "In7.Cu")
		(net 615)
	)
	(segment
		(start 195.815668 91.155549)
		(end 195.815668 90.750856)
		(width 0.15)
		(layer "In7.Cu")
		(net 615)
	)
	(segment
		(start 194.833168 89.368699)
		(end 194.973168 89.368699)
		(width 0.15)
		(layer "In7.Cu")
		(net 615)
	)
	(segment
		(start 133.818032 85.9625)
		(end 133.818032 86.123576)
		(width 0.15)
		(layer "In7.Cu")
		(net 615)
	)
	(arc
		(start 135.31 86.15734)
		(mid 135.356863 86.044203)
		(end 135.47 85.99734)
		(width 0.15)
		(layer "In7.Cu")
		(net 615)
	)
	(arc
		(start 194.273168 90.333356)
		(mid 194.373931 90.291619)
		(end 194.415668 90.190856)
		(width 0.15)
		(layer "In7.Cu")
		(net 615)
	)
	(arc
		(start 196.373168 90.333356)
		(mid 196.668385 90.455639)
		(end 196.790668 90.750856)
		(width 0.15)
		(layer "In7.Cu")
		(net 615)
	)
	(arc
		(start 198.890668 91.155531)
		(mid 198.932405 91.256294)
		(end 199.033168 91.298031)
		(width 0.15)
		(layer "In7.Cu")
		(net 615)
	)
	(arc
		(start 199.173168 91.298031)
		(mid 199.273931 91.256294)
		(end 199.315668 91.155531)
		(width 0.15)
		(layer "In7.Cu")
		(net 615)
	)
	(arc
		(start 198.473168 89.7687)
		(mid 198.768385 89.890983)
		(end 198.890668 90.1862)
		(width 0.15)
		(layer "In7.Cu")
		(net 615)
	)
	(arc
		(start 135.55 85.99734)
		(mid 135.663137 86.044203)
		(end 135.71 86.15734)
		(width 0.15)
		(layer "In7.Cu")
		(net 615)
	)
	(arc
		(start 135.71 86.2025)
		(mid 135.756863 86.315637)
		(end 135.87 86.3625)
		(width 0.15)
		(layer "In7.Cu")
		(net 615)
	)
	(arc
		(start 196.790668 91.155549)
		(mid 196.832405 91.256312)
		(end 196.933168 91.298049)
		(width 0.15)
		(layer "In7.Cu")
		(net 615)
	)
	(arc
		(start 199.315668 90.750856)
		(mid 199.437951 90.455639)
		(end 199.733168 90.333356)
		(width 0.15)
		(layer "In7.Cu")
		(net 615)
	)
	(arc
		(start 195.815668 90.750856)
		(mid 195.937951 90.455639)
		(end 196.233168 90.333356)
		(width 0.15)
		(layer "In7.Cu")
		(net 615)
	)
	(arc
		(start 194.973168 89.368699)
		(mid 195.268385 89.490982)
		(end 195.390668 89.786199)
		(width 0.15)
		(layer "In7.Cu")
		(net 615)
	)
	(arc
		(start 197.773168 90.333356)
		(mid 197.873931 90.291619)
		(end 197.915668 90.190856)
		(width 0.15)
		(layer "In7.Cu")
		(net 615)
	)
	(arc
		(start 135.15 86.3625)
		(mid 135.263137 86.315637)
		(end 135.31 86.2025)
		(width 0.15)
		(layer "In7.Cu")
		(net 615)
	)
	(arc
		(start 197.215668 90.750856)
		(mid 197.337951 90.455639)
		(end 197.633168 90.333356)
		(width 0.15)
		(layer "In7.Cu")
		(net 615)
	)
	(arc
		(start 197.915668 90.1862)
		(mid 198.037951 89.890983)
		(end 198.333168 89.7687)
		(width 0.15)
		(layer "In7.Cu")
		(net 615)
	)
	(arc
		(start 195.390668 91.155549)
		(mid 195.432405 91.256312)
		(end 195.533168 91.298049)
		(width 0.15)
		(layer "In7.Cu")
		(net 615)
	)
	(arc
		(start 197.073168 91.298049)
		(mid 197.173931 91.256312)
		(end 197.215668 91.155549)
		(width 0.15)
		(layer "In7.Cu")
		(net 615)
	)
	(arc
		(start 195.673168 91.298049)
		(mid 195.773931 91.256312)
		(end 195.815668 91.155549)
		(width 0.15)
		(layer "In7.Cu")
		(net 615)
	)
	(arc
		(start 194.415668 89.786199)
		(mid 194.537951 89.490982)
		(end 194.833168 89.368699)
		(width 0.15)
		(layer "In7.Cu")
		(net 615)
	)
	(segment
		(start 204.27 90.970856)
		(end 204.245 90.970856)
		(width 0.19)
		(layer "F.Cu")
		(net 617)
	)
	(segment
		(start 202.715 90.655856)
		(end 202.6 90.770856)
		(width 0.19)
		(layer "F.Cu")
		(net 617)
	)
	(segment
		(start 204.245 90.970856)
		(end 203.93 90.655856)
		(width 0.19)
		(layer "F.Cu")
		(net 617)
	)
	(segment
		(start 203.93 90.655856)
		(end 202.715 90.655856)
		(width 0.19)
		(layer "F.Cu")
		(net 617)
	)
	(via
		(at 202.6 90.770856)
		(size 0.45)
		(drill 0.1)
		(layers "F.Cu" "B.Cu")
		(net 617)
	)
	(via
		(at 133.230532 85.65)
		(size 0.45)
		(drill 0.1)
		(layers "F.Cu" "B.Cu")
		(net 617)
	)
	(segment
		(start 195.115668 89.786199)
		(end 195.115668 91.155549)
		(width 0.15)
		(layer "In7.Cu")
		(net 617)
	)
	(segment
		(start 142.1139 90.608356)
		(end 194.273168 90.608356)
		(width 0.15)
		(layer "In7.Cu")
		(net 617)
	)
	(segment
		(start 196.515668 90.750856)
		(end 196.515668 91.155549)
		(width 0.15)
		(layer "In7.Cu")
		(net 617)
	)
	(segment
		(start 195.533168 91.573049)
		(end 195.673168 91.573049)
		(width 0.15)
		(layer "In7.Cu")
		(net 617)
	)
	(segment
		(start 133.543032 85.9625)
		(end 133.543032 86.237488)
		(width 0.15)
		(layer "In7.Cu")
		(net 617)
	)
	(segment
		(start 199.590668 91.155531)
		(end 199.590668 90.750856)
		(width 0.15)
		(layer "In7.Cu")
		(net 617)
	)
	(segment
		(start 133.543032 86.237488)
		(end 133.943044 86.6375)
		(width 0.15)
		(layer "In7.Cu")
		(net 617)
	)
	(segment
		(start 199.033168 91.573031)
		(end 199.173168 91.573031)
		(width 0.15)
		(layer "In7.Cu")
		(net 617)
	)
	(segment
		(start 197.633168 90.608356)
		(end 197.773168 90.608356)
		(width 0.15)
		(layer "In7.Cu")
		(net 617)
	)
	(segment
		(start 198.615668 90.1862)
		(end 198.615668 91.155531)
		(width 0.15)
		(layer "In7.Cu")
		(net 617)
	)
	(segment
		(start 197.490668 91.155549)
		(end 197.490668 90.750856)
		(width 0.15)
		(layer "In7.Cu")
		(net 617)
	)
	(segment
		(start 194.833168 89.643699)
		(end 194.973168 89.643699)
		(width 0.15)
		(layer "In7.Cu")
		(net 617)
	)
	(segment
		(start 133.943044 86.6375)
		(end 138.143044 86.6375)
		(width 0.15)
		(layer "In7.Cu")
		(net 617)
	)
	(segment
		(start 198.190668 90.190856)
		(end 198.190668 90.1862)
		(width 0.15)
		(layer "In7.Cu")
		(net 617)
	)
	(segment
		(start 199.733168 90.608356)
		(end 202.4375 90.608356)
		(width 0.15)
		(layer "In7.Cu")
		(net 617)
	)
	(segment
		(start 196.233168 90.608356)
		(end 196.373168 90.608356)
		(width 0.15)
		(layer "In7.Cu")
		(net 617)
	)
	(segment
		(start 194.690668 90.190856)
		(end 194.690668 89.786199)
		(width 0.15)
		(layer "In7.Cu")
		(net 617)
	)
	(segment
		(start 202.4375 90.608356)
		(end 202.6 90.770856)
		(width 0.15)
		(layer "In7.Cu")
		(net 617)
	)
	(segment
		(start 198.333168 90.0437)
		(end 198.473168 90.0437)
		(width 0.15)
		(layer "In7.Cu")
		(net 617)
	)
	(segment
		(start 196.933168 91.573049)
		(end 197.073168 91.573049)
		(width 0.15)
		(layer "In7.Cu")
		(net 617)
	)
	(segment
		(start 133.230532 85.65)
		(end 133.543032 85.9625)
		(width 0.15)
		(layer "In7.Cu")
		(net 617)
	)
	(segment
		(start 196.090668 91.155549)
		(end 196.090668 90.750856)
		(width 0.15)
		(layer "In7.Cu")
		(net 617)
	)
	(segment
		(start 138.143044 86.6375)
		(end 142.1139 90.608356)
		(width 0.15)
		(layer "In7.Cu")
		(net 617)
	)
	(arc
		(start 194.973168 89.643699)
		(mid 195.073931 89.685436)
		(end 195.115668 89.786199)
		(width 0.15)
		(layer "In7.Cu")
		(net 617)
	)
	(arc
		(start 195.115668 91.155549)
		(mid 195.237951 91.450766)
		(end 195.533168 91.573049)
		(width 0.15)
		(layer "In7.Cu")
		(net 617)
	)
	(arc
		(start 198.615668 91.155531)
		(mid 198.737951 91.450748)
		(end 199.033168 91.573031)
		(width 0.15)
		(layer "In7.Cu")
		(net 617)
	)
	(arc
		(start 196.090668 90.750856)
		(mid 196.132405 90.650093)
		(end 196.233168 90.608356)
		(width 0.15)
		(layer "In7.Cu")
		(net 617)
	)
	(arc
		(start 197.490668 90.750856)
		(mid 197.532405 90.650093)
		(end 197.633168 90.608356)
		(width 0.15)
		(layer "In7.Cu")
		(net 617)
	)
	(arc
		(start 199.590668 90.750856)
		(mid 199.632405 90.650093)
		(end 199.733168 90.608356)
		(width 0.15)
		(layer "In7.Cu")
		(net 617)
	)
	(arc
		(start 197.073168 91.573049)
		(mid 197.368385 91.450766)
		(end 197.490668 91.155549)
		(width 0.15)
		(layer "In7.Cu")
		(net 617)
	)
	(arc
		(start 198.473168 90.0437)
		(mid 198.573931 90.085437)
		(end 198.615668 90.1862)
		(width 0.15)
		(layer "In7.Cu")
		(net 617)
	)
	(arc
		(start 196.373168 90.608356)
		(mid 196.473931 90.650093)
		(end 196.515668 90.750856)
		(width 0.15)
		(layer "In7.Cu")
		(net 617)
	)
	(arc
		(start 196.515668 91.155549)
		(mid 196.637951 91.450766)
		(end 196.933168 91.573049)
		(width 0.15)
		(layer "In7.Cu")
		(net 617)
	)
	(arc
		(start 197.773168 90.608356)
		(mid 198.068385 90.486073)
		(end 198.190668 90.190856)
		(width 0.15)
		(layer "In7.Cu")
		(net 617)
	)
	(arc
		(start 194.690668 89.786199)
		(mid 194.732405 89.685436)
		(end 194.833168 89.643699)
		(width 0.15)
		(layer "In7.Cu")
		(net 617)
	)
	(arc
		(start 199.173168 91.573031)
		(mid 199.468385 91.450748)
		(end 199.590668 91.155531)
		(width 0.15)
		(layer "In7.Cu")
		(net 617)
	)
	(arc
		(start 198.190668 90.1862)
		(mid 198.232405 90.085437)
		(end 198.333168 90.0437)
		(width 0.15)
		(layer "In7.Cu")
		(net 617)
	)
	(arc
		(start 194.273168 90.608356)
		(mid 194.568385 90.486073)
		(end 194.690668 90.190856)
		(width 0.15)
		(layer "In7.Cu")
		(net 617)
	)
	(arc
		(start 195.673168 91.573049)
		(mid 195.968385 91.450766)
		(end 196.090668 91.155549)
		(width 0.15)
		(layer "In7.Cu")
		(net 617)
	)
	(segment
		(start 116.430532 72.15)
		(end 116.695532 71.885)
		(width 0.19)
		(layer "F.Cu")
		(net 618)
	)
	(segment
		(start 209.115 102.0525)
		(end 209 102.1675)
		(width 0.19)
		(layer "F.Cu")
		(net 618)
	)
	(segment
		(start 116.695532 71.885)
		(end 116.695532 71.515)
		(width 0.19)
		(layer "F.Cu")
		(net 618)
	)
	(segment
		(start 116.695532 71.515)
		(end 116.580532 71.4)
		(width 0.19)
		(layer "F.Cu")
		(net 618)
	)
	(segment
		(start 210.495 102.355)
		(end 210.1925 102.0525)
		(width 0.19)
		(layer "F.Cu")
		(net 618)
	)
	(segment
		(start 210.52 102.355)
		(end 210.495 102.355)
		(width 0.19)
		(layer "F.Cu")
		(net 618)
	)
	(segment
		(start 210.1925 102.0525)
		(end 209.115 102.0525)
		(width 0.19)
		(layer "F.Cu")
		(net 618)
	)
	(via
		(at 116.580532 71.4)
		(size 0.45)
		(drill 0.1)
		(layers "F.Cu" "B.Cu")
		(net 618)
	)
	(via
		(at 209 102.1675)
		(size 0.45)
		(drill 0.1)
		(layers "F.Cu" "B.Cu")
		(net 618)
	)
	(segment
		(start 146.256956 78.6625)
		(end 144.856956 77.2625)
		(width 0.15)
		(layer "In7.Cu")
		(net 618)
	)
	(segment
		(start 180.856956 78.6625)
		(end 146.256956 78.6625)
		(width 0.15)
		(layer "In7.Cu")
		(net 618)
	)
	(segment
		(start 210.789456 102.005)
		(end 212.1375 100.656956)
		(width 0.15)
		(layer "In7.Cu")
		(net 618)
	)
	(segment
		(start 144.856956 77.2625)
		(end 138.356956 77.2625)
		(width 0.15)
		(layer "In7.Cu")
		(net 618)
	)
	(segment
		(start 190.456956 84.5625)
		(end 187.506956 81.6125)
		(width 0.15)
		(layer "In7.Cu")
		(net 618)
	)
	(segment
		(start 214.7375 92.743044)
		(end 206.256956 84.2625)
		(width 0.15)
		(layer "In7.Cu")
		(net 618)
	)
	(segment
		(start 206.256956 84.2625)
		(end 201.643044 84.2625)
		(width 0.15)
		(layer "In7.Cu")
		(net 618)
	)
	(segment
		(start 212.1375 99.056956)
		(end 213.3375 97.856956)
		(width 0.15)
		(layer "In7.Cu")
		(net 618)
	)
	(segment
		(start 209 102.1675)
		(end 209.1625 102.005)
		(width 0.15)
		(layer "In7.Cu")
		(net 618)
	)
	(segment
		(start 201.343044 84.5625)
		(end 190.456956 84.5625)
		(width 0.15)
		(layer "In7.Cu")
		(net 618)
	)
	(segment
		(start 187.506956 81.6125)
		(end 183.806956 81.6125)
		(width 0.15)
		(layer "In7.Cu")
		(net 618)
	)
	(segment
		(start 212.1375 100.656956)
		(end 212.1375 99.056956)
		(width 0.15)
		(layer "In7.Cu")
		(net 618)
	)
	(segment
		(start 209.1625 102.005)
		(end 210.789456 102.005)
		(width 0.15)
		(layer "In7.Cu")
		(net 618)
	)
	(segment
		(start 138.6875 72.806956)
		(end 138.6875 70.648588)
		(width 0.15)
		(layer "In7.Cu")
		(net 618)
	)
	(segment
		(start 183.806956 81.6125)
		(end 180.856956 78.6625)
		(width 0.15)
		(layer "In7.Cu")
		(net 618)
	)
	(segment
		(start 214.7375 95.356956)
		(end 214.7375 92.743044)
		(width 0.15)
		(layer "In7.Cu")
		(net 618)
	)
	(segment
		(start 135.21391 67.174998)
		(end 117.630546 67.174998)
		(width 0.15)
		(layer "In7.Cu")
		(net 618)
	)
	(segment
		(start 116.743032 68.062512)
		(end 116.743032 71.2375)
		(width 0.15)
		(layer "In7.Cu")
		(net 618)
	)
	(segment
		(start 138.356956 77.2625)
		(end 138.1375 77.043044)
		(width 0.15)
		(layer "In7.Cu")
		(net 618)
	)
	(segment
		(start 138.1375 77.043044)
		(end 138.1375 73.356956)
		(width 0.15)
		(layer "In7.Cu")
		(net 618)
	)
	(segment
		(start 213.3375 97.856956)
		(end 213.3375 96.756956)
		(width 0.15)
		(layer "In7.Cu")
		(net 618)
	)
	(segment
		(start 138.6875 70.648588)
		(end 135.21391 67.174998)
		(width 0.15)
		(layer "In7.Cu")
		(net 618)
	)
	(segment
		(start 201.643044 84.2625)
		(end 201.343044 84.5625)
		(width 0.15)
		(layer "In7.Cu")
		(net 618)
	)
	(segment
		(start 117.630546 67.174998)
		(end 116.743032 68.062512)
		(width 0.15)
		(layer "In7.Cu")
		(net 618)
	)
	(segment
		(start 213.3375 96.756956)
		(end 214.7375 95.356956)
		(width 0.15)
		(layer "In7.Cu")
		(net 618)
	)
	(segment
		(start 116.743032 71.2375)
		(end 116.580532 71.4)
		(width 0.15)
		(layer "In7.Cu")
		(net 618)
	)
	(segment
		(start 138.1375 73.356956)
		(end 138.6875 72.806956)
		(width 0.15)
		(layer "In7.Cu")
		(net 618)
	)
	(segment
		(start 108.430532 84.15)
		(end 108.695532 84.415)
		(width 0.19)
		(layer "F.Cu")
		(net 620)
	)
	(segment
		(start 108.695532 84.985)
		(end 108.580532 85.1)
		(width 0.19)
		(layer "F.Cu")
		(net 620)
	)
	(segment
		(start 108.695532 84.415)
		(end 108.695532 84.985)
		(width 0.19)
		(layer "F.Cu")
		(net 620)
	)
	(via
		(at 108.580532 85.1)
		(size 0.45)
		(drill 0.1)
		(layers "F.Cu" "B.Cu")
		(net 620)
	)
	(segment
		(start 113.685 102.749)
		(end 113.06 102.749)
		(width 0.19)
		(layer "B.Cu")
		(net 620)
	)
	(segment
		(start 112.9955 102.6845)
		(end 107.340628 102.6845)
		(width 0.19)
		(layer "B.Cu")
		(net 620)
	)
	(segment
		(start 113.06 102.749)
		(end 112.9955 102.6845)
		(width 0.19)
		(layer "B.Cu")
		(net 620)
	)
	(segment
		(start 103.830501 88.907869)
		(end 106.62337 86.115)
		(width 0.19)
		(layer "B.Cu")
		(net 620)
	)
	(segment
		(start 108.42337 86.115)
		(end 108.695532 85.842838)
		(width 0.19)
		(layer "B.Cu")
		(net 620)
	)
	(segment
		(start 106.62337 86.115)
		(end 108.42337 86.115)
		(width 0.19)
		(layer "B.Cu")
		(net 620)
	)
	(segment
		(start 108.695532 85.215)
		(end 108.580532 85.1)
		(width 0.19)
		(layer "B.Cu")
		(net 620)
	)
	(segment
		(start 107.340628 102.6845)
		(end 103.830501 99.174373)
		(width 0.19)
		(layer "B.Cu")
		(net 620)
	)
	(segment
		(start 108.695532 85.842838)
		(end 108.695532 85.215)
		(width 0.19)
		(layer "B.Cu")
		(net 620)
	)
	(segment
		(start 103.830501 99.174373)
		(end 103.830501 88.907869)
		(width 0.19)
		(layer "B.Cu")
		(net 620)
	)
	(segment
		(start 138.65 70.65)
		(end 139.1 71.1)
		(width 0.1)
		(layer "F.Cu")
		(net 621)
	)
	(segment
		(start 138.630532 70.65)
		(end 138.65 70.65)
		(width 0.1)
		(layer "F.Cu")
		(net 621)
	)
	(via
		(at 139.1 71.1)
		(size 0.45)
		(drill 0.1)
		(layers "F.Cu" "B.Cu")
		(net 621)
	)
	(segment
		(start 210.52 104.3)
		(end 210.495 104.3)
		(width 0.19)
		(layer "F.Cu")
		(net 622)
	)
	(segment
		(start 209.115 104.6025)
		(end 209 104.4875)
		(width 0.19)
		(layer "F.Cu")
		(net 622)
	)
	(segment
		(start 119.065532 83.485)
		(end 119.180532 83.6)
		(width 0.19)
		(layer "F.Cu")
		(net 622)
	)
	(segment
		(start 119.330532 82.65)
		(end 119.065532 82.915)
		(width 0.19)
		(layer "F.Cu")
		(net 622)
	)
	(segment
		(start 210.495 104.3)
		(end 210.1925 104.6025)
		(width 0.19)
		(layer "F.Cu")
		(net 622)
	)
	(segment
		(start 210.1925 104.6025)
		(end 209.115 104.6025)
		(width 0.19)
		(layer "F.Cu")
		(net 622)
	)
	(segment
		(start 119.065532 82.915)
		(end 119.065532 83.485)
		(width 0.19)
		(layer "F.Cu")
		(net 622)
	)
	(via
		(at 119.180532 83.6)
		(size 0.45)
		(drill 0.1)
		(layers "F.Cu" "B.Cu")
		(net 622)
	)
	(via
		(at 209 104.4875)
		(size 0.45)
		(drill 0.1)
		(layers "F.Cu" "B.Cu")
		(net 622)
	)
	(segment
		(start 214.1625 99.043044)
		(end 214.1625 102.443044)
		(width 0.15)
		(layer "In7.Cu")
		(net 622)
	)
	(segment
		(start 215.6625 91.656956)
		(end 215.6625 93.656956)
		(width 0.15)
		(layer "In7.Cu")
		(net 622)
	)
	(segment
		(start 116.386013 67.355505)
		(end 116.536745 67.204772)
		(width 0.15)
		(layer "In7.Cu")
		(net 622)
	)
	(segment
		(start 117.158669 66.035787)
		(end 135.685787 66.035787)
		(width 0.15)
		(layer "In7.Cu")
		(net 622)
	)
	(segment
		(start 141.2625 73.956956)
		(end 141.843044 74.5375)
		(width 0.15)
		(layer "In7.Cu")
		(net 622)
	)
	(segment
		(start 119.180532 83.6)
		(end 119.018032 83.4375)
		(width 0.15)
		(layer "In7.Cu")
		(net 622)
	)
	(segment
		(start 115.7575 73.013044)
		(end 115.0375 72.293044)
		(width 0.15)
		(layer "In7.Cu")
		(net 622)
	)
	(segment
		(start 120.2375 78.706956)
		(end 120.2375 77.543044)
		(width 0.15)
		(layer "In7.Cu")
		(net 622)
	)
	(segment
		(start 120.2375 77.543044)
		(end 118.256956 75.5625)
		(width 0.15)
		(layer "In7.Cu")
		(net 622)
	)
	(segment
		(start 135.685787 66.035787)
		(end 141.2625 71.6125)
		(width 0.15)
		(layer "In7.Cu")
		(net 622)
	)
	(segment
		(start 188.080543 80.474999)
		(end 189.543044 81.9375)
		(width 0.15)
		(layer "In7.Cu")
		(net 622)
	)
	(segment
		(start 116.536745 66.657708)
		(end 117.158669 66.035787)
		(width 0.15)
		(layer "In7.Cu")
		(net 622)
	)
	(segment
		(start 207.343044 83.3375)
		(end 215.6625 91.656956)
		(width 0.15)
		(layer "In7.Cu")
		(net 622)
	)
	(segment
		(start 189.543044 81.9375)
		(end 196.943044 81.9375)
		(width 0.15)
		(layer "In7.Cu")
		(net 622)
	)
	(segment
		(start 211.955544 104.65)
		(end 213.074491 103.531053)
		(width 0.15)
		(layer "In7.Cu")
		(net 622)
	)
	(segment
		(start 115.0375 68.156956)
		(end 115.838951 67.355505)
		(width 0.15)
		(layer "In7.Cu")
		(net 622)
	)
	(segment
		(start 213.583611 103.021936)
		(end 213.958376 102.647167)
		(width 0.15)
		(layer "In7.Cu")
		(net 622)
	)
	(segment
		(start 141.2625 71.6125)
		(end 141.2625 73.956956)
		(width 0.15)
		(layer "In7.Cu")
		(net 622)
	)
	(segment
		(start 145.8625 75.156956)
		(end 145.8625 76.056956)
		(width 0.15)
		(layer "In7.Cu")
		(net 622)
	)
	(segment
		(start 115.7575 74.343044)
		(end 115.7575 73.013044)
		(width 0.15)
		(layer "In7.Cu")
		(net 622)
	)
	(segment
		(start 145.8625 76.056956)
		(end 147.243044 77.4375)
		(width 0.15)
		(layer "In7.Cu")
		(net 622)
	)
	(segment
		(start 116.976956 75.5625)
		(end 115.7575 74.343044)
		(width 0.15)
		(layer "In7.Cu")
		(net 622)
	)
	(segment
		(start 201.856956 83.3375)
		(end 207.343044 83.3375)
		(width 0.15)
		(layer "In7.Cu")
		(net 622)
	)
	(segment
		(start 215.6625 93.656956)
		(end 216.0625 94.056956)
		(width 0.15)
		(layer "In7.Cu")
		(net 622)
	)
	(segment
		(start 196.943044 81.9375)
		(end 199.143044 84.1375)
		(width 0.15)
		(layer "In7.Cu")
		(net 622)
	)
	(segment
		(start 119.018032 83.4375)
		(end 119.018032 79.926424)
		(width 0.15)
		(layer "In7.Cu")
		(net 622)
	)
	(segment
		(start 184.680543 80.474999)
		(end 188.080543 80.474999)
		(width 0.15)
		(layer "In7.Cu")
		(net 622)
	)
	(segment
		(start 181.643044 77.4375)
		(end 184.680543 80.474999)
		(width 0.15)
		(layer "In7.Cu")
		(net 622)
	)
	(segment
		(start 115.0375 72.293044)
		(end 115.0375 68.156956)
		(width 0.15)
		(layer "In7.Cu")
		(net 622)
	)
	(segment
		(start 212.876503 102.880514)
		(end 212.933071 102.823947)
		(width 0.15)
		(layer "In7.Cu")
		(net 622)
	)
	(segment
		(start 199.143044 84.1375)
		(end 201.056956 84.1375)
		(width 0.15)
		(layer "In7.Cu")
		(net 622)
	)
	(segment
		(start 119.018032 79.926424)
		(end 120.2375 78.706956)
		(width 0.15)
		(layer "In7.Cu")
		(net 622)
	)
	(segment
		(start 147.243044 77.4375)
		(end 181.643044 77.4375)
		(width 0.15)
		(layer "In7.Cu")
		(net 622)
	)
	(segment
		(start 145.243044 74.5375)
		(end 145.8625 75.156956)
		(width 0.15)
		(layer "In7.Cu")
		(net 622)
	)
	(segment
		(start 213.958376 102.647167)
		(end 214.1625 102.443044)
		(width 0.15)
		(layer "In7.Cu")
		(net 622)
	)
	(segment
		(start 118.256956 75.5625)
		(end 116.976956 75.5625)
		(width 0.15)
		(layer "In7.Cu")
		(net 622)
	)
	(segment
		(start 201.056956 84.1375)
		(end 201.856956 83.3375)
		(width 0.15)
		(layer "In7.Cu")
		(net 622)
	)
	(segment
		(start 213.074491 103.304779)
		(end 212.876502 103.10679)
		(width 0.15)
		(layer "In7.Cu")
		(net 622)
	)
	(segment
		(start 209.1625 104.65)
		(end 211.955544 104.65)
		(width 0.15)
		(layer "In7.Cu")
		(net 622)
	)
	(segment
		(start 216.0625 94.056956)
		(end 216.0625 97.143044)
		(width 0.15)
		(layer "In7.Cu")
		(net 622)
	)
	(segment
		(start 209 104.4875)
		(end 209.1625 104.65)
		(width 0.15)
		(layer "In7.Cu")
		(net 622)
	)
	(segment
		(start 141.843044 74.5375)
		(end 145.243044 74.5375)
		(width 0.15)
		(layer "In7.Cu")
		(net 622)
	)
	(segment
		(start 216.0625 97.143044)
		(end 214.1625 99.043044)
		(width 0.15)
		(layer "In7.Cu")
		(net 622)
	)
	(segment
		(start 213.159345 102.823947)
		(end 213.357335 103.021937)
		(width 0.15)
		(layer "In7.Cu")
		(net 622)
	)
	(arc
		(start 115.838951 67.355505)
		(mid 115.975716 67.298855)
		(end 116.112482 67.355505)
		(width 0.15)
		(layer "In7.Cu")
		(net 622)
	)
	(arc
		(start 116.536745 66.93124)
		(mid 116.480095 66.794474)
		(end 116.536745 66.657708)
		(width 0.15)
		(layer "In7.Cu")
		(net 622)
	)
	(arc
		(start 213.074491 103.531053)
		(mid 213.121354 103.417916)
		(end 213.074491 103.304779)
		(width 0.15)
		(layer "In7.Cu")
		(net 622)
	)
	(arc
		(start 212.876502 103.10679)
		(mid 212.82964 102.993651)
		(end 212.876503 102.880514)
		(width 0.15)
		(layer "In7.Cu")
		(net 622)
	)
	(arc
		(start 116.112482 67.355505)
		(mid 116.249248 67.412155)
		(end 116.386013 67.355505)
		(width 0.15)
		(layer "In7.Cu")
		(net 622)
	)
	(arc
		(start 213.357335 103.021937)
		(mid 213.470473 103.0688)
		(end 213.583611 103.021936)
		(width 0.15)
		(layer "In7.Cu")
		(net 622)
	)
	(arc
		(start 212.933071 102.823947)
		(mid 213.046208 102.777084)
		(end 213.159345 102.823947)
		(width 0.15)
		(layer "In7.Cu")
		(net 622)
	)
	(arc
		(start 116.536745 67.204772)
		(mid 116.593395 67.068006)
		(end 116.536745 66.93124)
		(width 0.15)
		(layer "In7.Cu")
		(net 622)
	)
	(segment
		(start 106.695532 82.385)
		(end 106.695532 81.915)
		(width 0.19)
		(layer "F.Cu")
		(net 623)
	)
	(segment
		(start 106.430532 82.65)
		(end 106.695532 82.385)
		(width 0.19)
		(layer "F.Cu")
		(net 623)
	)
	(segment
		(start 106.695532 81.915)
		(end 106.580532 81.8)
		(width 0.19)
		(layer "F.Cu")
		(net 623)
	)
	(segment
		(start 206.88 135.28)
		(end 206.88 135.305)
		(width 0.19)
		(layer "F.Cu")
		(net 623)
	)
	(segment
		(start 206.575 135.885)
		(end 206.69 136)
		(width 0.19)
		(layer "F.Cu")
		(net 623)
	)
	(segment
		(start 206.88 135.305)
		(end 206.575 135.61)
		(width 0.19)
		(layer "F.Cu")
		(net 623)
	)
	(segment
		(start 206.575 135.61)
		(end 206.575 135.885)
		(width 0.19)
		(layer "F.Cu")
		(net 623)
	)
	(via
		(at 206.69 136)
		(size 0.45)
		(drill 0.1)
		(layers "F.Cu" "B.Cu")
		(net 623)
	)
	(via
		(at 106.580532 81.8)
		(size 0.45)
		(drill 0.1)
		(layers "F.Cu" "B.Cu")
		(net 623)
	)
	(segment
		(start 186.356956 79.1625)
		(end 182.956956 75.7625)
		(width 0.15)
		(layer "In7.Cu")
		(net 623)
	)
	(segment
		(start 201.956956 82.2625)
		(end 201.406956 81.7125)
		(width 0.15)
		(layer "In7.Cu")
		(net 623)
	)
	(segment
		(start 206.69 136)
		(end 206.5275 135.8375)
		(width 0.15)
		(layer "In7.Cu")
		(net 623)
	)
	(segment
		(start 206.5275 128.216956)
		(end 210.106956 124.6375)
		(width 0.15)
		(layer "In7.Cu")
		(net 623)
	)
	(segment
		(start 114.6625 73.806956)
		(end 114.6625 76.143044)
		(width 0.15)
		(layer "In7.Cu")
		(net 623)
	)
	(segment
		(start 207.956956 82.2625)
		(end 201.956956 82.2625)
		(width 0.15)
		(layer "In7.Cu")
		(net 623)
	)
	(segment
		(start 206.5275 135.8375)
		(end 206.5275 128.216956)
		(width 0.15)
		(layer "In7.Cu")
		(net 623)
	)
	(segment
		(start 196.206956 79.5625)
		(end 189.306956 79.5625)
		(width 0.15)
		(layer "In7.Cu")
		(net 623)
	)
	(segment
		(start 201.406956 81.7125)
		(end 198.356956 81.7125)
		(width 0.15)
		(layer "In7.Cu")
		(net 623)
	)
	(segment
		(start 212.756956 124.6375)
		(end 213.5375 123.856956)
		(width 0.15)
		(layer "In7.Cu")
		(net 623)
	)
	(segment
		(start 136.44406 64.20515)
		(end 116.400394 64.20515)
		(width 0.15)
		(layer "In7.Cu")
		(net 623)
	)
	(segment
		(start 116.400394 64.20515)
		(end 112.6625 67.943044)
		(width 0.15)
		(layer "In7.Cu")
		(net 623)
	)
	(segment
		(start 107.393044 80.1625)
		(end 106.743032 80.812512)
		(width 0.15)
		(layer "In7.Cu")
		(net 623)
	)
	(segment
		(start 112.6625 67.943044)
		(end 112.6625 71.806956)
		(width 0.15)
		(layer "In7.Cu")
		(net 623)
	)
	(segment
		(start 218.3375 107.656956)
		(end 218.3375 95.243044)
		(width 0.15)
		(layer "In7.Cu")
		(net 623)
	)
	(segment
		(start 106.743032 81.6375)
		(end 106.580532 81.8)
		(width 0.15)
		(layer "In7.Cu")
		(net 623)
	)
	(segment
		(start 210.106956 124.6375)
		(end 212.756956 124.6375)
		(width 0.15)
		(layer "In7.Cu")
		(net 623)
	)
	(segment
		(start 106.743032 80.812512)
		(end 106.743032 81.6375)
		(width 0.15)
		(layer "In7.Cu")
		(net 623)
	)
	(segment
		(start 148.00141 75.7625)
		(end 136.44406 64.20515)
		(width 0.15)
		(layer "In7.Cu")
		(net 623)
	)
	(segment
		(start 114.6625 76.143044)
		(end 110.643044 80.1625)
		(width 0.15)
		(layer "In7.Cu")
		(net 623)
	)
	(segment
		(start 213.5375 112.456956)
		(end 218.3375 107.656956)
		(width 0.15)
		(layer "In7.Cu")
		(net 623)
	)
	(segment
		(start 213.5375 123.856956)
		(end 213.5375 112.456956)
		(width 0.15)
		(layer "In7.Cu")
		(net 623)
	)
	(segment
		(start 188.906956 79.1625)
		(end 186.356956 79.1625)
		(width 0.15)
		(layer "In7.Cu")
		(net 623)
	)
	(segment
		(start 217.6375 91.943044)
		(end 207.956956 82.2625)
		(width 0.15)
		(layer "In7.Cu")
		(net 623)
	)
	(segment
		(start 182.956956 75.7625)
		(end 148.00141 75.7625)
		(width 0.15)
		(layer "In7.Cu")
		(net 623)
	)
	(segment
		(start 218.3375 95.243044)
		(end 217.6375 94.543044)
		(width 0.15)
		(layer "In7.Cu")
		(net 623)
	)
	(segment
		(start 189.306956 79.5625)
		(end 188.906956 79.1625)
		(width 0.15)
		(layer "In7.Cu")
		(net 623)
	)
	(segment
		(start 217.6375 94.543044)
		(end 217.6375 91.943044)
		(width 0.15)
		(layer "In7.Cu")
		(net 623)
	)
	(segment
		(start 112.6625 71.806956)
		(end 114.6625 73.806956)
		(width 0.15)
		(layer "In7.Cu")
		(net 623)
	)
	(segment
		(start 198.356956 81.7125)
		(end 196.206956 79.5625)
		(width 0.15)
		(layer "In7.Cu")
		(net 623)
	)
	(segment
		(start 110.643044 80.1625)
		(end 107.393044 80.1625)
		(width 0.15)
		(layer "In7.Cu")
		(net 623)
	)
	(segment
		(start 102.430532 85.65)
		(end 100.3 87.780532)
		(width 0.1)
		(layer "F.Cu")
		(net 625)
	)
	(segment
		(start 153.375 105.81)
		(end 154.59 105.81)
		(width 0.1)
		(layer "F.Cu")
		(net 625)
	)
	(segment
		(start 100.3 87.780532)
		(end 100.3 92.65)
		(width 0.1)
		(layer "F.Cu")
		(net 625)
	)
	(segment
		(start 154.59 105.81)
		(end 154.6 105.8)
		(width 0.1)
		(layer "F.Cu")
		(net 625)
	)
	(via
		(at 154.6 105.8)
		(size 0.45)
		(drill 0.1)
		(layers "F.Cu" "B.Cu")
		(net 625)
	)
	(via
		(at 117 77.2)
		(size 0.45)
		(drill 0.1)
		(layers "F.Cu" "B.Cu")
		(net 625)
	)
	(via
		(at 100.3 92.65)
		(size 0.45)
		(drill 0.1)
		(layers "F.Cu" "B.Cu")
		(net 625)
	)
	(segment
		(start 122.55 71.1)
		(end 123.7 69.95)
		(width 0.1)
		(layer "In4.Cu")
		(net 625)
	)
	(segment
		(start 129 78)
		(end 129 79.1)
		(width 0.1)
		(layer "In4.Cu")
		(net 625)
	)
	(segment
		(start 127.4 87.25)
		(end 128.007843 87.857843)
		(width 0.1)
		(layer "In4.Cu")
		(net 625)
	)
	(segment
		(start 128.45 81.3)
		(end 127.7 82.05)
		(width 0.1)
		(layer "In4.Cu")
		(net 625)
	)
	(segment
		(start 130.092157 87.857843)
		(end 149.867157 107.632843)
		(width 0.1)
		(layer "In4.Cu")
		(net 625)
	)
	(segment
		(start 128.525 70.325)
		(end 128.525 72.5)
		(width 0.1)
		(layer "In4.Cu")
		(net 625)
	)
	(segment
		(start 117.85 72.3)
		(end 117.85 71.1)
		(width 0.1)
		(layer "In4.Cu")
		(net 625)
	)
	(segment
		(start 128.45 80.95)
		(end 128.45 81.3)
		(width 0.1)
		(layer "In4.Cu")
		(net 625)
	)
	(segment
		(start 149.867157 107.632843)
		(end 150.767157 107.632843)
		(width 0.1)
		(layer "In4.Cu")
		(net 625)
	)
	(segment
		(start 128.007843 87.857843)
		(end 130.092157 87.857843)
		(width 0.1)
		(layer "In4.Cu")
		(net 625)
	)
	(segment
		(start 127.7 82.05)
		(end 127.7 82.35)
		(width 0.1)
		(layer "In4.Cu")
		(net 625)
	)
	(segment
		(start 118.15 72.6)
		(end 117.85 72.3)
		(width 0.1)
		(layer "In4.Cu")
		(net 625)
	)
	(segment
		(start 128.8 76.45)
		(end 128.8 77.8)
		(width 0.1)
		(layer "In4.Cu")
		(net 625)
	)
	(segment
		(start 129 76.25)
		(end 128.8 76.45)
		(width 0.1)
		(layer "In4.Cu")
		(net 625)
	)
	(segment
		(start 129.25 73.225)
		(end 129.25 74.15)
		(width 0.1)
		(layer "In4.Cu")
		(net 625)
	)
	(segment
		(start 129.25 74.15)
		(end 129 74.4)
		(width 0.1)
		(layer "In4.Cu")
		(net 625)
	)
	(segment
		(start 128.8 77.8)
		(end 129 78)
		(width 0.1)
		(layer "In4.Cu")
		(net 625)
	)
	(segment
		(start 118.75 70.7)
		(end 119.15 71.1)
		(width 0.1)
		(layer "In4.Cu")
		(net 625)
	)
	(segment
		(start 128.5 83.15)
		(end 128.5 84.45)
		(width 0.1)
		(layer "In4.Cu")
		(net 625)
	)
	(segment
		(start 117 75.75)
		(end 118.15 74.6)
		(width 0.1)
		(layer "In4.Cu")
		(net 625)
	)
	(segment
		(start 119.15 71.1)
		(end 122.55 71.1)
		(width 0.1)
		(layer "In4.Cu")
		(net 625)
	)
	(segment
		(start 151.7 106.7)
		(end 153.7 106.7)
		(width 0.1)
		(layer "In4.Cu")
		(net 625)
	)
	(segment
		(start 118.15 74.6)
		(end 118.15 72.6)
		(width 0.1)
		(layer "In4.Cu")
		(net 625)
	)
	(segment
		(start 128.5 84.45)
		(end 127.4 85.55)
		(width 0.1)
		(layer "In4.Cu")
		(net 625)
	)
	(segment
		(start 123.7 69.95)
		(end 128.15 69.95)
		(width 0.1)
		(layer "In4.Cu")
		(net 625)
	)
	(segment
		(start 127.4 85.55)
		(end 127.4 87.25)
		(width 0.1)
		(layer "In4.Cu")
		(net 625)
	)
	(segment
		(start 128.525 72.5)
		(end 129.25 73.225)
		(width 0.1)
		(layer "In4.Cu")
		(net 625)
	)
	(segment
		(start 128.2 79.9)
		(end 128.2 80.7)
		(width 0.1)
		(layer "In4.Cu")
		(net 625)
	)
	(segment
		(start 117 77.2)
		(end 117 75.75)
		(width 0.1)
		(layer "In4.Cu")
		(net 625)
	)
	(segment
		(start 128.15 69.95)
		(end 128.525 70.325)
		(width 0.1)
		(layer "In4.Cu")
		(net 625)
	)
	(segment
		(start 129 79.1)
		(end 128.2 79.9)
		(width 0.1)
		(layer "In4.Cu")
		(net 625)
	)
	(segment
		(start 153.7 106.7)
		(end 154.6 105.8)
		(width 0.1)
		(layer "In4.Cu")
		(net 625)
	)
	(segment
		(start 117.85 71.1)
		(end 118.25 70.7)
		(width 0.1)
		(layer "In4.Cu")
		(net 625)
	)
	(segment
		(start 118.25 70.7)
		(end 118.75 70.7)
		(width 0.1)
		(layer "In4.Cu")
		(net 625)
	)
	(segment
		(start 127.7 82.35)
		(end 128.5 83.15)
		(width 0.1)
		(layer "In4.Cu")
		(net 625)
	)
	(segment
		(start 150.767157 107.632843)
		(end 151.7 106.7)
		(width 0.1)
		(layer "In4.Cu")
		(net 625)
	)
	(segment
		(start 128.2 80.7)
		(end 128.45 80.95)
		(width 0.1)
		(layer "In4.Cu")
		(net 625)
	)
	(segment
		(start 129 74.4)
		(end 129 76.25)
		(width 0.1)
		(layer "In4.Cu")
		(net 625)
	)
	(segment
		(start 105.2 84.55)
		(end 109.7 80.05)
		(width 0.1)
		(layer "In5.Cu")
		(net 625)
	)
	(segment
		(start 100.3 92.65)
		(end 105.2 87.75)
		(width 0.1)
		(layer "In5.Cu")
		(net 625)
	)
	(segment
		(start 114.5 80.05)
		(end 115.3 79.25)
		(width 0.1)
		(layer "In5.Cu")
		(net 625)
	)
	(segment
		(start 109.7 80.05)
		(end 114.5 80.05)
		(width 0.1)
		(layer "In5.Cu")
		(net 625)
	)
	(segment
		(start 115.05 77.75)
		(end 115.6 77.2)
		(width 0.1)
		(layer "In5.Cu")
		(net 625)
	)
	(segment
		(start 115.3 79.25)
		(end 115.3 78.5)
		(width 0.1)
		(layer "In5.Cu")
		(net 625)
	)
	(segment
		(start 115.05 78.25)
		(end 115.05 77.75)
		(width 0.1)
		(layer "In5.Cu")
		(net 625)
	)
	(segment
		(start 115.6 77.2)
		(end 117 77.2)
		(width 0.1)
		(layer "In5.Cu")
		(net 625)
	)
	(segment
		(start 105.2 87.75)
		(end 105.2 84.55)
		(width 0.1)
		(layer "In5.Cu")
		(net 625)
	)
	(segment
		(start 115.3 78.5)
		(end 115.05 78.25)
		(width 0.1)
		(layer "In5.Cu")
		(net 625)
	)
	(segment
		(start 144.45 73.55)
		(end 144.9 73.1)
		(width 0.1)
		(layer "F.Cu")
		(net 627)
	)
	(segment
		(start 149.4 71.1)
		(end 149.4 69.675)
		(width 0.1)
		(layer "F.Cu")
		(net 627)
	)
	(segment
		(start 149.0125 71.4875)
		(end 149.4 71.1)
		(width 0.1)
		(layer "F.Cu")
		(net 627)
	)
	(segment
		(start 146.475 73.1)
		(end 148.0875 71.4875)
		(width 0.1)
		(layer "F.Cu")
		(net 627)
	)
	(segment
		(start 149.4 69.675)
		(end 149.8 69.275)
		(width 0.1)
		(layer "F.Cu")
		(net 627)
	)
	(segment
		(start 148.0875 71.4875)
		(end 149.0125 71.4875)
		(width 0.1)
		(layer "F.Cu")
		(net 627)
	)
	(segment
		(start 149.8 69.275)
		(end 151.325 69.275)
		(width 0.1)
		(layer "F.Cu")
		(net 627)
	)
	(segment
		(start 143.130532 76.65)
		(end 143.8 75.980532)
		(width 0.1)
		(layer "F.Cu")
		(net 627)
	)
	(segment
		(start 144.9 73.1)
		(end 146.475 73.1)
		(width 0.1)
		(layer "F.Cu")
		(net 627)
	)
	(segment
		(start 144.45 74.025)
		(end 144.45 73.55)
		(width 0.1)
		(layer "F.Cu")
		(net 627)
	)
	(segment
		(start 143.8 75.980532)
		(end 143.8 74.675)
		(width 0.1)
		(layer "F.Cu")
		(net 627)
	)
	(segment
		(start 143.8 74.675)
		(end 144.45 74.025)
		(width 0.1)
		(layer "F.Cu")
		(net 627)
	)
	(via
		(at 151.325 69.275)
		(size 0.45)
		(drill 0.1)
		(layers "F.Cu" "B.Cu")
		(net 627)
	)
	(via
		(at 158.275 69.2)
		(size 0.45)
		(drill 0.1)
		(layers "F.Cu" "B.Cu")
		(net 627)
	)
	(via
		(at 156.375 64.15)
		(size 0.45)
		(drill 0.1)
		(layers "F.Cu" "B.Cu")
		(net 627)
	)
	(segment
		(start 159.098 63.25)
		(end 159.558 62.79)
		(width 0.1)
		(layer "B.Cu")
		(net 627)
	)
	(segment
		(start 158.51 63.25)
		(end 159.098 63.25)
		(width 0.1)
		(layer "B.Cu")
		(net 627)
	)
	(segment
		(start 157.61 64.15)
		(end 156.375 64.15)
		(width 0.1)
		(layer "B.Cu")
		(net 627)
	)
	(segment
		(start 158.51 63.25)
		(end 157.61 64.15)
		(width 0.1)
		(layer "B.Cu")
		(net 627)
	)
	(segment
		(start 156.375 67.3)
		(end 156.375 64.15)
		(width 0.1)
		(layer "In4.Cu")
		(net 627)
	)
	(segment
		(start 158.275 69.2)
		(end 156.375 67.3)
		(width 0.1)
		(layer "In4.Cu")
		(net 627)
	)
	(segment
		(start 153.675 69.7)
		(end 157.775 69.7)
		(width 0.1)
		(layer "In5.Cu")
		(net 627)
	)
	(segment
		(start 157.775 69.7)
		(end 158.275 69.2)
		(width 0.1)
		(layer "In5.Cu")
		(net 627)
	)
	(segment
		(start 151.325 69.275)
		(end 153.25 69.275)
		(width 0.1)
		(layer "In5.Cu")
		(net 627)
	)
	(segment
		(start 153.25 69.275)
		(end 153.675 69.7)
		(width 0.1)
		(layer "In5.Cu")
		(net 627)
	)
	(segment
		(start 210.52 101.38)
		(end 210.495 101.38)
		(width 0.19)
		(layer "F.Cu")
		(net 630)
	)
	(segment
		(start 209.115 101.6825)
		(end 209 101.5675)
		(width 0.19)
		(layer "F.Cu")
		(net 630)
	)
	(segment
		(start 210.495 101.38)
		(end 210.1925 101.6825)
		(width 0.19)
		(layer "F.Cu")
		(net 630)
	)
	(segment
		(start 117.065532 71.515)
		(end 117.180532 71.4)
		(width 0.19)
		(layer "F.Cu")
		(net 630)
	)
	(segment
		(start 117.065532 71.885)
		(end 117.065532 71.515)
		(width 0.19)
		(layer "F.Cu")
		(net 630)
	)
	(segment
		(start 210.1925 101.6825)
		(end 209.115 101.6825)
		(width 0.19)
		(layer "F.Cu")
		(net 630)
	)
	(segment
		(start 117.330532 72.15)
		(end 117.065532 71.885)
		(width 0.19)
		(layer "F.Cu")
		(net 630)
	)
	(via
		(at 117.180532 71.4)
		(size 0.45)
		(drill 0.1)
		(layers "F.Cu" "B.Cu")
		(net 630)
	)
	(via
		(at 209 101.5675)
		(size 0.45)
		(drill 0.1)
		(layers "F.Cu" "B.Cu")
		(net 630)
	)
	(segment
		(start 118.882298 67.850949)
		(end 118.882298 67.59)
		(width 0.15)
		(layer "In7.Cu")
		(net 630)
	)
	(segment
		(start 211.497528 100.908019)
		(end 211.554096 100.851449)
		(width 0.15)
		(layer "In7.Cu")
		(net 630)
	)
	(segment
		(start 210.931841 100.908019)
		(end 210.988411 100.85145)
		(width 0.15)
		(layer "In7.Cu")
		(net 630)
	)
	(segment
		(start 201.756956 84.5375)
		(end 206.143044 84.5375)
		(width 0.15)
		(layer "In7.Cu")
		(net 630)
	)
	(segment
		(start 144.743044 77.5375)
		(end 146.143044 78.9375)
		(width 0.15)
		(layer "In7.Cu")
		(net 630)
	)
	(segment
		(start 201.456956 84.8375)
		(end 201.756956 84.5375)
		(width 0.15)
		(layer "In7.Cu")
		(net 630)
	)
	(segment
		(start 135.1 67.45)
		(end 138.4125 70.7625)
		(width 0.15)
		(layer "In7.Cu")
		(net 630)
	)
	(segment
		(start 214.4625 95.243044)
		(end 213.0625 96.643044)
		(width 0.15)
		(layer "In7.Cu")
		(net 630)
	)
	(segment
		(start 117.018032 71.2375)
		(end 117.018032 68.176424)
		(width 0.15)
		(layer "In7.Cu")
		(net 630)
	)
	(segment
		(start 211.8625 98.943044)
		(end 211.8625 100.543044)
		(width 0.15)
		(layer "In7.Cu")
		(net 630)
	)
	(segment
		(start 138.4125 70.7625)
		(end 138.4125 72.693044)
		(width 0.15)
		(layer "In7.Cu")
		(net 630)
	)
	(segment
		(start 213.0625 96.643044)
		(end 213.0625 97.743044)
		(width 0.15)
		(layer "In7.Cu")
		(net 630)
	)
	(segment
		(start 119.022298 67.45)
		(end 135.1 67.45)
		(width 0.15)
		(layer "In7.Cu")
		(net 630)
	)
	(segment
		(start 213.0625 97.743044)
		(end 211.8625 98.943044)
		(width 0.15)
		(layer "In7.Cu")
		(net 630)
	)
	(segment
		(start 138.243044 77.5375)
		(end 144.743044 77.5375)
		(width 0.15)
		(layer "In7.Cu")
		(net 630)
	)
	(segment
		(start 118.532298 67.59)
		(end 118.532298 67.850949)
		(width 0.15)
		(layer "In7.Cu")
		(net 630)
	)
	(segment
		(start 117.018032 68.176424)
		(end 117.744456 67.45)
		(width 0.15)
		(layer "In7.Cu")
		(net 630)
	)
	(segment
		(start 187.393044 81.8875)
		(end 190.343044 84.8375)
		(width 0.15)
		(layer "In7.Cu")
		(net 630)
	)
	(segment
		(start 209 101.5675)
		(end 209.1625 101.73)
		(width 0.15)
		(layer "In7.Cu")
		(net 630)
	)
	(segment
		(start 210.988409 101.190861)
		(end 210.931841 101.134293)
		(width 0.15)
		(layer "In7.Cu")
		(net 630)
	)
	(segment
		(start 137.8625 73.243044)
		(end 137.8625 77.156956)
		(width 0.15)
		(layer "In7.Cu")
		(net 630)
	)
	(segment
		(start 183.693044 81.8875)
		(end 187.393044 81.8875)
		(width 0.15)
		(layer "In7.Cu")
		(net 630)
	)
	(segment
		(start 117.744456 67.45)
		(end 118.392298 67.45)
		(width 0.15)
		(layer "In7.Cu")
		(net 630)
	)
	(segment
		(start 180.743044 78.9375)
		(end 183.693044 81.8875)
		(width 0.15)
		(layer "In7.Cu")
		(net 630)
	)
	(segment
		(start 210.675544 101.73)
		(end 210.988409 101.417135)
		(width 0.15)
		(layer "In7.Cu")
		(net 630)
	)
	(segment
		(start 146.143044 78.9375)
		(end 180.743044 78.9375)
		(width 0.15)
		(layer "In7.Cu")
		(net 630)
	)
	(segment
		(start 117.180532 71.4)
		(end 117.018032 71.2375)
		(width 0.15)
		(layer "In7.Cu")
		(net 630)
	)
	(segment
		(start 214.4625 92.856956)
		(end 214.4625 95.243044)
		(width 0.15)
		(layer "In7.Cu")
		(net 630)
	)
	(segment
		(start 211.554096 100.851449)
		(end 211.8625 100.543044)
		(width 0.15)
		(layer "In7.Cu")
		(net 630)
	)
	(segment
		(start 138.4125 72.693044)
		(end 137.8625 73.243044)
		(width 0.15)
		(layer "In7.Cu")
		(net 630)
	)
	(segment
		(start 209.1625 101.73)
		(end 210.675544 101.73)
		(width 0.15)
		(layer "In7.Cu")
		(net 630)
	)
	(segment
		(start 211.214685 100.85145)
		(end 211.271254 100.908019)
		(width 0.15)
		(layer "In7.Cu")
		(net 630)
	)
	(segment
		(start 190.343044 84.8375)
		(end 201.456956 84.8375)
		(width 0.15)
		(layer "In7.Cu")
		(net 630)
	)
	(segment
		(start 206.143044 84.5375)
		(end 214.4625 92.856956)
		(width 0.15)
		(layer "In7.Cu")
		(net 630)
	)
	(segment
		(start 118.672298 67.990949)
		(end 118.742298 67.990949)
		(width 0.15)
		(layer "In7.Cu")
		(net 630)
	)
	(segment
		(start 137.8625 77.156956)
		(end 138.243044 77.5375)
		(width 0.15)
		(layer "In7.Cu")
		(net 630)
	)
	(arc
		(start 210.931841 101.134293)
		(mid 210.884978 101.021156)
		(end 210.931841 100.908019)
		(width 0.15)
		(layer "In7.Cu")
		(net 630)
	)
	(arc
		(start 118.392298 67.45)
		(mid 118.491293 67.491005)
		(end 118.532298 67.59)
		(width 0.15)
		(layer "In7.Cu")
		(net 630)
	)
	(arc
		(start 118.882298 67.59)
		(mid 118.923303 67.491005)
		(end 119.022298 67.45)
		(width 0.15)
		(layer "In7.Cu")
		(net 630)
	)
	(arc
		(start 118.532298 67.850949)
		(mid 118.573303 67.949944)
		(end 118.672298 67.990949)
		(width 0.15)
		(layer "In7.Cu")
		(net 630)
	)
	(arc
		(start 210.988409 101.417135)
		(mid 211.035272 101.303998)
		(end 210.988409 101.190861)
		(width 0.15)
		(layer "In7.Cu")
		(net 630)
	)
	(arc
		(start 118.742298 67.990949)
		(mid 118.841293 67.949944)
		(end 118.882298 67.850949)
		(width 0.15)
		(layer "In7.Cu")
		(net 630)
	)
	(arc
		(start 211.271254 100.908019)
		(mid 211.384391 100.954882)
		(end 211.497528 100.908019)
		(width 0.15)
		(layer "In7.Cu")
		(net 630)
	)
	(arc
		(start 210.988411 100.85145)
		(mid 211.101548 100.804587)
		(end 211.214685 100.85145)
		(width 0.15)
		(layer "In7.Cu")
		(net 630)
	)
	(segment
		(start 88.62 98.8)
		(end 88.595 98.8)
		(width 0.19)
		(layer "F.Cu")
		(net 631)
	)
	(segment
		(start 83.845532 100.985)
		(end 83.395532 100.535)
		(width 0.19)
		(layer "F.Cu")
		(net 631)
	)
	(segment
		(start 85.65337 100.985)
		(end 83.845532 100.985)
		(width 0.19)
		(layer "F.Cu")
		(net 631)
	)
	(segment
		(start 88.28 99.115)
		(end 87.52337 99.115)
		(width 0.19)
		(layer "F.Cu")
		(net 631)
	)
	(segment
		(start 88.595 98.8)
		(end 88.28 99.115)
		(width 0.19)
		(layer "F.Cu")
		(net 631)
	)
	(segment
		(start 87.52337 99.115)
		(end 85.65337 100.985)
		(width 0.19)
		(layer "F.Cu")
		(net 631)
	)
	(via
		(at 83.395532 100.535)
		(size 0.45)
		(drill 0.1)
		(layers "F.Cu" "B.Cu")
		(net 631)
	)
	(segment
		(start 219.13 114.261)
		(end 219.929 114.261)
		(width 0.1)
		(layer "B.Cu")
		(net 633)
	)
	(segment
		(start 219.929 114.261)
		(end 220.18 114.01)
		(width 0.1)
		(layer "B.Cu")
		(net 633)
	)
	(segment
		(start 150.9 138.15)
		(end 137.024 152.026)
		(width 1)
		(layer "F.Cu")
		(net 634)
	)
	(segment
		(start 84.7 142.7)
		(end 84.7 141.9)
		(width 1)
		(layer "F.Cu")
		(net 634)
	)
	(segment
		(start 168 148.6)
		(end 168 146.826314)
		(width 1)
		(layer "F.Cu")
		(net 634)
	)
	(segment
		(start 168.3 145.7)
		(end 168.713157 146.113157)
		(width 0.2)
		(layer "F.Cu")
		(net 634)
	)
	(segment
		(start 162.4 138.15)
		(end 150.9 138.15)
		(width 1)
		(layer "F.Cu")
		(net 634)
	)
	(segment
		(start 84.7 145.8)
		(end 84.7 144.3)
		(width 1)
		(layer "F.Cu")
		(net 634)
	)
	(segment
		(start 167.95 145.35)
		(end 168.3 145.7)
		(width 0.3)
		(layer "F.Cu")
		(net 634)
	)
	(segment
		(start 167.6 143)
		(end 169 143)
		(width 0.3)
		(layer "F.Cu")
		(net 634)
	)
	(segment
		(start 162.4 138.15)
		(end 162.4 134.6)
		(width 0.1)
		(layer "F.Cu")
		(net 634)
	)
	(segment
		(start 168.6 145.7)
		(end 168.3 145.7)
		(width 0.2)
		(layer "F.Cu")
		(net 634)
	)
	(segment
		(start 168.3 146)
		(end 168.6 145.7)
		(width 0.2)
		(layer "F.Cu")
		(net 634)
	)
	(segment
		(start 162.4 138.15)
		(end 166.15 138.15)
		(width 1)
		(layer "F.Cu")
		(net 634)
	)
	(segment
		(start 166.15 138.15)
		(end 169 141)
		(width 1)
		(layer "F.Cu")
		(net 634)
	)
	(segment
		(start 168.3 145.7)
		(end 168.3 146)
		(width 0.2)
		(layer "F.Cu")
		(net 634)
	)
	(segment
		(start 169 143)
		(end 169 145.826314)
		(width 1)
		(layer "F.Cu")
		(net 634)
	)
	(segment
		(start 84.7 143.5)
		(end 84.7 142.7)
		(width 1)
		(layer "F.Cu")
		(net 634)
	)
	(segment
		(start 169.159468 149.049468)
		(end 168.449468 149.049468)
		(width 1)
		(layer "F.Cu")
		(net 634)
	)
	(segment
		(start 167.95 145.28)
		(end 167.95 145.35)
		(width 0.2)
		(layer "F.Cu")
		(net 634)
	)
	(segment
		(start 84.7 144.3)
		(end 84.7 143.5)
		(width 1)
		(layer "F.Cu")
		(net 634)
	)
	(segment
		(start 137.024 152.026)
		(end 86.226 152.026)
		(width 1)
		(layer "F.Cu")
		(net 634)
	)
	(segment
		(start 168 146.826314)
		(end 168.713157 146.113157)
		(width 1)
		(layer "F.Cu")
		(net 634)
	)
	(segment
		(start 169 141)
		(end 169 143)
		(width 1)
		(layer "F.Cu")
		(net 634)
	)
	(segment
		(start 169.149468 149.039468)
		(end 169.159468 149.049468)
		(width 0.2)
		(layer "F.Cu")
		(net 634)
	)
	(segment
		(start 86.226 152.026)
		(end 84 149.8)
		(width 1)
		(layer "F.Cu")
		(net 634)
	)
	(segment
		(start 84 146.5)
		(end 84.7 145.8)
		(width 1)
		(layer "F.Cu")
		(net 634)
	)
	(segment
		(start 169 145.826314)
		(end 168.713157 146.113157)
		(width 1)
		(layer "F.Cu")
		(net 634)
	)
	(segment
		(start 168.449468 149.049468)
		(end 168 148.6)
		(width 1)
		(layer "F.Cu")
		(net 634)
	)
	(segment
		(start 84 149.8)
		(end 84 146.5)
		(width 1)
		(layer "F.Cu")
		(net 634)
	)
	(segment
		(start 177.5 57.1)
		(end 177.5 58)
		(width 0.1)
		(layer "F.Cu")
		(net 634)
	)
	(via
		(at 84.7 143.5)
		(size 0.45)
		(drill 0.1)
		(layers "F.Cu" "B.Cu")
		(net 634)
	)
	(via
		(at 191.4 88.2)
		(size 0.45)
		(drill 0.1)
		(layers "F.Cu" "B.Cu")
		(net 634)
	)
	(via
		(at 162.4 134.6)
		(size 0.45)
		(drill 0.1)
		(layers "F.Cu" "B.Cu")
		(net 634)
	)
	(via
		(at 177.5 58)
		(size 0.45)
		(drill 0.1)
		(layers "F.Cu" "B.Cu")
		(net 634)
	)
	(via
		(at 84.7 141.9)
		(size 0.45)
		(drill 0.1)
		(layers "F.Cu" "B.Cu")
		(net 634)
	)
	(via
		(at 84.7 144.3)
		(size 0.45)
		(drill 0.1)
		(layers "F.Cu" "B.Cu")
		(net 634)
	)
	(via
		(at 187.68 64.78)
		(size 0.45)
		(drill 0.1)
		(layers "F.Cu" "B.Cu")
		(net 634)
	)
	(via
		(at 84.7 142.7)
		(size 0.45)
		(drill 0.1)
		(layers "F.Cu" "B.Cu")
		(net 634)
	)
	(segment
		(start 179.6 55.2)
		(end 178.6 56.2)
		(width 0.1)
		(layer "B.Cu")
		(net 634)
	)
	(segment
		(start 190 89.6)
		(end 191.4 88.2)
		(width 0.1)
		(layer "B.Cu")
		(net 634)
	)
	(segment
		(start 178.6 57.99)
		(end 178.61 58)
		(width 0.1)
		(layer "B.Cu")
		(net 634)
	)
	(segment
		(start 184.4 55.2)
		(end 179.6 55.2)
		(width 0.1)
		(layer "B.Cu")
		(net 634)
	)
	(segment
		(start 84.7 143.5)
		(end 84.7 142.7)
		(width 1)
		(layer "B.Cu")
		(net 634)
	)
	(segment
		(start 177.5 58)
		(end 178.61 58)
		(width 0.1)
		(layer "B.Cu")
		(net 634)
	)
	(segment
		(start 178.6 56.88)
		(end 177.5 57.98)
		(width 0.1)
		(layer "B.Cu")
		(net 634)
	)
	(segment
		(start 165.2 128.8)
		(end 168.6 125.4)
		(width 0.1)
		(layer "B.Cu")
		(net 634)
	)
	(segment
		(start 168.6 125.4)
		(end 174.8 125.4)
		(width 0.1)
		(layer "B.Cu")
		(net 634)
	)
	(segment
		(start 178.61 58)
		(end 178.59 57.98)
		(width 0.1)
		(layer "B.Cu")
		(net 634)
	)
	(segment
		(start 190 98.975)
		(end 190 89.6)
		(width 0.1)
		(layer "B.Cu")
		(net 634)
	)
	(segment
		(start 174.8 125.4)
		(end 190.9 109.3)
		(width 0.1)
		(layer "B.Cu")
		(net 634)
	)
	(segment
		(start 190.9 99.875)
		(end 190 98.975)
		(width 0.1)
		(layer "B.Cu")
		(net 634)
	)
	(segment
		(start 187.68 64.78)
		(end 187.68 63.18)
		(width 0.1)
		(layer "B.Cu")
		(net 634)
	)
	(segment
		(start 190.9 109.3)
		(end 190.9 99.875)
		(width 0.1)
		(layer "B.Cu")
		(net 634)
	)
	(segment
		(start 187.68 63.18)
		(end 186.07 61.57)
		(width 0.1)
		(layer "B.Cu")
		(net 634)
	)
	(segment
		(start 186.07 56.87)
		(end 184.4 55.2)
		(width 0.1)
		(layer "B.Cu")
		(net 634)
	)
	(segment
		(start 84.7 141.9)
		(end 84.7 140.75)
		(width 1)
		(layer "B.Cu")
		(net 634)
	)
	(segment
		(start 178.6 56.2)
		(end 178.6 56.88)
		(width 0.1)
		(layer "B.Cu")
		(net 634)
	)
	(segment
		(start 186.07 61.57)
		(end 186.07 56.87)
		(width 0.1)
		(layer "B.Cu")
		(net 634)
	)
	(segment
		(start 84.7 142.7)
		(end 84.7 141.9)
		(width 1)
		(layer "B.Cu")
		(net 634)
	)
	(segment
		(start 165.2 131.8)
		(end 165.2 128.8)
		(width 0.1)
		(layer "B.Cu")
		(net 634)
	)
	(segment
		(start 162.4 134.6)
		(end 165.2 131.8)
		(width 0.1)
		(layer "B.Cu")
		(net 634)
	)
	(segment
		(start 84.7 144.3)
		(end 84.7 143.5)
		(width 1)
		(layer "B.Cu")
		(net 634)
	)
	(segment
		(start 187.8 65.2)
		(end 187.8 77)
		(width 0.1)
		(layer "In5.Cu")
		(net 634)
	)
	(segment
		(start 187 80)
		(end 187.6 80.6)
		(width 0.1)
		(layer "In5.Cu")
		(net 634)
	)
	(segment
		(start 187.6 80.6)
		(end 187.6 84.4)
		(width 0.1)
		(layer "In5.Cu")
		(net 634)
	)
	(segment
		(start 187.8 77)
		(end 187 77.8)
		(width 0.1)
		(layer "In5.Cu")
		(net 634)
	)
	(segment
		(start 187.7 65.1)
		(end 187.8 65.2)
		(width 0.1)
		(layer "In5.Cu")
		(net 634)
	)
	(segment
		(start 187.7 64.8)
		(end 187.7 65.1)
		(width 0.1)
		(layer "In5.Cu")
		(net 634)
	)
	(segment
		(start 187.68 64.78)
		(end 187.7 64.8)
		(width 0.1)
		(layer "In5.Cu")
		(net 634)
	)
	(segment
		(start 187.6 84.4)
		(end 191.4 88.2)
		(width 0.1)
		(layer "In5.Cu")
		(net 634)
	)
	(segment
		(start 187 77.8)
		(end 187 80)
		(width 0.1)
		(layer "In5.Cu")
		(net 634)
	)
	(segment
		(start 214.263632 93.120857)
		(end 214.263632 92.670856)
		(width 0.19)
		(layer "F.Cu")
		(net 635)
	)
	(segment
		(start 212.8 94.92)
		(end 212.8 94.895)
		(width 0.19)
		(layer "F.Cu")
		(net 635)
	)
	(segment
		(start 213.1175 94.12087)
		(end 213.52337 93.715)
		(width 0.19)
		(layer "F.Cu")
		(net 635)
	)
	(segment
		(start 213.1175 94.5775)
		(end 213.1175 94.12087)
		(width 0.19)
		(layer "F.Cu")
		(net 635)
	)
	(segment
		(start 214.02337 93.715)
		(end 214.279632 93.458738)
		(width 0.19)
		(layer "F.Cu")
		(net 635)
	)
	(segment
		(start 214.279632 93.136857)
		(end 214.263632 93.120857)
		(width 0.19)
		(layer "F.Cu")
		(net 635)
	)
	(segment
		(start 214.279632 93.458738)
		(end 214.279632 93.136857)
		(width 0.19)
		(layer "F.Cu")
		(net 635)
	)
	(segment
		(start 212.8 94.895)
		(end 213.1175 94.5775)
		(width 0.19)
		(layer "F.Cu")
		(net 635)
	)
	(segment
		(start 213.52337 93.715)
		(end 214.02337 93.715)
		(width 0.19)
		(layer "F.Cu")
		(net 635)
	)
	(via
		(at 212.8 94.9)
		(size 0.45)
		(drill 0.1)
		(layers "F.Cu" "B.Cu")
		(net 635)
	)
	(segment
		(start 212.8 94.929002)
		(end 212.8 94.9)
		(width 0.19)
		(layer "B.Cu")
		(net 635)
	)
	(segment
		(start 101.780157 119.958216)
		(end 101.843795 119.894576)
		(width 0.19)
		(layer "F.Cu")
		(net 637)
	)
	(segment
		(start 100.94 104.64837)
		(end 102.14837 103.44)
		(width 0.19)
		(layer "F.Cu")
		(net 637)
	)
	(segment
		(start 103.82337 103.44)
		(end 104.695532 102.567838)
		(width 0.19)
		(layer "F.Cu")
		(net 637)
	)
	(segment
		(start 102.14837 103.44)
		(end 103.82337 103.44)
		(width 0.19)
		(layer "F.Cu")
		(net 637)
	)
	(segment
		(start 101.135957 119.950414)
		(end 101.199597 119.886775)
		(width 0.19)
		(layer "F.Cu")
		(net 637)
	)
	(segment
		(start 100.82337 120.915)
		(end 101.207397 120.530973)
		(width 0.19)
		(layer "F.Cu")
		(net 637)
	)
	(segment
		(start 101.207397 120.276415)
		(end 101.135956 120.204974)
		(width 0.19)
		(layer "F.Cu")
		(net 637)
	)
	(segment
		(start 102.715 119.02337)
		(end 102.715 117.941916)
		(width 0.19)
		(layer "F.Cu")
		(net 637)
	)
	(segment
		(start 100.94 114.70163)
		(end 100.94 104.64837)
		(width 0.19)
		(layer "F.Cu")
		(net 637)
	)
	(segment
		(start 104.695532 84.415)
		(end 104.430532 84.15)
		(width 0.19)
		(layer "F.Cu")
		(net 637)
	)
	(segment
		(start 104.695532 102.567838)
		(end 104.695532 84.415)
		(width 0.19)
		(layer "F.Cu")
		(net 637)
	)
	(segment
		(start 102.715 117.941916)
		(end 102.715 116.47663)
		(width 0.19)
		(layer "F.Cu")
		(net 637)
	)
	(segment
		(start 101.454155 119.886775)
		(end 101.525597 119.958217)
		(width 0.19)
		(layer "F.Cu")
		(net 637)
	)
	(segment
		(start 95.27663 118.415)
		(end 97.77663 120.915)
		(width 0.19)
		(layer "F.Cu")
		(net 637)
	)
	(segment
		(start 93.18 118.1)
		(end 93.205 118.1)
		(width 0.19)
		(layer "F.Cu")
		(net 637)
	)
	(segment
		(start 93.205 118.1)
		(end 93.52 118.415)
		(width 0.19)
		(layer "F.Cu")
		(net 637)
	)
	(segment
		(start 102.715 116.47663)
		(end 100.94 114.70163)
		(width 0.19)
		(layer "F.Cu")
		(net 637)
	)
	(segment
		(start 97.77663 120.915)
		(end 100.82337 120.915)
		(width 0.19)
		(layer "F.Cu")
		(net 637)
	)
	(segment
		(start 93.52 118.415)
		(end 95.27663 118.415)
		(width 0.19)
		(layer "F.Cu")
		(net 637)
	)
	(segment
		(start 101.843795 119.894576)
		(end 102.715 119.02337)
		(width 0.19)
		(layer "F.Cu")
		(net 637)
	)
	(arc
		(start 101.525597 119.958217)
		(mid 101.652876 120.010938)
		(end 101.780157 119.958216)
		(width 0.19)
		(layer "F.Cu")
		(net 637)
	)
	(arc
		(start 101.199597 119.886775)
		(mid 101.326876 119.834054)
		(end 101.454155 119.886775)
		(width 0.19)
		(layer "F.Cu")
		(net 637)
	)
	(arc
		(start 101.135956 120.204974)
		(mid 101.083236 120.077694)
		(end 101.135957 119.950414)
		(width 0.19)
		(layer "F.Cu")
		(net 637)
	)
	(arc
		(start 101.207397 120.530973)
		(mid 101.260118 120.403694)
		(end 101.207397 120.276415)
		(width 0.19)
		(layer "F.Cu")
		(net 637)
	)
	(via
		(at 166.25 56)
		(size 0.45)
		(drill 0.1)
		(layers "F.Cu" "B.Cu")
		(net 639)
	)
	(segment
		(start 166.25 56)
		(end 166.25 57.02)
		(width 0.1)
		(layer "B.Cu")
		(net 639)
	)
	(segment
		(start 83.845532 101.355)
		(end 83.395532 101.805)
		(width 0.19)
		(layer "F.Cu")
		(net 640)
	)
	(segment
		(start 88.28 99.485)
		(end 87.67663 99.485)
		(width 0.19)
		(layer "F.Cu")
		(net 640)
	)
	(segment
		(start 85.80663 101.355)
		(end 83.845532 101.355)
		(width 0.19)
		(layer "F.Cu")
		(net 640)
	)
	(segment
		(start 88.62 99.8)
		(end 88.595 99.8)
		(width 0.19)
		(layer "F.Cu")
		(net 640)
	)
	(segment
		(start 88.595 99.8)
		(end 88.28 99.485)
		(width 0.19)
		(layer "F.Cu")
		(net 640)
	)
	(segment
		(start 87.67663 99.485)
		(end 85.80663 101.355)
		(width 0.19)
		(layer "F.Cu")
		(net 640)
	)
	(via
		(at 83.395532 101.805)
		(size 0.45)
		(drill 0.1)
		(layers "F.Cu" "B.Cu")
		(net 640)
	)
	(segment
		(start 94.705532 76.375)
		(end 94.705532 76.025)
		(width 0.17)
		(layer "F.Cu")
		(net 642)
	)
	(segment
		(start 94.430532 76.65)
		(end 94.705532 76.375)
		(width 0.17)
		(layer "F.Cu")
		(net 642)
	)
	(segment
		(start 94.705532 76.025)
		(end 94.580532 75.9)
		(width 0.17)
		(layer "F.Cu")
		(net 642)
	)
	(via
		(at 109.4 121.395)
		(size 0.45)
		(drill 0.1)
		(layers "F.Cu" "B.Cu")
		(net 642)
	)
	(via
		(at 94.580532 75.9)
		(size 0.45)
		(drill 0.1)
		(layers "F.Cu" "B.Cu")
		(net 642)
	)
	(segment
		(start 109.829999 121.27)
		(end 109.525 121.27)
		(width 0.17)
		(layer "B.Cu")
		(net 642)
	)
	(segment
		(start 110.64 121.6)
		(end 110.159999 121.6)
		(width 0.17)
		(layer "B.Cu")
		(net 642)
	)
	(segment
		(start 109.525 121.27)
		(end 109.4 121.395)
		(width 0.17)
		(layer "B.Cu")
		(net 642)
	)
	(segment
		(start 110.159999 121.6)
		(end 109.829999 121.27)
		(width 0.17)
		(layer "B.Cu")
		(net 642)
	)
	(segment
		(start 94.04023 75.2625)
		(end 94.4534 75.2625)
		(width 0.125)
		(layer "In7.Cu")
		(net 642)
	)
	(segment
		(start 108.06 122.1375)
		(end 103.7034 122.1375)
		(width 0.125)
		(layer "In7.Cu")
		(net 642)
	)
	(segment
		(start 94.768031 75.577131)
		(end 94.768031 75.712501)
		(width 0.125)
		(layer "In7.Cu")
		(net 642)
	)
	(segment
		(start 108.48 122.0175)
		(end 108.48 121.752277)
		(width 0.125)
		(layer "In7.Cu")
		(net 642)
	)
	(segment
		(start 90.6625 113.9034)
		(end 90.6625 106.0034)
		(width 0.125)
		(layer "In7.Cu")
		(net 642)
	)
	(segment
		(start 90.1625 91.7966)
		(end 90.1625 78.2466)
		(width 0.125)
		(layer "In7.Cu")
		(net 642)
	)
	(segment
		(start 109.9534 122.1375)
		(end 108.6 122.1375)
		(width 0.125)
		(layer "In7.Cu")
		(net 642)
	)
	(segment
		(start 90.6625 106.0034)
		(end 87.9625 103.3034)
		(width 0.125)
		(layer "In7.Cu")
		(net 642)
	)
	(segment
		(start 108.18 121.752277)
		(end 108.18 122.0175)
		(width 0.125)
		(layer "In7.Cu")
		(net 642)
	)
	(segment
		(start 108.36 121.632277)
		(end 108.3 121.632277)
		(width 0.125)
		(layer "In7.Cu")
		(net 642)
	)
	(segment
		(start 93.55023 75.4025)
		(end 93.55023 75.7725)
		(width 0.125)
		(layer "In7.Cu")
		(net 642)
	)
	(segment
		(start 93.3625 116.6034)
		(end 90.6625 113.9034)
		(width 0.125)
		(layer "In7.Cu")
		(net 642)
	)
	(segment
		(start 90.1625 78.2466)
		(end 93.1466 75.2625)
		(width 0.125)
		(layer "In7.Cu")
		(net 642)
	)
	(segment
		(start 110.2875 121.5466)
		(end 110.2875 121.8034)
		(width 0.125)
		(layer "In7.Cu")
		(net 642)
	)
	(segment
		(start 109.587499 121.207501)
		(end 109.948401 121.207501)
		(width 0.125)
		(layer "In7.Cu")
		(net 642)
	)
	(segment
		(start 93.69023 75.9125)
		(end 93.76023 75.9125)
		(width 0.125)
		(layer "In7.Cu")
		(net 642)
	)
	(segment
		(start 110.2875 121.8034)
		(end 109.9534 122.1375)
		(width 0.125)
		(layer "In7.Cu")
		(net 642)
	)
	(segment
		(start 103.7034 122.1375)
		(end 103.0034 122.8375)
		(width 0.125)
		(layer "In7.Cu")
		(net 642)
	)
	(segment
		(start 87.9625 93.9966)
		(end 90.1625 91.7966)
		(width 0.125)
		(layer "In7.Cu")
		(net 642)
	)
	(segment
		(start 109.948401 121.207501)
		(end 110.2875 121.5466)
		(width 0.125)
		(layer "In7.Cu")
		(net 642)
	)
	(segment
		(start 93.1466 75.2625)
		(end 93.41023 75.2625)
		(width 0.125)
		(layer "In7.Cu")
		(net 642)
	)
	(segment
		(start 87.9625 103.3034)
		(end 87.9625 93.9966)
		(width 0.125)
		(layer "In7.Cu")
		(net 642)
	)
	(segment
		(start 93.3625 119.0034)
		(end 93.3625 116.6034)
		(width 0.125)
		(layer "In7.Cu")
		(net 642)
	)
	(segment
		(start 93.90023 75.7725)
		(end 93.90023 75.4025)
		(width 0.125)
		(layer "In7.Cu")
		(net 642)
	)
	(segment
		(start 94.768031 75.712501)
		(end 94.580532 75.9)
		(width 0.125)
		(layer "In7.Cu")
		(net 642)
	)
	(segment
		(start 94.4534 75.2625)
		(end 94.768031 75.577131)
		(width 0.125)
		(layer "In7.Cu")
		(net 642)
	)
	(segment
		(start 103.0034 122.8375)
		(end 97.1966 122.8375)
		(width 0.125)
		(layer "In7.Cu")
		(net 642)
	)
	(segment
		(start 109.4 121.395)
		(end 109.587499 121.207501)
		(width 0.125)
		(layer "In7.Cu")
		(net 642)
	)
	(segment
		(start 97.1966 122.8375)
		(end 93.3625 119.0034)
		(width 0.125)
		(layer "In7.Cu")
		(net 642)
	)
	(arc
		(start 108.18 122.0175)
		(mid 108.144853 122.102353)
		(end 108.06 122.1375)
		(width 0.125)
		(layer "In7.Cu")
		(net 642)
	)
	(arc
		(start 108.6 122.1375)
		(mid 108.515147 122.102353)
		(end 108.48 122.0175)
		(width 0.125)
		(layer "In7.Cu")
		(net 642)
	)
	(arc
		(start 108.48 121.752277)
		(mid 108.444853 121.667424)
		(end 108.36 121.632277)
		(width 0.125)
		(layer "In7.Cu")
		(net 642)
	)
	(arc
		(start 93.76023 75.9125)
		(mid 93.859225 75.871495)
		(end 93.90023 75.7725)
		(width 0.125)
		(layer "In7.Cu")
		(net 642)
	)
	(arc
		(start 93.55023 75.7725)
		(mid 93.591235 75.871495)
		(end 93.69023 75.9125)
		(width 0.125)
		(layer "In7.Cu")
		(net 642)
	)
	(arc
		(start 108.3 121.632277)
		(mid 108.215147 121.667424)
		(end 108.18 121.752277)
		(width 0.125)
		(layer "In7.Cu")
		(net 642)
	)
	(arc
		(start 93.90023 75.4025)
		(mid 93.941235 75.303505)
		(end 94.04023 75.2625)
		(width 0.125)
		(layer "In7.Cu")
		(net 642)
	)
	(arc
		(start 93.41023 75.2625)
		(mid 93.509225 75.303505)
		(end 93.55023 75.4025)
		(width 0.125)
		(layer "In7.Cu")
		(net 642)
	)
	(segment
		(start 141.4 92.85)
		(end 144.5 89.75)
		(width 0.1)
		(layer "F.Cu")
		(net 643)
	)
	(segment
		(start 144.5 89.75)
		(end 145.9 89.75)
		(width 0.1)
		(layer "F.Cu")
		(net 643)
	)
	(segment
		(start 141.65 84.95)
		(end 141.95 84.65)
		(width 0.1)
		(layer "F.Cu")
		(net 643)
	)
	(segment
		(start 140.35 84.95)
		(end 140 85.3)
		(width 0.1)
		(layer "F.Cu")
		(net 643)
	)
	(segment
		(start 140.35 84.95)
		(end 141.65 84.95)
		(width 0.1)
		(layer "F.Cu")
		(net 643)
	)
	(segment
		(start 141.95 83.8)
		(end 141.95 84.65)
		(width 0.1)
		(layer "F.Cu")
		(net 643)
	)
	(segment
		(start 141.75 83.6)
		(end 141.95 83.8)
		(width 0.1)
		(layer "F.Cu")
		(net 643)
	)
	(segment
		(start 153.225 105.41)
		(end 155.475 105.41)
		(width 0.1)
		(layer "F.Cu")
		(net 643)
	)
	(segment
		(start 142 82)
		(end 141.75 82.25)
		(width 0.1)
		(layer "F.Cu")
		(net 643)
	)
	(segment
		(start 142 80.8)
		(end 142 82)
		(width 0.1)
		(layer "F.Cu")
		(net 643)
	)
	(segment
		(start 140 87.65)
		(end 140.55 88.2)
		(width 0.1)
		(layer "F.Cu")
		(net 643)
	)
	(segment
		(start 146.2 89.45)
		(end 145.9 89.75)
		(width 0.1)
		(layer "F.Cu")
		(net 643)
	)
	(segment
		(start 138.830532 78.15)
		(end 139.380532 78.7)
		(width 0.1)
		(layer "F.Cu")
		(net 643)
	)
	(segment
		(start 141.8 80.6)
		(end 142 80.8)
		(width 0.1)
		(layer "F.Cu")
		(net 643)
	)
	(segment
		(start 141.4 92.85)
		(end 141.4 94.2)
		(width 0.1)
		(layer "F.Cu")
		(net 643)
	)
	(segment
		(start 146.2 89.05)
		(end 146.2 89.45)
		(width 0.1)
		(layer "F.Cu")
		(net 643)
	)
	(segment
		(start 140 85.3)
		(end 140 87.65)
		(width 0.1)
		(layer "F.Cu")
		(net 643)
	)
	(segment
		(start 141.3 78.7)
		(end 141.8 79.2)
		(width 0.1)
		(layer "F.Cu")
		(net 643)
	)
	(segment
		(start 141.8 79.2)
		(end 141.8 80.6)
		(width 0.1)
		(layer "F.Cu")
		(net 643)
	)
	(segment
		(start 140.55 88.2)
		(end 145.35 88.2)
		(width 0.1)
		(layer "F.Cu")
		(net 643)
	)
	(segment
		(start 145.35 88.2)
		(end 146.2 89.05)
		(width 0.1)
		(layer "F.Cu")
		(net 643)
	)
	(segment
		(start 141.75 82.25)
		(end 141.75 83.6)
		(width 0.1)
		(layer "F.Cu")
		(net 643)
	)
	(segment
		(start 139.380532 78.7)
		(end 141.3 78.7)
		(width 0.1)
		(layer "F.Cu")
		(net 643)
	)
	(via
		(at 141.4 94.2)
		(size 0.45)
		(drill 0.1)
		(layers "F.Cu" "B.Cu")
		(net 643)
	)
	(via
		(at 155.475 105.41)
		(size 0.45)
		(drill 0.1)
		(layers "F.Cu" "B.Cu")
		(net 643)
	)
	(segment
		(start 141.4 98)
		(end 147.95 104.55)
		(width 0.1)
		(layer "In4.Cu")
		(net 643)
	)
	(segment
		(start 147.95 104.55)
		(end 151.7 104.55)
		(width 0.1)
		(layer "In4.Cu")
		(net 643)
	)
	(segment
		(start 155.85 102.7)
		(end 155.85 105.035)
		(width 0.1)
		(layer "In4.Cu")
		(net 643)
	)
	(segment
		(start 151.7 104.55)
		(end 154.1 102.15)
		(width 0.1)
		(layer "In4.Cu")
		(net 643)
	)
	(segment
		(start 141.4 94.2)
		(end 141.4 98)
		(width 0.1)
		(layer "In4.Cu")
		(net 643)
	)
	(segment
		(start 154.1 102.15)
		(end 155.3 102.15)
		(width 0.1)
		(layer "In4.Cu")
		(net 643)
	)
	(segment
		(start 155.3 102.15)
		(end 155.85 102.7)
		(width 0.1)
		(layer "In4.Cu")
		(net 643)
	)
	(segment
		(start 155.85 105.035)
		(end 155.475 105.41)
		(width 0.1)
		(layer "In4.Cu")
		(net 643)
	)
	(via
		(at 164 54.5)
		(size 0.45)
		(drill 0.1)
		(layers "F.Cu" "B.Cu")
		(net 644)
	)
	(segment
		(start 168.348 60.8)
		(end 166.8 60.8)
		(width 0.1)
		(layer "B.Cu")
		(net 644)
	)
	(segment
		(start 166.8 60.8)
		(end 164.56 58.56)
		(width 0.1)
		(layer "B.Cu")
		(net 644)
	)
	(segment
		(start 164.56 58.56)
		(end 164.56 55.06)
		(width 0.1)
		(layer "B.Cu")
		(net 644)
	)
	(segment
		(start 164.56 55.06)
		(end 164 54.5)
		(width 0.1)
		(layer "B.Cu")
		(net 644)
	)
	(via
		(at 164 56)
		(size 0.45)
		(drill 0.1)
		(layers "F.Cu" "B.Cu")
		(net 645)
	)
	(segment
		(start 164 56)
		(end 164 57.02)
		(width 0.1)
		(layer "B.Cu")
		(net 645)
	)
	(segment
		(start 90.62 91.7)
		(end 90.595 91.7)
		(width 0.19)
		(layer "F.Cu")
		(net 648)
	)
	(segment
		(start 87.52663 92.015)
		(end 85.485 89.97337)
		(width 0.19)
		(layer "F.Cu")
		(net 648)
	)
	(segment
		(start 90.28 92.015)
		(end 87.52663 92.015)
		(width 0.19)
		(layer "F.Cu")
		(net 648)
	)
	(segment
		(start 83.12663 84.835)
		(end 83.82663 84.835)
		(width 0.19)
		(layer "F.Cu")
		(net 648)
	)
	(segment
		(start 83.82663 84.835)
		(end 84.285 84.37663)
		(width 0.19)
		(layer "F.Cu")
		(net 648)
	)
	(segment
		(start 85.485 89.97337)
		(end 85.485 87.42337)
		(width 0.19)
		(layer "F.Cu")
		(net 648)
	)
	(segment
		(start 85.07663 87.015)
		(end 83.17663 87.015)
		(width 0.19)
		(layer "F.Cu")
		(net 648)
	)
	(segment
		(start 82.935 86.77337)
		(end 82.935 85.02663)
		(width 0.19)
		(layer "F.Cu")
		(net 648)
	)
	(segment
		(start 83.81663 83.205)
		(end 82.575532 83.205)
		(width 0.19)
		(layer "F.Cu")
		(net 648)
	)
	(segment
		(start 84.285 84.37663)
		(end 84.285 83.67337)
		(width 0.19)
		(layer "F.Cu")
		(net 648)
	)
	(segment
		(start 84.285 83.67337)
		(end 83.81663 83.205)
		(width 0.19)
		(layer "F.Cu")
		(net 648)
	)
	(segment
		(start 85.485 87.42337)
		(end 85.07663 87.015)
		(width 0.19)
		(layer "F.Cu")
		(net 648)
	)
	(segment
		(start 82.575532 83.205)
		(end 82.125532 82.755)
		(width 0.19)
		(layer "F.Cu")
		(net 648)
	)
	(segment
		(start 90.595 91.7)
		(end 90.28 92.015)
		(width 0.19)
		(layer "F.Cu")
		(net 648)
	)
	(segment
		(start 83.17663 87.015)
		(end 82.935 86.77337)
		(width 0.19)
		(layer "F.Cu")
		(net 648)
	)
	(segment
		(start 82.935 85.02663)
		(end 83.12663 84.835)
		(width 0.19)
		(layer "F.Cu")
		(net 648)
	)
	(via
		(at 82.125532 82.755)
		(size 0.45)
		(drill 0.1)
		(layers "F.Cu" "B.Cu")
		(net 648)
	)
	(via
		(at 142.230532 76.65)
		(size 0.45)
		(drill 0.1)
		(layers "F.Cu" "B.Cu")
		(net 652)
	)
	(segment
		(start 143.6 74.4)
		(end 143.8 74.6)
		(width 0.1)
		(layer "B.Cu")
		(net 652)
	)
	(segment
		(start 143.4 77.1)
		(end 142.680532 77.1)
		(width 0.1)
		(layer "B.Cu")
		(net 652)
	)
	(segment
		(start 142.680532 77.1)
		(end 142.230532 76.65)
		(width 0.1)
		(layer "B.Cu")
		(net 652)
	)
	(segment
		(start 143.8 74.6)
		(end 143.8 76.2)
		(width 0.1)
		(layer "B.Cu")
		(net 652)
	)
	(segment
		(start 143.6 76.9)
		(end 143.4 77.1)
		(width 0.1)
		(layer "B.Cu")
		(net 652)
	)
	(segment
		(start 143.6 76.4)
		(end 143.6 76.9)
		(width 0.1)
		(layer "B.Cu")
		(net 652)
	)
	(segment
		(start 143.8 72.18)
		(end 143.8 73.1)
		(width 0.1)
		(layer "B.Cu")
		(net 652)
	)
	(segment
		(start 143.8 73.1)
		(end 143.6 73.3)
		(width 0.1)
		(layer "B.Cu")
		(net 652)
	)
	(segment
		(start 143.8 76.2)
		(end 143.6 76.4)
		(width 0.1)
		(layer "B.Cu")
		(net 652)
	)
	(segment
		(start 143.6 73.3)
		(end 143.6 74.4)
		(width 0.1)
		(layer "B.Cu")
		(net 652)
	)
	(segment
		(start 95.055532 76.375)
		(end 95.055532 76.025)
		(width 0.17)
		(layer "F.Cu")
		(net 653)
	)
	(segment
		(start 95.330532 76.65)
		(end 95.055532 76.375)
		(width 0.17)
		(layer "F.Cu")
		(net 653)
	)
	(segment
		(start 95.055532 76.025)
		(end 95.180532 75.9)
		(width 0.17)
		(layer "F.Cu")
		(net 653)
	)
	(via
		(at 95.180532 75.9)
		(size 0.45)
		(drill 0.1)
		(layers "F.Cu" "B.Cu")
		(net 653)
	)
	(via
		(at 109.4 120.795)
		(size 0.45)
		(drill 0.1)
		(layers "F.Cu" "B.Cu")
		(net 653)
	)
	(segment
		(start 110.159999 120.59)
		(end 109.829999 120.92)
		(width 0.17)
		(layer "B.Cu")
		(net 653)
	)
	(segment
		(start 109.525 120.92)
		(end 109.4 120.795)
		(width 0.17)
		(layer "B.Cu")
		(net 653)
	)
	(segment
		(start 110.64 120.59)
		(end 110.159999 120.59)
		(width 0.17)
		(layer "B.Cu")
		(net 653)
	)
	(segment
		(start 109.829999 120.92)
		(end 109.525 120.92)
		(width 0.17)
		(layer "B.Cu")
		(net 653)
	)
	(segment
		(start 110.5125 121.8966)
		(end 110.0466 122.3625)
		(width 0.125)
		(layer "In7.Cu")
		(net 653)
	)
	(segment
		(start 110.5125 121.4534)
		(end 110.5125 121.8966)
		(width 0.125)
		(layer "In7.Cu")
		(net 653)
	)
	(segment
		(start 94.5466 75.0375)
		(end 94.993033 75.483933)
		(width 0.125)
		(layer "In7.Cu")
		(net 653)
	)
	(segment
		(start 103.0966 123.0625)
		(end 97.1034 123.0625)
		(width 0.125)
		(layer "In7.Cu")
		(net 653)
	)
	(segment
		(start 94.993033 75.483933)
		(end 94.993033 75.712501)
		(width 0.125)
		(layer "In7.Cu")
		(net 653)
	)
	(segment
		(start 87.7375 93.9034)
		(end 89.9375 91.7034)
		(width 0.125)
		(layer "In7.Cu")
		(net 653)
	)
	(segment
		(start 90.4375 113.9966)
		(end 90.4375 106.0966)
		(width 0.125)
		(layer "In7.Cu")
		(net 653)
	)
	(segment
		(start 87.7375 103.3966)
		(end 87.7375 93.9034)
		(width 0.125)
		(layer "In7.Cu")
		(net 653)
	)
	(segment
		(start 93.1375 119.0966)
		(end 93.1375 116.6966)
		(width 0.125)
		(layer "In7.Cu")
		(net 653)
	)
	(segment
		(start 110.0466 122.3625)
		(end 103.7966 122.3625)
		(width 0.125)
		(layer "In7.Cu")
		(net 653)
	)
	(segment
		(start 97.1034 123.0625)
		(end 93.1375 119.0966)
		(width 0.125)
		(layer "In7.Cu")
		(net 653)
	)
	(segment
		(start 90.4375 106.0966)
		(end 87.7375 103.3966)
		(width 0.125)
		(layer "In7.Cu")
		(net 653)
	)
	(segment
		(start 93.0534 75.0375)
		(end 94.5466 75.0375)
		(width 0.125)
		(layer "In7.Cu")
		(net 653)
	)
	(segment
		(start 110.041599 120.982499)
		(end 110.5125 121.4534)
		(width 0.125)
		(layer "In7.Cu")
		(net 653)
	)
	(segment
		(start 109.587499 120.982499)
		(end 110.041599 120.982499)
		(width 0.125)
		(layer "In7.Cu")
		(net 653)
	)
	(segment
		(start 89.9375 78.1534)
		(end 93.0534 75.0375)
		(width 0.125)
		(layer "In7.Cu")
		(net 653)
	)
	(segment
		(start 89.9375 91.7034)
		(end 89.9375 78.1534)
		(width 0.125)
		(layer "In7.Cu")
		(net 653)
	)
	(segment
		(start 94.993033 75.712501)
		(end 95.180532 75.9)
		(width 0.125)
		(layer "In7.Cu")
		(net 653)
	)
	(segment
		(start 103.7966 122.3625)
		(end 103.0966 123.0625)
		(width 0.125)
		(layer "In7.Cu")
		(net 653)
	)
	(segment
		(start 109.4 120.795)
		(end 109.587499 120.982499)
		(width 0.125)
		(layer "In7.Cu")
		(net 653)
	)
	(segment
		(start 93.1375 116.6966)
		(end 90.4375 113.9966)
		(width 0.125)
		(layer "In7.Cu")
		(net 653)
	)
	(segment
		(start 81.785 77.12337)
		(end 81.849093 77.187463)
		(width 0.19)
		(layer "F.Cu")
		(net 656)
	)
	(segment
		(start 82.529506 77.867877)
		(end 82.935 78.27337)
		(width 0.19)
		(layer "F.Cu")
		(net 656)
	)
	(segment
		(start 83.85 79.6)
		(end 83.95 79.7)
		(width 0.19)
		(layer "F.Cu")
		(net 656)
	)
	(segment
		(start 83.95 79.7)
		(end 83.95 80.05)
		(width 0.19)
		(layer "F.Cu")
		(net 656)
	)
	(segment
		(start 82.361391 77.187463)
		(end 82.529505 77.355577)
		(width 0.19)
		(layer "F.Cu")
		(net 656)
	)
	(segment
		(start 83.785 80.215)
		(end 83.395532 80.215)
		(width 0.19)
		(layer "F.Cu")
		(net 656)
	)
	(segment
		(start 83.3 79.6)
		(end 83.85 79.6)
		(width 0.19)
		(layer "F.Cu")
		(net 656)
	)
	(segment
		(start 81.785 76.62)
		(end 81.785 77.12337)
		(width 0.19)
		(layer "F.Cu")
		(net 656)
	)
	(segment
		(start 83.95 80.05)
		(end 83.785 80.215)
		(width 0.19)
		(layer "F.Cu")
		(net 656)
	)
	(segment
		(start 82.1 76.28)
		(end 82.1 76.305)
		(width 0.19)
		(layer "F.Cu")
		(net 656)
	)
	(segment
		(start 82.935 79.235)
		(end 83.3 79.6)
		(width 0.19)
		(layer "F.Cu")
		(net 656)
	)
	(segment
		(start 82.1 76.305)
		(end 81.785 76.62)
		(width 0.19)
		(layer "F.Cu")
		(net 656)
	)
	(segment
		(start 82.935 78.27337)
		(end 82.935 79.235)
		(width 0.19)
		(layer "F.Cu")
		(net 656)
	)
	(via
		(at 83.395532 80.215)
		(size 0.45)
		(drill 0.1)
		(layers "F.Cu" "B.Cu")
		(net 656)
	)
	(arc
		(start 82.529505 77.355577)
		(mid 82.582556 77.483653)
		(end 82.529505 77.611727)
		(width 0.19)
		(layer "F.Cu")
		(net 656)
	)
	(arc
		(start 82.529505 77.611727)
		(mid 82.476455 77.739801)
		(end 82.529506 77.867877)
		(width 0.19)
		(layer "F.Cu")
		(net 656)
	)
	(arc
		(start 82.105243 77.187464)
		(mid 82.233317 77.134414)
		(end 82.361391 77.187463)
		(width 0.19)
		(layer "F.Cu")
		(net 656)
	)
	(arc
		(start 81.849093 77.187463)
		(mid 81.977169 77.240514)
		(end 82.105243 77.187464)
		(width 0.19)
		(layer "F.Cu")
		(net 656)
	)
	(segment
		(start 87.785 102.67663)
		(end 87.785 103.07663)
		(width 0.19)
		(layer "F.Cu")
		(net 657)
	)
	(segment
		(start 85.8 103.885)
		(end 85.79 103.895)
		(width 0.19)
		(layer "F.Cu")
		(net 657)
	)
	(segment
		(start 88.28 102.285)
		(end 88.17663 102.285)
		(width 0.19)
		(layer "F.Cu")
		(net 657)
	)
	(segment
		(start 87.785 103.07663)
		(end 86.97663 103.885)
		(width 0.19)
		(layer "F.Cu")
		(net 657)
	)
	(segment
		(start 86.97663 103.885)
		(end 85.8 103.885)
		(width 0.19)
		(layer "F.Cu")
		(net 657)
	)
	(segment
		(start 88.595 102.6)
		(end 88.28 102.285)
		(width 0.19)
		(layer "F.Cu")
		(net 657)
	)
	(segment
		(start 82.575532 103.895)
		(end 82.125532 104.345)
		(width 0.19)
		(layer "F.Cu")
		(net 657)
	)
	(segment
		(start 85.79 103.895)
		(end 82.575532 103.895)
		(width 0.19)
		(layer "F.Cu")
		(net 657)
	)
	(segment
		(start 88.62 102.6)
		(end 88.595 102.6)
		(width 0.19)
		(layer "F.Cu")
		(net 657)
	)
	(segment
		(start 88.17663 102.285)
		(end 87.785 102.67663)
		(width 0.19)
		(layer "F.Cu")
		(net 657)
	)
	(via
		(at 82.125532 104.345)
		(size 0.45)
		(drill 0.1)
		(layers "F.Cu" "B.Cu")
		(net 657)
	)
	(segment
		(start 79.4 75.8)
		(end 79.2 75.6)
		(width 0.1)
		(layer "F.Cu")
		(net 659)
	)
	(segment
		(start 79.4 76.8)
		(end 79.4 75.8)
		(width 0.1)
		(layer "F.Cu")
		(net 659)
	)
	(via
		(at 79.2 75.6)
		(size 0.45)
		(drill 0.1)
		(layers "F.Cu" "B.Cu")
		(net 659)
	)
	(segment
		(start 81.2 75.6)
		(end 79.2 75.6)
		(width 0.1)
		(layer "B.Cu")
		(net 659)
	)
	(segment
		(start 82.125532 76.525532)
		(end 81.2 75.6)
		(width 0.1)
		(layer "B.Cu")
		(net 659)
	)
	(segment
		(start 82.125532 78.945)
		(end 82.125532 76.525532)
		(width 0.1)
		(layer "B.Cu")
		(net 659)
	)
	(segment
		(start 82.565 86.92663)
		(end 82.565 84.87337)
		(width 0.19)
		(layer "F.Cu")
		(net 661)
	)
	(segment
		(start 83.915 84.22337)
		(end 83.915 83.82663)
		(width 0.19)
		(layer "F.Cu")
		(net 661)
	)
	(segment
		(start 83.02337 87.385)
		(end 82.565 86.92663)
		(width 0.19)
		(layer "F.Cu")
		(net 661)
	)
	(segment
		(start 82.575532 83.575)
		(end 82.125532 84.025)
		(width 0.19)
		(layer "F.Cu")
		(net 661)
	)
	(segment
		(start 85.115 87.57663)
		(end 84.92337 87.385)
		(width 0.19)
		(layer "F.Cu")
		(net 661)
	)
	(segment
		(start 90.595 92.7)
		(end 90.28 92.385)
		(width 0.19)
		(layer "F.Cu")
		(net 661)
	)
	(segment
		(start 83.67337 84.465)
		(end 83.915 84.22337)
		(width 0.19)
		(layer "F.Cu")
		(net 661)
	)
	(segment
		(start 83.915 83.82663)
		(end 83.66337 83.575)
		(width 0.19)
		(layer "F.Cu")
		(net 661)
	)
	(segment
		(start 87.37337 92.385)
		(end 85.115 90.12663)
		(width 0.19)
		(layer "F.Cu")
		(net 661)
	)
	(segment
		(start 90.28 92.385)
		(end 87.37337 92.385)
		(width 0.19)
		(layer "F.Cu")
		(net 661)
	)
	(segment
		(start 83.66337 83.575)
		(end 82.575532 83.575)
		(width 0.19)
		(layer "F.Cu")
		(net 661)
	)
	(segment
		(start 90.62 92.7)
		(end 90.595 92.7)
		(width 0.19)
		(layer "F.Cu")
		(net 661)
	)
	(segment
		(start 82.565 84.87337)
		(end 82.97337 84.465)
		(width 0.19)
		(layer "F.Cu")
		(net 661)
	)
	(segment
		(start 84.92337 87.385)
		(end 83.02337 87.385)
		(width 0.19)
		(layer "F.Cu")
		(net 661)
	)
	(segment
		(start 85.115 90.12663)
		(end 85.115 87.57663)
		(width 0.19)
		(layer "F.Cu")
		(net 661)
	)
	(segment
		(start 82.97337 84.465)
		(end 83.67337 84.465)
		(width 0.19)
		(layer "F.Cu")
		(net 661)
	)
	(via
		(at 82.125532 84.025)
		(size 0.45)
		(drill 0.1)
		(layers "F.Cu" "B.Cu")
		(net 661)
	)
	(segment
		(start 208.555 135.885)
		(end 208.67 136)
		(width 0.19)
		(layer "F.Cu")
		(net 662)
	)
	(segment
		(start 208.86 135.305)
		(end 208.555 135.61)
		(width 0.19)
		(layer "F.Cu")
		(net 662)
	)
	(segment
		(start 106.695532 76.115)
		(end 106.580532 76)
		(width 0.19)
		(layer "F.Cu")
		(net 662)
	)
	(segment
		(start 106.430532 76.65)
		(end 106.695532 76.385)
		(width 0.19)
		(layer "F.Cu")
		(net 662)
	)
	(segment
		(start 106.695532 76.385)
		(end 106.695532 76.115)
		(width 0.19)
		(layer "F.Cu")
		(net 662)
	)
	(segment
		(start 208.86 135.28)
		(end 208.86 135.305)
		(width 0.19)
		(layer "F.Cu")
		(net 662)
	)
	(segment
		(start 208.555 135.61)
		(end 208.555 135.885)
		(width 0.19)
		(layer "F.Cu")
		(net 662)
	)
	(via
		(at 106.580532 76)
		(size 0.45)
		(drill 0.1)
		(layers "F.Cu" "B.Cu")
		(net 662)
	)
	(via
		(at 208.67 136)
		(size 0.45)
		(drill 0.1)
		(layers "F.Cu" "B.Cu")
		(net 662)
	)
	(segment
		(start 147.6375 73.743044)
		(end 148.056956 74.1625)
		(width 0.15)
		(layer "In7.Cu")
		(net 662)
	)
	(segment
		(start 144.556956 71.2625)
		(end 145.606956 71.2625)
		(width 0.15)
		(layer "In7.Cu")
		(net 662)
	)
	(segment
		(start 202.006956 81.4625)
		(end 208.456956 81.4625)
		(width 0.15)
		(layer "In7.Cu")
		(net 662)
	)
	(segment
		(start 128.117451 62.508093)
		(end 128.853044 61.7725)
		(width 0.15)
		(layer "In7.Cu")
		(net 662)
	)
	(segment
		(start 148.056956 74.1625)
		(end 184.256956 74.1625)
		(width 0.15)
		(layer "In7.Cu")
		(net 662)
	)
	(segment
		(start 187.456956 77.3625)
		(end 195.156956 77.3625)
		(width 0.15)
		(layer "In7.Cu")
		(net 662)
	)
	(segment
		(start 219.3375 90.843044)
		(end 219.3375 108.356956)
		(width 0.15)
		(layer "In7.Cu")
		(net 662)
	)
	(segment
		(start 142.975003 68.336091)
		(end 142.975003 69.680547)
		(width 0.15)
		(layer "In7.Cu")
		(net 662)
	)
	(segment
		(start 142.975003 69.680547)
		(end 144.556956 71.2625)
		(width 0.15)
		(layer "In7.Cu")
		(net 662)
	)
	(segment
		(start 208.5075 130.686956)
		(end 208.5075 135.8375)
		(width 0.15)
		(layer "In7.Cu")
		(net 662)
	)
	(segment
		(start 213.556956 86.5625)
		(end 215.456956 86.5625)
		(width 0.15)
		(layer "In7.Cu")
		(net 662)
	)
	(segment
		(start 128.853044 61.7725)
		(end 130.356956 61.7725)
		(width 0.15)
		(layer "In7.Cu")
		(net 662)
	)
	(segment
		(start 216.1375 123.056956)
		(end 208.5075 130.686956)
		(width 0.15)
		(layer "In7.Cu")
		(net 662)
	)
	(segment
		(start 216.1375 111.556956)
		(end 216.1375 123.056956)
		(width 0.15)
		(layer "In7.Cu")
		(net 662)
	)
	(segment
		(start 216.7375 87.843044)
		(end 216.7375 89.143044)
		(width 0.15)
		(layer "In7.Cu")
		(net 662)
	)
	(segment
		(start 145.606956 71.2625)
		(end 147.6375 73.293044)
		(width 0.15)
		(layer "In7.Cu")
		(net 662)
	)
	(segment
		(start 200.806956 80.2625)
		(end 202.006956 81.4625)
		(width 0.15)
		(layer "In7.Cu")
		(net 662)
	)
	(segment
		(start 109.543044 74.2125)
		(end 110.7625 72.993044)
		(width 0.15)
		(layer "In7.Cu")
		(net 662)
	)
	(segment
		(start 208.5075 135.8375)
		(end 208.67 136)
		(width 0.15)
		(layer "In7.Cu")
		(net 662)
	)
	(segment
		(start 130.356956 61.7725)
		(end 130.874456 62.29)
		(width 0.15)
		(layer "In7.Cu")
		(net 662)
	)
	(segment
		(start 198.056956 80.2625)
		(end 200.806956 80.2625)
		(width 0.15)
		(layer "In7.Cu")
		(net 662)
	)
	(segment
		(start 215.456956 86.5625)
		(end 216.7375 87.843044)
		(width 0.15)
		(layer "In7.Cu")
		(net 662)
	)
	(segment
		(start 218.656956 90.1625)
		(end 219.3375 90.843044)
		(width 0.15)
		(layer "In7.Cu")
		(net 662)
	)
	(segment
		(start 195.156956 77.3625)
		(end 198.056956 80.2625)
		(width 0.15)
		(layer "In7.Cu")
		(net 662)
	)
	(segment
		(start 110.7625 67.443044)
		(end 115.697451 62.508093)
		(width 0.15)
		(layer "In7.Cu")
		(net 662)
	)
	(segment
		(start 208.456956 81.4625)
		(end 213.556956 86.5625)
		(width 0.15)
		(layer "In7.Cu")
		(net 662)
	)
	(segment
		(start 219.3375 108.356956)
		(end 216.1375 111.556956)
		(width 0.15)
		(layer "In7.Cu")
		(net 662)
	)
	(segment
		(start 115.697451 62.508093)
		(end 128.117451 62.508093)
		(width 0.15)
		(layer "In7.Cu")
		(net 662)
	)
	(segment
		(start 130.874456 62.29)
		(end 136.928912 62.29)
		(width 0.15)
		(layer "In7.Cu")
		(net 662)
	)
	(segment
		(start 184.256956 74.1625)
		(end 187.456956 77.3625)
		(width 0.15)
		(layer "In7.Cu")
		(net 662)
	)
	(segment
		(start 107.393044 74.2125)
		(end 109.543044 74.2125)
		(width 0.15)
		(layer "In7.Cu")
		(net 662)
	)
	(segment
		(start 217.756956 90.1625)
		(end 218.656956 90.1625)
		(width 0.15)
		(layer "In7.Cu")
		(net 662)
	)
	(segment
		(start 216.7375 89.143044)
		(end 217.756956 90.1625)
		(width 0.15)
		(layer "In7.Cu")
		(net 662)
	)
	(segment
		(start 110.7625 72.993044)
		(end 110.7625 67.443044)
		(width 0.15)
		(layer "In7.Cu")
		(net 662)
	)
	(segment
		(start 106.580532 76)
		(end 106.743032 75.8375)
		(width 0.15)
		(layer "In7.Cu")
		(net 662)
	)
	(segment
		(start 106.743032 74.862512)
		(end 107.393044 74.2125)
		(width 0.15)
		(layer "In7.Cu")
		(net 662)
	)
	(segment
		(start 106.743032 75.8375)
		(end 106.743032 74.862512)
		(width 0.15)
		(layer "In7.Cu")
		(net 662)
	)
	(segment
		(start 136.928912 62.29)
		(end 142.975003 68.336091)
		(width 0.15)
		(layer "In7.Cu")
		(net 662)
	)
	(segment
		(start 147.6375 73.293044)
		(end 147.6375 73.743044)
		(width 0.15)
		(layer "In7.Cu")
		(net 662)
	)
	(segment
		(start 212.115631 87.971856)
		(end 212.565632 87.971856)
		(width 0.19)
		(layer "F.Cu")
		(net 663)
	)
	(segment
		(start 205.255 87.970856)
		(end 205.57 87.655856)
		(width 0.19)
		(layer "F.Cu")
		(net 663)
	)
	(segment
		(start 211.644226 87.655856)
		(end 211.944726 87.956356)
		(width 0.19)
		(layer "F.Cu")
		(net 663)
	)
	(segment
		(start 212.100131 87.956356)
		(end 212.115631 87.971856)
		(width 0.19)
		(layer "F.Cu")
		(net 663)
	)
	(segment
		(start 211.944726 87.956356)
		(end 212.100131 87.956356)
		(width 0.19)
		(layer "F.Cu")
		(net 663)
	)
	(segment
		(start 205.57 87.655856)
		(end 211.644226 87.655856)
		(width 0.19)
		(layer "F.Cu")
		(net 663)
	)
	(segment
		(start 205.23 87.970856)
		(end 205.255 87.970856)
		(width 0.19)
		(layer "F.Cu")
		(net 663)
	)
	(segment
		(start 90.595 101.2)
		(end 90.28 100.885)
		(width 0.19)
		(layer "F.Cu")
		(net 665)
	)
	(segment
		(start 88.37663 100.885)
		(end 86.62663 102.635)
		(width 0.19)
		(layer "F.Cu")
		(net 665)
	)
	(segment
		(start 83.865 99.47337)
		(end 83.865 99.12663)
		(width 0.19)
		(layer "F.Cu")
		(net 665)
	)
	(segment
		(start 82.575532 98.815)
		(end 82.125532 99.265)
		(width 0.19)
		(layer "F.Cu")
		(net 665)
	)
	(segment
		(start 90.62 101.2)
		(end 90.595 101.2)
		(width 0.19)
		(layer "F.Cu")
		(net 665)
	)
	(segment
		(start 83.62337 99.715)
		(end 83.865 99.47337)
		(width 0.19)
		(layer "F.Cu")
		(net 665)
	)
	(segment
		(start 83.865 99.12663)
		(end 83.55337 98.815)
		(width 0.19)
		(layer "F.Cu")
		(net 665)
	)
	(segment
		(start 83.07337 99.715)
		(end 83.62337 99.715)
		(width 0.19)
		(layer "F.Cu")
		(net 665)
	)
	(segment
		(start 82.565 102.12663)
		(end 82.565 100.22337)
		(width 0.19)
		(layer "F.Cu")
		(net 665)
	)
	(segment
		(start 83.07337 102.635)
		(end 82.565 102.12663)
		(width 0.19)
		(layer "F.Cu")
		(net 665)
	)
	(segment
		(start 82.565 100.22337)
		(end 83.07337 99.715)
		(width 0.19)
		(layer "F.Cu")
		(net 665)
	)
	(segment
		(start 86.62663 102.635)
		(end 83.07337 102.635)
		(width 0.19)
		(layer "F.Cu")
		(net 665)
	)
	(segment
		(start 83.55337 98.815)
		(end 82.575532 98.815)
		(width 0.19)
		(layer "F.Cu")
		(net 665)
	)
	(segment
		(start 90.28 100.885)
		(end 88.37663 100.885)
		(width 0.19)
		(layer "F.Cu")
		(net 665)
	)
	(via
		(at 82.125532 99.265)
		(size 0.45)
		(drill 0.1)
		(layers "F.Cu" "B.Cu")
		(net 665)
	)
	(segment
		(start 212.101631 90.356856)
		(end 212.115631 90.370856)
		(width 0.19)
		(layer "F.Cu")
		(net 666)
	)
	(segment
		(start 205.23 90.970856)
		(end 205.255 90.970856)
		(width 0.19)
		(layer "F.Cu")
		(net 666)
	)
	(segment
		(start 205.57 90.655856)
		(end 210.755774 90.655856)
		(width 0.19)
		(layer "F.Cu")
		(net 666)
	)
	(segment
		(start 205.255 90.970856)
		(end 205.57 90.655856)
		(width 0.19)
		(layer "F.Cu")
		(net 666)
	)
	(segment
		(start 212.115631 90.370856)
		(end 212.565632 90.370856)
		(width 0.19)
		(layer "F.Cu")
		(net 666)
	)
	(segment
		(start 212.101631 90.356856)
		(end 211.054774 90.356856)
		(width 0.19)
		(layer "F.Cu")
		(net 666)
	)
	(segment
		(start 211.054774 90.356856)
		(end 210.755774 90.655856)
		(width 0.19)
		(layer "F.Cu")
		(net 666)
	)
	(segment
		(start 90.379945 123.309898)
		(end 90.450655 123.239189)
		(width 0.19)
		(layer "F.Cu")
		(net 668)
	)
	(segment
		(start 96.015 147.32337)
		(end 94.830502 148.507868)
		(width 0.19)
		(layer "F.Cu")
		(net 668)
	)
	(segment
		(start 96.015 132.57663)
		(end 96.015 147.32337)
		(width 0.19)
		(layer "F.Cu")
		(net 668)
	)
	(segment
		(start 90.57663 121.385)
		(end 89.885 122.07663)
		(width 0.19)
		(layer "F.Cu")
		(net 668)
	)
	(segment
		(start 89.975 125.202468)
		(end 89.847667 125.202468)
		(width 0.19)
		(layer "F.Cu")
		(net 668)
	)
	(segment
		(start 89.607667 125.442468)
		(end 89.607667 125.562468)
		(width 0.19)
		(layer "F.Cu")
		(net 668)
	)
	(segment
		(start 89.885 122.585)
		(end 90 122.7)
		(width 0.19)
		(layer "F.Cu")
		(net 668)
	)
	(segment
		(start 90.215 126.042468)
		(end 90.215 126.77663)
		(width 0.19)
		(layer "F.Cu")
		(net 668)
	)
	(segment
		(start 89.885 122.07663)
		(end 89.885 122.585)
		(width 0.19)
		(layer "F.Cu")
		(net 668)
	)
	(segment
		(start 98.430532 79.65)
		(end 98.695532 79.915)
		(width 0.19)
		(layer "F.Cu")
		(net 668)
	)
	(segment
		(start 90.215 124.32337)
		(end 90.215 124.962468)
		(width 0.19)
		(layer "F.Cu")
		(net 668)
	)
	(segment
		(start 90.215 126.77663)
		(end 96.015 132.57663)
		(width 0.19)
		(layer "F.Cu")
		(net 668)
	)
	(segment
		(start 94.830502 148.507868)
		(end 94.242133 148.507868)
		(width 0.19)
		(layer "F.Cu")
		(net 668)
	)
	(segment
		(start 98.695532 79.915)
		(end 98.695532 80.185)
		(width 0.19)
		(layer "F.Cu")
		(net 668)
	)
	(segment
		(start 98.695532 80.185)
		(end 98.580532 80.3)
		(width 0.19)
		(layer "F.Cu")
		(net 668)
	)
	(segment
		(start 91.515 123.02337)
		(end 91.515 121.87663)
		(width 0.19)
		(layer "F.Cu")
		(net 668)
	)
	(segment
		(start 91.515 121.87663)
		(end 91.02337 121.385)
		(width 0.19)
		(layer "F.Cu")
		(net 668)
	)
	(segment
		(start 93.940001 148.205736)
		(end 93.46 148.205736)
		(width 0.19)
		(layer "F.Cu")
		(net 668)
	)
	(segment
		(start 90.521365 124.017005)
		(end 90.215 124.32337)
		(width 0.19)
		(layer "F.Cu")
		(net 668)
	)
	(segment
		(start 94.242133 148.507868)
		(end 93.940001 148.205736)
		(width 0.19)
		(layer "F.Cu")
		(net 668)
	)
	(segment
		(start 90.733499 123.239188)
		(end 90.874921 123.38061)
		(width 0.19)
		(layer "F.Cu")
		(net 668)
	)
	(segment
		(start 89.847667 125.802468)
		(end 89.975 125.802468)
		(width 0.19)
		(layer "F.Cu")
		(net 668)
	)
	(segment
		(start 90.521365 123.734163)
		(end 90.379944 123.592742)
		(width 0.19)
		(layer "F.Cu")
		(net 668)
	)
	(segment
		(start 91.228473 123.309898)
		(end 91.515 123.02337)
		(width 0.19)
		(layer "F.Cu")
		(net 668)
	)
	(segment
		(start 91.157763 123.380611)
		(end 91.228473 123.309898)
		(width 0.19)
		(layer "F.Cu")
		(net 668)
	)
	(segment
		(start 91.02337 121.385)
		(end 90.57663 121.385)
		(width 0.19)
		(layer "F.Cu")
		(net 668)
	)
	(via
		(at 90 122.7)
		(size 0.45)
		(drill 0.1)
		(layers "F.Cu" "B.Cu")
		(net 668)
	)
	(via
		(at 98.580532 80.3)
		(size 0.45)
		(drill 0.1)
		(layers "F.Cu" "B.Cu")
		(net 668)
	)
	(via
		(at 85.55 97.366373)
		(size 0.45)
		(drill 0.1)
		(layers "F.Cu" "B.Cu")
		(net 668)
	)
	(via
		(at 93.4 148.2)
		(size 0.45)
		(drill 0.1)
		(layers "F.Cu" "B.Cu")
		(net 668)
	)
	(arc
		(start 89.847667 125.202468)
		(mid 89.677961 125.272762)
		(end 89.607667 125.442468)
		(width 0.19)
		(layer "F.Cu")
		(net 668)
	)
	(arc
		(start 89.607667 125.562468)
		(mid 89.677961 125.732174)
		(end 89.847667 125.802468)
		(width 0.19)
		(layer "F.Cu")
		(net 668)
	)
	(arc
		(start 90.521365 124.017005)
		(mid 90.579944 123.875583)
		(end 90.521365 123.734163)
		(width 0.19)
		(layer "F.Cu")
		(net 668)
	)
	(arc
		(start 89.975 125.802468)
		(mid 90.144706 125.872762)
		(end 90.215 126.042468)
		(width 0.19)
		(layer "F.Cu")
		(net 668)
	)
	(arc
		(start 90.379944 123.592742)
		(mid 90.321366 123.45132)
		(end 90.379945 123.309898)
		(width 0.19)
		(layer "F.Cu")
		(net 668)
	)
	(arc
		(start 90.215 124.962468)
		(mid 90.144706 125.132174)
		(end 89.975 125.202468)
		(width 0.19)
		(layer "F.Cu")
		(net 668)
	)
	(arc
		(start 90.450655 123.239189)
		(mid 90.592078 123.180609)
		(end 90.733499 123.239188)
		(width 0.19)
		(layer "F.Cu")
		(net 668)
	)
	(arc
		(start 90.874921 123.38061)
		(mid 91.016342 123.439189)
		(end 91.157763 123.380611)
		(width 0.19)
		(layer "F.Cu")
		(net 668)
	)
	(segment
		(start 93.35 148.17)
		(end 93.37 148.17)
		(width 0.19)
		(layer "B.Cu")
		(net 668)
	)
	(segment
		(start 93.37 148.17)
		(end 93.4 148.2)
		(width 0.19)
		(layer "B.Cu")
		(net 668)
	)
	(segment
		(start 95.594762 80.589642)
		(end 95.658401 80.526002)
		(width 0.15)
		(layer "In5.Cu")
		(net 668)
	)
	(segment
		(start 84.1375 95.668044)
		(end 84.1375 91.581956)
		(width 0.15)
		(layer "In5.Cu")
		(net 668)
	)
	(segment
		(start 92.9375 82.256956)
		(end 94.84523 80.349226)
		(width 0.15)
		(layer "In5.Cu")
		(net 668)
	)
	(segment
		(start 95.658401 80.271443)
		(end 95.417984 80.031026)
		(width 0.15)
		(layer "In5.Cu")
		(net 668)
	)
	(segment
		(start 86.9125 91.0875)
		(end 92.9375 85.0625)
		(width 0.15)
		(layer "In5.Cu")
		(net 668)
	)
	(segment
		(start 95.481626 79.712829)
		(end 96.156956 79.0375)
		(width 0.15)
		(layer "In5.Cu")
		(net 668)
	)
	(segment
		(start 84.1375 91.581956)
		(end 84.631956 91.0875)
		(width 0.15)
		(layer "In5.Cu")
		(net 668)
	)
	(segment
		(start 98.743032 80.1375)
		(end 98.580532 80.3)
		(width 0.15)
		(layer "In5.Cu")
		(net 668)
	)
	(segment
		(start 84.956956 95.9625)
		(end 84.431956 95.9625)
		(width 0.15)
		(layer "In5.Cu")
		(net 668)
	)
	(segment
		(start 95.099788 80.349226)
		(end 95.340204 80.589642)
		(width 0.15)
		(layer "In5.Cu")
		(net 668)
	)
	(segment
		(start 96.156956 79.0375)
		(end 98.093044 79.0375)
		(width 0.15)
		(layer "In5.Cu")
		(net 668)
	)
	(segment
		(start 84.431956 95.9625)
		(end 84.1375 95.668044)
		(width 0.15)
		(layer "In5.Cu")
		(net 668)
	)
	(segment
		(start 92.9375 85.0625)
		(end 92.9375 82.256956)
		(width 0.15)
		(layer "In5.Cu")
		(net 668)
	)
	(segment
		(start 98.743032 79.687488)
		(end 98.743032 80.1375)
		(width 0.15)
		(layer "In5.Cu")
		(net 668)
	)
	(segment
		(start 85.3875 96.393044)
		(end 84.956956 95.9625)
		(width 0.15)
		(layer "In5.Cu")
		(net 668)
	)
	(segment
		(start 85.3875 97.203873)
		(end 85.3875 96.393044)
		(width 0.15)
		(layer "In5.Cu")
		(net 668)
	)
	(segment
		(start 95.417984 79.776468)
		(end 95.481626 79.712829)
		(width 0.15)
		(layer "In5.Cu")
		(net 668)
	)
	(segment
		(start 85.55 97.366373)
		(end 85.3875 97.203873)
		(width 0.15)
		(layer "In5.Cu")
		(net 668)
	)
	(segment
		(start 98.093044 79.0375)
		(end 98.743032 79.687488)
		(width 0.15)
		(layer "In5.Cu")
		(net 668)
	)
	(segment
		(start 84.631956 91.0875)
		(end 86.9125 91.0875)
		(width 0.15)
		(layer "In5.Cu")
		(net 668)
	)
	(arc
		(start 95.417984 80.031026)
		(mid 95.365263 79.903747)
		(end 95.417984 79.776468)
		(width 0.15)
		(layer "In5.Cu")
		(net 668)
	)
	(arc
		(start 94.84523 80.349226)
		(mid 94.972509 80.296505)
		(end 95.099788 80.349226)
		(width 0.15)
		(layer "In5.Cu")
		(net 668)
	)
	(arc
		(start 95.658401 80.526002)
		(mid 95.711122 80.398722)
		(end 95.658401 80.271443)
		(width 0.15)
		(layer "In5.Cu")
		(net 668)
	)
	(arc
		(start 95.340204 80.589642)
		(mid 95.467483 80.642363)
		(end 95.594762 80.589642)
		(width 0.15)
		(layer "In5.Cu")
		(net 668)
	)
	(segment
		(start 85.55 97.366373)
		(end 85.3875 97.528873)
		(width 0.15)
		(layer "In7.Cu")
		(net 668)
	)
	(segment
		(start 88.7625 108.118044)
		(end 88.7625 118.268044)
		(width 0.15)
		(layer "In7.Cu")
		(net 668)
	)
	(segment
		(start 89.8375 119.343044)
		(end 89.8375 122.5375)
		(width 0.15)
		(layer "In7.Cu")
		(net 668)
	)
	(segment
		(start 88.7625 118.268044)
		(end 89.8375 119.343044)
		(width 0.15)
		(layer "In7.Cu")
		(net 668)
	)
	(segment
		(start 85.631956 106.1125)
		(end 86.756956 106.1125)
		(width 0.15)
		(layer "In7.Cu")
		(net 668)
	)
	(segment
		(start 85.3875 105.868044)
		(end 85.631956 106.1125)
		(width 0.15)
		(layer "In7.Cu")
		(net 668)
	)
	(segment
		(start 89.8375 122.5375)
		(end 90 122.7)
		(width 0.15)
		(layer "In7.Cu")
		(net 668)
	)
	(segment
		(start 86.756956 106.1125)
		(end 88.7625 108.118044)
		(width 0.15)
		(layer "In7.Cu")
		(net 668)
	)
	(segment
		(start 85.3875 97.528873)
		(end 85.3875 105.868044)
		(width 0.15)
		(layer "In7.Cu")
		(net 668)
	)
	(segment
		(start 109.065532 79.215)
		(end 109.180532 79.1)
		(width 0.19)
		(layer "F.Cu")
		(net 669)
	)
	(segment
		(start 109.065532 80.885)
		(end 109.065532 79.215)
		(width 0.19)
		(layer "F.Cu")
		(net 669)
	)
	(segment
		(start 109.330532 81.15)
		(end 109.065532 80.885)
		(width 0.19)
		(layer "F.Cu")
		(net 669)
	)
	(via
		(at 109.180532 79.1)
		(size 0.45)
		(drill 0.1)
		(layers "F.Cu" "B.Cu")
		(net 669)
	)
	(segment
		(start 105.085 81.47663)
		(end 105.97663 80.585)
		(width 0.19)
		(layer "B.Cu")
		(net 669)
	)
	(segment
		(start 108.47663 80.585)
		(end 109.065532 79.996098)
		(width 0.19)
		(layer "B.Cu")
		(net 669)
	)
	(segment
		(start 101.2005 93.356362)
		(end 101.2005 87.66113)
		(width 0.19)
		(layer "B.Cu")
		(net 669)
	)
	(segment
		(start 101.473083 93.596362)
		(end 101.4405 93.596362)
		(width 0.19)
		(layer "B.Cu")
		(net 669)
	)
	(segment
		(start 112.9945 105.3145)
		(end 106.251246 105.3145)
		(width 0.19)
		(layer "B.Cu")
		(net 669)
	)
	(segment
		(start 105.085 83.77663)
		(end 105.085 81.47663)
		(width 0.19)
		(layer "B.Cu")
		(net 669)
	)
	(segment
		(start 101.4405 94.196362)
		(end 101.473083 94.196362)
		(width 0.19)
		(layer "B.Cu")
		(net 669)
	)
	(segment
		(start 109.065532 79.996098)
		(end 109.065532 79.215)
		(width 0.19)
		(layer "B.Cu")
		(net 669)
	)
	(segment
		(start 101.2005 100.263754)
		(end 101.2005 94.436362)
		(width 0.19)
		(layer "B.Cu")
		(net 669)
	)
	(segment
		(start 101.2005 87.66113)
		(end 105.085 83.77663)
		(width 0.19)
		(layer "B.Cu")
		(net 669)
	)
	(segment
		(start 101.713083 93.956362)
		(end 101.713083 93.836362)
		(width 0.19)
		(layer "B.Cu")
		(net 669)
	)
	(segment
		(start 109.065532 79.215)
		(end 109.180532 79.1)
		(width 0.19)
		(layer "B.Cu")
		(net 669)
	)
	(segment
		(start 113.685 105.249)
		(end 113.06 105.249)
		(width 0.19)
		(layer "B.Cu")
		(net 669)
	)
	(segment
		(start 105.97663 80.585)
		(end 108.47663 80.585)
		(width 0.19)
		(layer "B.Cu")
		(net 669)
	)
	(segment
		(start 113.06 105.249)
		(end 112.9945 105.3145)
		(width 0.19)
		(layer "B.Cu")
		(net 669)
	)
	(segment
		(start 106.251246 105.3145)
		(end 101.2005 100.263754)
		(width 0.19)
		(layer "B.Cu")
		(net 669)
	)
	(arc
		(start 101.2005 94.436362)
		(mid 101.270794 94.266656)
		(end 101.4405 94.196362)
		(width 0.19)
		(layer "B.Cu")
		(net 669)
	)
	(arc
		(start 101.4405 93.596362)
		(mid 101.270794 93.526068)
		(end 101.2005 93.356362)
		(width 0.19)
		(layer "B.Cu")
		(net 669)
	)
	(arc
		(start 101.713083 93.836362)
		(mid 101.642789 93.666656)
		(end 101.473083 93.596362)
		(width 0.19)
		(layer "B.Cu")
		(net 669)
	)
	(arc
		(start 101.473083 94.196362)
		(mid 101.642789 94.126068)
		(end 101.713083 93.956362)
		(width 0.19)
		(layer "B.Cu")
		(net 669)
	)
	(via
		(at 141.330532 76.65)
		(size 0.45)
		(drill 0.1)
		(layers "F.Cu" "B.Cu")
		(net 673)
	)
	(segment
		(start 109.065532 84.985)
		(end 109.180532 85.1)
		(width 0.19)
		(layer "F.Cu")
		(net 674)
	)
	(segment
		(start 109.065532 84.415)
		(end 109.065532 84.985)
		(width 0.19)
		(layer "F.Cu")
		(net 674)
	)
	(segment
		(start 109.330532 84.15)
		(end 109.065532 84.415)
		(width 0.19)
		(layer "F.Cu")
		(net 674)
	)
	(via
		(at 109.180532 85.1)
		(size 0.45)
		(drill 0.1)
		(layers "F.Cu" "B.Cu")
		(net 674)
	)
	(segment
		(start 109.065532 85.996098)
		(end 109.065532 85.215)
		(width 0.19)
		(layer "B.Cu")
		(net 674)
	)
	(segment
		(start 104.2005 89.06113)
		(end 106.77663 86.485)
		(width 0.19)
		(layer "B.Cu")
		(net 674)
	)
	(segment
		(start 108.57663 86.485)
		(end 109.065532 85.996098)
		(width 0.19)
		(layer "B.Cu")
		(net 674)
	)
	(segment
		(start 104.713059 94.14618)
		(end 104.713059 94.02618)
		(width 0.19)
		(layer "B.Cu")
		(net 674)
	)
	(segment
		(start 104.2005 93.54618)
		(end 104.2005 89.06113)
		(width 0.19)
		(layer "B.Cu")
		(net 674)
	)
	(segment
		(start 112.9955 102.3145)
		(end 107.493886 102.3145)
		(width 0.19)
		(layer "B.Cu")
		(net 674)
	)
	(segment
		(start 109.065532 85.215)
		(end 109.180532 85.1)
		(width 0.19)
		(layer "B.Cu")
		(net 674)
	)
	(segment
		(start 104.4405 94.38618)
		(end 104.473059 94.38618)
		(width 0.19)
		(layer "B.Cu")
		(net 674)
	)
	(segment
		(start 104.2005 99.021114)
		(end 104.2005 94.62618)
		(width 0.19)
		(layer "B.Cu")
		(net 674)
	)
	(segment
		(start 107.493886 102.3145)
		(end 104.2005 99.021114)
		(width 0.19)
		(layer "B.Cu")
		(net 674)
	)
	(segment
		(start 113.06 102.25)
		(end 112.9955 102.3145)
		(width 0.19)
		(layer "B.Cu")
		(net 674)
	)
	(segment
		(start 106.77663 86.485)
		(end 108.57663 86.485)
		(width 0.19)
		(layer "B.Cu")
		(net 674)
	)
	(segment
		(start 113.685 102.25)
		(end 113.06 102.25)
		(width 0.19)
		(layer "B.Cu")
		(net 674)
	)
	(segment
		(start 104.473059 93.78618)
		(end 104.4405 93.78618)
		(width 0.19)
		(layer "B.Cu")
		(net 674)
	)
	(arc
		(start 104.2005 94.62618)
		(mid 104.270794 94.456474)
		(end 104.4405 94.38618)
		(width 0.19)
		(layer "B.Cu")
		(net 674)
	)
	(arc
		(start 104.4405 93.78618)
		(mid 104.270794 93.715886)
		(end 104.2005 93.54618)
		(width 0.19)
		(layer "B.Cu")
		(net 674)
	)
	(arc
		(start 104.473059 94.38618)
		(mid 104.642765 94.315886)
		(end 104.713059 94.14618)
		(width 0.19)
		(layer "B.Cu")
		(net 674)
	)
	(arc
		(start 104.713059 94.02618)
		(mid 104.642765 93.856474)
		(end 104.473059 93.78618)
		(width 0.19)
		(layer "B.Cu")
		(net 674)
	)
	(segment
		(start 83.82663 97.165)
		(end 85.07663 98.415)
		(width 0.19)
		(layer "F.Cu")
		(net 675)
	)
	(segment
		(start 85.07663 98.415)
		(end 86.27337 98.415)
		(width 0.19)
		(layer "F.Cu")
		(net 675)
	)
	(segment
		(start 80.67663 93.735)
		(end 80.435 93.97663)
		(width 0.19)
		(layer "F.Cu")
		(net 675)
	)
	(segment
		(start 81.87663 97.165)
		(end 83.82663 97.165)
		(width 0.19)
		(layer "F.Cu")
		(net 675)
	)
	(segment
		(start 80.838311 94.806064)
		(end 81.145847 94.498525)
		(width 0.19)
		(layer "F.Cu")
		(net 675)
	)
	(segment
		(start 87.07337 97.615)
		(end 90.28 97.615)
		(width 0.19)
		(layer "F.Cu")
		(net 675)
	)
	(segment
		(start 81.421618 94.774296)
		(end 81.114081 95.081834)
		(width 0.19)
		(layer "F.Cu")
		(net 675)
	)
	(segment
		(start 81.535 96.82337)
		(end 81.87663 97.165)
		(width 0.19)
		(layer "F.Cu")
		(net 675)
	)
	(segment
		(start 86.27337 98.415)
		(end 87.07337 97.615)
		(width 0.19)
		(layer "F.Cu")
		(net 675)
	)
	(segment
		(start 81.675532 93.735)
		(end 80.67663 93.735)
		(width 0.19)
		(layer "F.Cu")
		(net 675)
	)
	(segment
		(start 90.28 97.615)
		(end 90.595 97.3)
		(width 0.19)
		(layer "F.Cu")
		(net 675)
	)
	(segment
		(start 80.435 93.97663)
		(end 80.435 94.62337)
		(width 0.19)
		(layer "F.Cu")
		(net 675)
	)
	(segment
		(start 90.595 97.3)
		(end 90.62 97.3)
		(width 0.19)
		(layer "F.Cu")
		(net 675)
	)
	(segment
		(start 82.125532 94.185)
		(end 81.675532 93.735)
		(width 0.19)
		(layer "F.Cu")
		(net 675)
	)
	(segment
		(start 81.366465 94.498526)
		(end 81.421619 94.55368)
		(width 0.19)
		(layer "F.Cu")
		(net 675)
	)
	(segment
		(start 81.535 95.72337)
		(end 81.535 96.82337)
		(width 0.19)
		(layer "F.Cu")
		(net 675)
	)
	(segment
		(start 81.11408 95.30245)
		(end 81.169236 95.357606)
		(width 0.19)
		(layer "F.Cu")
		(net 675)
	)
	(segment
		(start 80.435 94.62337)
		(end 80.617693 94.806063)
		(width 0.19)
		(layer "F.Cu")
		(net 675)
	)
	(segment
		(start 81.169236 95.357606)
		(end 81.535 95.72337)
		(width 0.19)
		(layer "F.Cu")
		(net 675)
	)
	(via
		(at 82.125532 94.185)
		(size 0.45)
		(drill 0.1)
		(layers "F.Cu" "B.Cu")
		(net 675)
	)
	(arc
		(start 81.421619 94.55368)
		(mid 81.46731 94.663989)
		(end 81.421618 94.774296)
		(width 0.19)
		(layer "F.Cu")
		(net 675)
	)
	(arc
		(start 81.114081 95.081834)
		(mid 81.068389 95.192141)
		(end 81.11408 95.30245)
		(width 0.19)
		(layer "F.Cu")
		(net 675)
	)
	(arc
		(start 81.145847 94.498525)
		(mid 81.256156 94.452835)
		(end 81.366465 94.498526)
		(width 0.19)
		(layer "F.Cu")
		(net 675)
	)
	(arc
		(start 80.617693 94.806063)
		(mid 80.728002 94.851754)
		(end 80.838311 94.806064)
		(width 0.19)
		(layer "F.Cu")
		(net 675)
	)
	(via
		(at 125.7 114.9)
		(size 0.45)
		(drill 0.1)
		(layers "F.Cu" "B.Cu")
		(net 676)
	)
	(via
		(at 138.3 98.25)
		(size 0.45)
		(drill 0.1)
		(layers "F.Cu" "B.Cu")
		(net 676)
	)
	(via
		(at 131.630532 81.15)
		(size 0.45)
		(drill 0.1)
		(layers "F.Cu" "B.Cu")
		(net 676)
	)
	(segment
		(start 115.31337 131.825)
		(end 116.765 130.37337)
		(width 0.19)
		(layer "B.Cu")
		(net 676)
	)
	(segment
		(start 114.873501 131.76)
		(end 114.938501 131.825)
		(width 0.19)
		(layer "B.Cu")
		(net 676)
	)
	(segment
		(start 118.92337 116.615)
		(end 122.42337 116.615)
		(width 0.19)
		(layer "B.Cu")
		(net 676)
	)
	(segment
		(start 113.711 131.76)
		(end 114.873501 131.76)
		(width 0.19)
		(layer "B.Cu")
		(net 676)
	)
	(segment
		(start 128.985093 84.236134)
		(end 128.940097 84.281129)
		(width 0.19)
		(layer "B.Cu")
		(net 676)
	)
	(segment
		(start 128.940097 84.62054)
		(end 129.024949 84.705392)
		(width 0.19)
		(layer "B.Cu")
		(net 676)
	)
	(segment
		(start 138.415 96.97663)
		(end 138.415 98.135)
		(width 0.19)
		(layer "B.Cu")
		(net 676)
	)
	(segment
		(start 122.42337 116.615)
		(end 124.02337 115.015)
		(width 0.19)
		(layer "B.Cu")
		(net 676)
	)
	(segment
		(start 114.938501 131.825)
		(end 115.31337 131.825)
		(width 0.19)
		(layer "B.Cu")
		(net 676)
	)
	(segment
		(start 129.37337 81.665)
		(end 128.665 82.37337)
		(width 0.19)
		(layer "B.Cu")
		(net 676)
	)
	(segment
		(start 130.265 85.17663)
		(end 130.265 88.82663)
		(width 0.19)
		(layer "B.Cu")
		(net 676)
	)
	(segment
		(start 128.665 82.37337)
		(end 128.665 83.57663)
		(width 0.19)
		(layer "B.Cu")
		(net 676)
	)
	(segment
		(start 116.765 118.77337)
		(end 118.92337 116.615)
		(width 0.19)
		(layer "B.Cu")
		(net 676)
	)
	(segment
		(start 129.748767 84.660396)
		(end 130.265 85.17663)
		(width 0.19)
		(layer "B.Cu")
		(net 676)
	)
	(segment
		(start 138.415 98.135)
		(end 138.3 98.25)
		(width 0.19)
		(layer "B.Cu")
		(net 676)
	)
	(segment
		(start 128.665 83.57663)
		(end 128.985093 83.896723)
		(width 0.19)
		(layer "B.Cu")
		(net 676)
	)
	(segment
		(start 125.585 115.015)
		(end 125.7 114.9)
		(width 0.19)
		(layer "B.Cu")
		(net 676)
	)
	(segment
		(start 131.630532 81.52674)
		(end 131.492272 81.665)
		(width 0.19)
		(layer "B.Cu")
		(net 676)
	)
	(segment
		(start 116.765 130.37337)
		(end 116.765 118.77337)
		(width 0.19)
		(layer "B.Cu")
		(net 676)
	)
	(segment
		(start 129.364361 84.705392)
		(end 129.409356 84.660396)
		(width 0.19)
		(layer "B.Cu")
		(net 676)
	)
	(segment
		(start 131.492272 81.665)
		(end 129.37337 81.665)
		(width 0.19)
		(layer "B.Cu")
		(net 676)
	)
	(segment
		(start 130.265 88.82663)
		(end 138.415 96.97663)
		(width 0.19)
		(layer "B.Cu")
		(net 676)
	)
	(segment
		(start 124.02337 115.015)
		(end 125.585 115.015)
		(width 0.19)
		(layer "B.Cu")
		(net 676)
	)
	(segment
		(start 131.630532 81.15)
		(end 131.630532 81.52674)
		(width 0.19)
		(layer "B.Cu")
		(net 676)
	)
	(arc
		(start 128.940097 84.281129)
		(mid 128.869803 84.450834)
		(end 128.940097 84.62054)
		(width 0.19)
		(layer "B.Cu")
		(net 676)
	)
	(arc
		(start 128.985093 83.896723)
		(mid 129.055387 84.066429)
		(end 128.985093 84.236134)
		(width 0.19)
		(layer "B.Cu")
		(net 676)
	)
	(arc
		(start 129.024949 84.705392)
		(mid 129.194655 84.775687)
		(end 129.364361 84.705392)
		(width 0.19)
		(layer "B.Cu")
		(net 676)
	)
	(arc
		(start 129.409356 84.660396)
		(mid 129.579061 84.590102)
		(end 129.748767 84.660396)
		(width 0.19)
		(layer "B.Cu")
		(net 676)
	)
	(segment
		(start 138.4625 98.4125)
		(end 138.3 98.25)
		(width 0.15)
		(layer "In7.Cu")
		(net 676)
	)
	(segment
		(start 125.8625 115.0625)
		(end 127.243044 115.0625)
		(width 0.15)
		(layer "In7.Cu")
		(net 676)
	)
	(segment
		(start 127.863044 114.4425)
		(end 128.843044 114.4425)
		(width 0.15)
		(layer "In7.Cu")
		(net 676)
	)
	(segment
		(start 130.1625 109.643044)
		(end 138.4625 101.343044)
		(width 0.15)
		(layer "In7.Cu")
		(net 676)
	)
	(segment
		(start 127.243044 115.0625)
		(end 127.863044 114.4425)
		(width 0.15)
		(layer "In7.Cu")
		(net 676)
	)
	(segment
		(start 125.7 114.9)
		(end 125.8625 115.0625)
		(width 0.15)
		(layer "In7.Cu")
		(net 676)
	)
	(segment
		(start 128.843044 114.4425)
		(end 130.1625 113.123044)
		(width 0.15)
		(layer "In7.Cu")
		(net 676)
	)
	(segment
		(start 130.1625 113.123044)
		(end 130.1625 109.643044)
		(width 0.15)
		(layer "In7.Cu")
		(net 676)
	)
	(segment
		(start 138.4625 101.343044)
		(end 138.4625 98.4125)
		(width 0.15)
		(layer "In7.Cu")
		(net 676)
	)
	(segment
		(start 129.095 140.714999)
		(end 129.095 141.705)
		(width 0.1)
		(layer "F.Cu")
		(net 677)
	)
	(segment
		(start 129.095 141.705)
		(end 128.81 141.99)
		(width 0.1)
		(layer "F.Cu")
		(net 677)
	)
	(segment
		(start 128.81 141.99)
		(end 128.81 142.72)
		(width 0.1)
		(layer "F.Cu")
		(net 677)
	)
	(via
		(at 128.9 141.9)
		(size 0.45)
		(drill 0.1)
		(layers "F.Cu" "B.Cu")
		(net 677)
	)
	(via
		(at 87 141.1)
		(size 0.45)
		(drill 0.1)
		(layers "F.Cu" "B.Cu")
		(net 677)
	)
	(segment
		(start 82.65 120.25)
		(end 81.460532 120.25)
		(width 0.1)
		(layer "B.Cu")
		(net 677)
	)
	(segment
		(start 87.5 141.1)
		(end 89.2 139.4)
		(width 0.1)
		(layer "B.Cu")
		(net 677)
	)
	(segment
		(start 82.9 128.85)
		(end 82.9 120.5)
		(width 0.1)
		(layer "B.Cu")
		(net 677)
	)
	(segment
		(start 89.2 139.4)
		(end 89.2 131.3)
		(width 0.1)
		(layer "B.Cu")
		(net 677)
	)
	(segment
		(start 81.460532 120.25)
		(end 80.855532 120.855)
		(width 0.1)
		(layer "B.Cu")
		(net 677)
	)
	(segment
		(start 89.2 131.3)
		(end 87.7 129.8)
		(width 0.1)
		(layer "B.Cu")
		(net 677)
	)
	(segment
		(start 87.7 129.8)
		(end 83.85 129.8)
		(width 0.1)
		(layer "B.Cu")
		(net 677)
	)
	(segment
		(start 82.9 120.5)
		(end 82.65 120.25)
		(width 0.1)
		(layer "B.Cu")
		(net 677)
	)
	(segment
		(start 83.85 129.8)
		(end 82.9 128.85)
		(width 0.1)
		(layer "B.Cu")
		(net 677)
	)
	(segment
		(start 87 141.1)
		(end 87.5 141.1)
		(width 0.1)
		(layer "B.Cu")
		(net 677)
	)
	(segment
		(start 87 141.1)
		(end 99.634314 141.1)
		(width 0.1)
		(layer "In7.Cu")
		(net 677)
	)
	(segment
		(start 121.8 141)
		(end 120.5 142.3)
		(width 0.1)
		(layer "In7.Cu")
		(net 677)
	)
	(segment
		(start 128.9 141.9)
		(end 128 141)
		(width 0.1)
		(layer "In7.Cu")
		(net 677)
	)
	(segment
		(start 100.834314 142.3)
		(end 99.634314 141.1)
		(width 0.1)
		(layer "In7.Cu")
		(net 677)
	)
	(segment
		(start 128 141)
		(end 121.8 141)
		(width 0.1)
		(layer "In7.Cu")
		(net 677)
	)
	(segment
		(start 120.5 142.3)
		(end 100.834314 142.3)
		(width 0.1)
		(layer "In7.Cu")
		(net 677)
	)
	(via
		(at 143.330532 78.15)
		(size 0.45)
		(drill 0.1)
		(layers "F.Cu" "B.Cu")
		(net 678)
	)
	(segment
		(start 143.330532 78.15)
		(end 143.330532 78.51)
		(width 0.1)
		(layer "B.Cu")
		(net 678)
	)
	(segment
		(start 143.330532 78.51)
		(end 143.630532 78.81)
		(width 0.1)
		(layer "B.Cu")
		(net 678)
	)
	(segment
		(start 116.6 130.7)
		(end 118.8 132.9)
		(width 0.1)
		(layer "F.Cu")
		(net 679)
	)
	(segment
		(start 121.8 83.6)
		(end 121.8 84.7)
		(width 0.1)
		(layer "F.Cu")
		(net 679)
	)
	(segment
		(start 121.1 106.1)
		(end 116.6 110.6)
		(width 0.1)
		(layer "F.Cu")
		(net 679)
	)
	(segment
		(start 121.8 84.7)
		(end 121.1 85.4)
		(width 0.1)
		(layer "F.Cu")
		(net 679)
	)
	(segment
		(start 120.430532 84.15)
		(end 120.430532 83.969468)
		(width 0.1)
		(layer "F.Cu")
		(net 679)
	)
	(segment
		(start 121.7 83.5)
		(end 121.8 83.6)
		(width 0.1)
		(layer "F.Cu")
		(net 679)
	)
	(segment
		(start 116.6 110.6)
		(end 116.6 130.7)
		(width 0.1)
		(layer "F.Cu")
		(net 679)
	)
	(segment
		(start 121.1 85.4)
		(end 121.1 106.1)
		(width 0.1)
		(layer "F.Cu")
		(net 679)
	)
	(segment
		(start 118.8 132.9)
		(end 126 132.9)
		(width 0.1)
		(layer "F.Cu")
		(net 679)
	)
	(segment
		(start 120.430532 83.969468)
		(end 120.9 83.5)
		(width 0.1)
		(layer "F.Cu")
		(net 679)
	)
	(segment
		(start 120.9 83.5)
		(end 121.7 83.5)
		(width 0.1)
		(layer "F.Cu")
		(net 679)
	)
	(via
		(at 126 132.9)
		(size 0.45)
		(drill 0.1)
		(layers "F.Cu" "B.Cu")
		(net 679)
	)
	(segment
		(start 126 132.9)
		(end 125.08 132.9)
		(width 0.1)
		(layer "B.Cu")
		(net 679)
	)
	(segment
		(start 85.235 95.185)
		(end 85.085 95.035)
		(width 0.19)
		(layer "F.Cu")
		(net 680)
	)
	(segment
		(start 83.865 92.67663)
		(end 83.62337 92.435)
		(width 0.19)
		(layer "F.Cu")
		(net 680)
	)
	(segment
		(start 82.565 92.02663)
		(end 82.565 90.02337)
		(width 0.19)
		(layer "F.Cu")
		(net 680)
	)
	(segment
		(start 83.865 88.92663)
		(end 83.59337 88.655)
		(width 0.19)
		(layer "F.Cu")
		(net 680)
	)
	(segment
		(start 83.62337 92.435)
		(end 82.97337 92.435)
		(width 0.19)
		(layer "F.Cu")
		(net 680)
	)
	(segment
		(start 83.865 89.27337)
		(end 83.865 88.92663)
		(width 0.19)
		(layer "F.Cu")
		(net 680)
	)
	(segment
		(start 83.59337 88.655)
		(end 82.575532 88.655)
		(width 0.19)
		(layer "F.Cu")
		(net 680)
	)
	(segment
		(start 90.595 95.5)
		(end 90.28 95.185)
		(width 0.19)
		(layer "F.Cu")
		(net 680)
	)
	(segment
		(start 90.62 95.5)
		(end 90.595 95.5)
		(width 0.19)
		(layer "F.Cu")
		(net 680)
	)
	(segment
		(start 82.565 90.02337)
		(end 83.02337 89.565)
		(width 0.19)
		(layer "F.Cu")
		(net 680)
	)
	(segment
		(start 82.575532 88.655)
		(end 82.125532 89.105)
		(width 0.19)
		(layer "F.Cu")
		(net 680)
	)
	(segment
		(start 82.97337 92.435)
		(end 82.565 92.02663)
		(width 0.19)
		(layer "F.Cu")
		(net 680)
	)
	(segment
		(start 83.02337 89.565)
		(end 83.57337 89.565)
		(width 0.19)
		(layer "F.Cu")
		(net 680)
	)
	(segment
		(start 83.865 94.52663)
		(end 83.865 92.67663)
		(width 0.19)
		(layer "F.Cu")
		(net 680)
	)
	(segment
		(start 83.57337 89.565)
		(end 83.865 89.27337)
		(width 0.19)
		(layer "F.Cu")
		(net 680)
	)
	(segment
		(start 90.28 95.185)
		(end 85.235 95.185)
		(width 0.19)
		(layer "F.Cu")
		(net 680)
	)
	(segment
		(start 84.37337 95.035)
		(end 83.865 94.52663)
		(width 0.19)
		(layer "F.Cu")
		(net 680)
	)
	(segment
		(start 85.085 95.035)
		(end 84.37337 95.035)
		(width 0.19)
		(layer "F.Cu")
		(net 680)
	)
	(via
		(at 82.125532 89.105)
		(size 0.45)
		(drill 0.1)
		(layers "F.Cu" "B.Cu")
		(net 680)
	)
	(segment
		(start 110.695532 85.915)
		(end 110.695532 90.585)
		(width 0.19)
		(layer "F.Cu")
		(net 681)
	)
	(segment
		(start 110.430532 85.65)
		(end 110.695532 85.915)
		(width 0.19)
		(layer "F.Cu")
		(net 681)
	)
	(segment
		(start 110.695532 90.585)
		(end 110.580532 90.7)
		(width 0.19)
		(layer "F.Cu")
		(net 681)
	)
	(via
		(at 110.580532 90.7)
		(size 0.45)
		(drill 0.1)
		(layers "F.Cu" "B.Cu")
		(net 681)
	)
	(segment
		(start 113.685 96.749)
		(end 113.06 96.749)
		(width 0.19)
		(layer "B.Cu")
		(net 681)
	)
	(segment
		(start 112.9945 96.6835)
		(end 111.62187 96.6835)
		(width 0.19)
		(layer "B.Cu")
		(net 681)
	)
	(segment
		(start 113.06 96.749)
		(end 112.9945 96.6835)
		(width 0.19)
		(layer "B.Cu")
		(net 681)
	)
	(segment
		(start 111.62187 96.6835)
		(end 110.695532 95.757162)
		(width 0.19)
		(layer "B.Cu")
		(net 681)
	)
	(segment
		(start 110.580532 90.7)
		(end 110.695532 90.815)
		(width 0.19)
		(layer "B.Cu")
		(net 681)
	)
	(segment
		(start 110.695532 90.815)
		(end 110.695532 95.757162)
		(width 0.19)
		(layer "B.Cu")
		(net 681)
	)
	(segment
		(start 91.495001 102.78)
		(end 91.180001 103.095)
		(width 0.19)
		(layer "B.Cu")
		(net 682)
	)
	(segment
		(start 89.993242 101.194283)
		(end 89.96878 101.218744)
		(width 0.19)
		(layer "B.Cu")
		(net 682)
	)
	(segment
		(start 91.495001 102.356631)
		(end 91.495001 102.750893)
		(width 0.19)
		(layer "B.Cu")
		(net 682)
	)
	(segment
		(start 89.615 100.47663)
		(end 89.993242 100.854872)
		(width 0.19)
		(layer "B.Cu")
		(net 682)
	)
	(segment
		(start 86.3 98.81)
		(end 89.34837 98.81)
		(width 0.19)
		(layer "B.Cu")
		(net 682)
	)
	(segment
		(start 86.285 98.795)
		(end 86.3 98.81)
		(width 0.19)
		(layer "B.Cu")
		(net 682)
	)
	(segment
		(start 85.135532 98.795)
		(end 86.285 98.795)
		(width 0.1)
		(layer "B.Cu")
		(net 682)
	)
	(segment
		(start 84.665532 99.265)
		(end 85.135532 98.795)
		(width 0.1)
		(layer "B.Cu")
		(net 682)
	)
	(segment
		(start 89.615 99.07663)
		(end 89.615 100.47663)
		(width 0.19)
		(layer "B.Cu")
		(net 682)
	)
	(segment
		(start 89.96878 101.558155)
		(end 90.053632 101.643007)
		(width 0.19)
		(layer "B.Cu")
		(net 682)
	)
	(segment
		(start 89.34837 98.81)
		(end 89.615 99.07663)
		(width 0.19)
		(layer "B.Cu")
		(net 682)
	)
	(segment
		(start 91.180001 103.095)
		(end 91.180001 103.12)
		(width 0.19)
		(layer "B.Cu")
		(net 682)
	)
	(segment
		(start 90.756916 101.618545)
		(end 90.84177 101.7034)
		(width 0.19)
		(layer "B.Cu")
		(net 682)
	)
	(segment
		(start 90.84177 101.7034)
		(end 91.495001 102.356631)
		(width 0.19)
		(layer "B.Cu")
		(net 682)
	)
	(segment
		(start 90.393044 101.643007)
		(end 90.417505 101.618545)
		(width 0.19)
		(layer "B.Cu")
		(net 682)
	)
	(segment
		(start 91.495001 102.750893)
		(end 91.495001 102.78)
		(width 0.19)
		(layer "B.Cu")
		(net 682)
	)
	(arc
		(start 90.417505 101.618545)
		(mid 90.58721 101.548251)
		(end 90.756916 101.618545)
		(width 0.19)
		(layer "B.Cu")
		(net 682)
	)
	(arc
		(start 89.96878 101.218744)
		(mid 89.898486 101.388449)
		(end 89.96878 101.558155)
		(width 0.19)
		(layer "B.Cu")
		(net 682)
	)
	(arc
		(start 89.993242 100.854872)
		(mid 90.063536 101.024578)
		(end 89.993242 101.194283)
		(width 0.19)
		(layer "B.Cu")
		(net 682)
	)
	(arc
		(start 90.053632 101.643007)
		(mid 90.223338 101.713302)
		(end 90.393044 101.643007)
		(width 0.19)
		(layer "B.Cu")
		(net 682)
	)
	(segment
		(start 84.125 81.925)
		(end 85.6 83.4)
		(width 0.1)
		(layer "F.Cu")
		(net 683)
	)
	(segment
		(start 82.85 57)
		(end 82.85 55.67)
		(width 0.1)
		(layer "F.Cu")
		(net 683)
	)
	(segment
		(start 81.925 81.925)
		(end 80.2 80.2)
		(width 0.1)
		(layer "F.Cu")
		(net 683)
	)
	(segment
		(start 82.85 55.67)
		(end 83.02 55.5)
		(width 0.1)
		(layer "F.Cu")
		(net 683)
	)
	(segment
		(start 83.02 54.77)
		(end 83 54.75)
		(width 0.1)
		(layer "F.Cu")
		(net 683)
	)
	(segment
		(start 88.130532 85.65)
		(end 85.880532 83.4)
		(width 0.1)
		(layer "F.Cu")
		(net 683)
	)
	(segment
		(start 80.2 80.2)
		(end 80.2 69.8)
		(width 0.1)
		(layer "F.Cu")
		(net 683)
	)
	(segment
		(start 83.02 55.5)
		(end 83.02 54.77)
		(width 0.1)
		(layer "F.Cu")
		(net 683)
	)
	(segment
		(start 85.880532 83.4)
		(end 85.6 83.4)
		(width 0.1)
		(layer "F.Cu")
		(net 683)
	)
	(segment
		(start 81.925 81.925)
		(end 84.125 81.925)
		(width 0.1)
		(layer "F.Cu")
		(net 683)
	)
	(via
		(at 80.2 69.8)
		(size 0.45)
		(drill 0.1)
		(layers "F.Cu" "B.Cu")
		(net 683)
	)
	(via
		(at 83 54.75)
		(size 0.45)
		(drill 0.1)
		(layers "F.Cu" "B.Cu")
		(net 683)
	)
	(segment
		(start 83 65.95)
		(end 83.55 65.4)
		(width 0.1)
		(layer "B.Cu")
		(net 683)
	)
	(segment
		(start 84.4 59.85)
		(end 84.5 59.85)
		(width 0.1)
		(layer "B.Cu")
		(net 683)
	)
	(segment
		(start 84.6 59.75)
		(end 84.6 59.2)
		(width 0.1)
		(layer "B.Cu")
		(net 683)
	)
	(segment
		(start 84.6 59.95)
		(end 84.6 59.85)
		(width 0.1)
		(layer "B.Cu")
		(net 683)
	)
	(segment
		(start 80.2 69.8)
		(end 80.2 67.9)
		(width 0.1)
		(layer "B.Cu")
		(net 683)
	)
	(segment
		(start 84.6 59.2)
		(end 83 57.6)
		(width 0.1)
		(layer "B.Cu")
		(net 683)
	)
	(segment
		(start 83 57.6)
		(end 83 54.75)
		(width 0.1)
		(layer "B.Cu")
		(net 683)
	)
	(segment
		(start 83.55 65.05)
		(end 84.6 64)
		(width 0.1)
		(layer "B.Cu")
		(net 683)
	)
	(segment
		(start 83.55 65.4)
		(end 83.55 65.05)
		(width 0.1)
		(layer "B.Cu")
		(net 683)
	)
	(segment
		(start 84.6 59.85)
		(end 84.6 59.75)
		(width 0.1)
		(layer "B.Cu")
		(net 683)
	)
	(segment
		(start 84.4 59.85)
		(end 84.6 59.85)
		(width 0.1)
		(layer "B.Cu")
		(net 683)
	)
	(segment
		(start 84.6 64)
		(end 84.6 59.95)
		(width 0.1)
		(layer "B.Cu")
		(net 683)
	)
	(segment
		(start 80.8 67.3)
		(end 82.7 67.3)
		(width 0.1)
		(layer "B.Cu")
		(net 683)
	)
	(segment
		(start 83 67)
		(end 83 65.95)
		(width 0.1)
		(layer "B.Cu")
		(net 683)
	)
	(segment
		(start 84.5 59.85)
		(end 84.6 59.95)
		(width 0.1)
		(layer "B.Cu")
		(net 683)
	)
	(segment
		(start 80.2 67.9)
		(end 80.8 67.3)
		(width 0.1)
		(layer "B.Cu")
		(net 683)
	)
	(segment
		(start 82.7 67.3)
		(end 83 67)
		(width 0.1)
		(layer "B.Cu")
		(net 683)
	)
	(segment
		(start 83.5 59.85)
		(end 84.4 59.85)
		(width 0.1)
		(layer "B.Cu")
		(net 683)
	)
	(segment
		(start 84.5 59.85)
		(end 84.6 59.75)
		(width 0.1)
		(layer "B.Cu")
		(net 683)
	)
	(segment
		(start 208.185 135.885)
		(end 208.07 136)
		(width 0.19)
		(layer "F.Cu")
		(net 684)
	)
	(segment
		(start 107.065532 76.385)
		(end 107.065532 76.115)
		(width 0.19)
		(layer "F.Cu")
		(net 684)
	)
	(segment
		(start 207.88 135.28)
		(end 207.88 135.305)
		(width 0.19)
		(layer "F.Cu")
		(net 684)
	)
	(segment
		(start 107.065532 76.115)
		(end 107.180532 76)
		(width 0.19)
		(layer "F.Cu")
		(net 684)
	)
	(segment
		(start 207.88 135.305)
		(end 208.185 135.61)
		(width 0.19)
		(layer "F.Cu")
		(net 684)
	)
	(segment
		(start 208.185 135.61)
		(end 208.185 135.885)
		(width 0.19)
		(layer "F.Cu")
		(net 684)
	)
	(segment
		(start 107.330532 76.65)
		(end 107.065532 76.385)
		(width 0.19)
		(layer "F.Cu")
		(net 684)
	)
	(via
		(at 107.180532 76)
		(size 0.45)
		(drill 0.1)
		(layers "F.Cu" "B.Cu")
		(net 684)
	)
	(via
		(at 208.07 136)
		(size 0.45)
		(drill 0.1)
		(layers "F.Cu" "B.Cu")
		(net 684)
	)
	(segment
		(start 144.443044 71.5375)
		(end 145.493044 71.5375)
		(width 0.15)
		(layer "In7.Cu")
		(net 684)
	)
	(segment
		(start 112.397919 66.196536)
		(end 112.879887 65.714569)
		(width 0.15)
		(layer "In7.Cu")
		(net 684)
	)
	(segment
		(start 130.243044 62.0475)
		(end 130.760547 62.565003)
		(width 0.15)
		(layer "In7.Cu")
		(net 684)
	)
	(segment
		(start 130.760547 62.565003)
		(end 136.815001 62.565003)
		(width 0.15)
		(layer "In7.Cu")
		(net 684)
	)
	(segment
		(start 195.043044 77.6375)
		(end 197.943044 80.5375)
		(width 0.15)
		(layer "In7.Cu")
		(net 684)
	)
	(segment
		(start 147.3625 73.856956)
		(end 147.943044 74.4375)
		(width 0.15)
		(layer "In7.Cu")
		(net 684)
	)
	(segment
		(start 109.656956 74.4875)
		(end 111.0375 73.106956)
		(width 0.15)
		(layer "In7.Cu")
		(net 684)
	)
	(segment
		(start 145.493044 71.5375)
		(end 147.3625 73.406956)
		(width 0.15)
		(layer "In7.Cu")
		(net 684)
	)
	(segment
		(start 215.7025 119.073635)
		(end 215.5725 119.073635)
		(width 0.15)
		(layer "In7.Cu")
		(net 684)
	)
	(segment
		(start 208.2325 135.8375)
		(end 208.2325 130.573044)
		(width 0.15)
		(layer "In7.Cu")
		(net 684)
	)
	(segment
		(start 187.343044 77.6375)
		(end 195.043044 77.6375)
		(width 0.15)
		(layer "In7.Cu")
		(net 684)
	)
	(segment
		(start 184.143044 74.4375)
		(end 187.343044 77.6375)
		(width 0.15)
		(layer "In7.Cu")
		(net 684)
	)
	(segment
		(start 215.8625 122.943044)
		(end 215.8625 119.233635)
		(width 0.15)
		(layer "In7.Cu")
		(net 684)
	)
	(segment
		(start 208.2325 130.573044)
		(end 215.8625 122.943044)
		(width 0.15)
		(layer "In7.Cu")
		(net 684)
	)
	(segment
		(start 215.4125 118.913635)
		(end 215.4125 118.833635)
		(width 0.15)
		(layer "In7.Cu")
		(net 684)
	)
	(segment
		(start 208.343044 81.7375)
		(end 213.443044 86.8375)
		(width 0.15)
		(layer "In7.Cu")
		(net 684)
	)
	(segment
		(start 215.8625 118.513635)
		(end 215.8625 111.443044)
		(width 0.15)
		(layer "In7.Cu")
		(net 684)
	)
	(segment
		(start 219.0625 108.243044)
		(end 215.8625 111.443044)
		(width 0.15)
		(layer "In7.Cu")
		(net 684)
	)
	(segment
		(start 111.903803 67.045065)
		(end 112.15086 66.798007)
		(width 0.15)
		(layer "In7.Cu")
		(net 684)
	)
	(segment
		(start 128.23136 62.783096)
		(end 128.966956 62.0475)
		(width 0.15)
		(layer "In7.Cu")
		(net 684)
	)
	(segment
		(start 136.815001 62.565003)
		(end 142.7 68.450002)
		(width 0.15)
		(layer "In7.Cu")
		(net 684)
	)
	(segment
		(start 201.893044 81.7375)
		(end 208.343044 81.7375)
		(width 0.15)
		(layer "In7.Cu")
		(net 684)
	)
	(segment
		(start 200.693044 80.5375)
		(end 201.893044 81.7375)
		(width 0.15)
		(layer "In7.Cu")
		(net 684)
	)
	(segment
		(start 142.7 69.794456)
		(end 144.443044 71.5375)
		(width 0.15)
		(layer "In7.Cu")
		(net 684)
	)
	(segment
		(start 142.7 68.450002)
		(end 142.7 69.794456)
		(width 0.15)
		(layer "In7.Cu")
		(net 684)
	)
	(segment
		(start 208.07 136)
		(end 208.2325 135.8375)
		(width 0.15)
		(layer "In7.Cu")
		(net 684)
	)
	(segment
		(start 107.180532 76)
		(end 107.018032 75.8375)
		(width 0.15)
		(layer "In7.Cu")
		(net 684)
	)
	(segment
		(start 213.443044 86.8375)
		(end 215.343044 86.8375)
		(width 0.15)
		(layer "In7.Cu")
		(net 684)
	)
	(segment
		(start 115.81136 62.783096)
		(end 128.23136 62.783096)
		(width 0.15)
		(layer "In7.Cu")
		(net 684)
	)
	(segment
		(start 215.343044 86.8375)
		(end 216.4625 87.956956)
		(width 0.15)
		(layer "In7.Cu")
		(net 684)
	)
	(segment
		(start 112.879887 65.714569)
		(end 115.81136 62.783096)
		(width 0.15)
		(layer "In7.Cu")
		(net 684)
	)
	(segment
		(start 107.018032 74.976424)
		(end 107.506956 74.4875)
		(width 0.15)
		(layer "In7.Cu")
		(net 684)
	)
	(segment
		(start 112.15086 66.443593)
		(end 112.397919 66.196536)
		(width 0.15)
		(layer "In7.Cu")
		(net 684)
	)
	(segment
		(start 216.4625 87.956956)
		(end 216.4625 89.256956)
		(width 0.15)
		(layer "In7.Cu")
		(net 684)
	)
	(segment
		(start 107.506956 74.4875)
		(end 109.656956 74.4875)
		(width 0.15)
		(layer "In7.Cu")
		(net 684)
	)
	(segment
		(start 218.543044 90.4375)
		(end 219.0625 90.956956)
		(width 0.15)
		(layer "In7.Cu")
		(net 684)
	)
	(segment
		(start 215.5725 118.673635)
		(end 215.7025 118.673635)
		(width 0.15)
		(layer "In7.Cu")
		(net 684)
	)
	(segment
		(start 216.4625 89.256956)
		(end 217.643044 90.4375)
		(width 0.15)
		(layer "In7.Cu")
		(net 684)
	)
	(segment
		(start 217.643044 90.4375)
		(end 218.543044 90.4375)
		(width 0.15)
		(layer "In7.Cu")
		(net 684)
	)
	(segment
		(start 219.0625 90.956956)
		(end 219.0625 108.243044)
		(width 0.15)
		(layer "In7.Cu")
		(net 684)
	)
	(segment
		(start 111.0375 67.556956)
		(end 111.549391 67.045065)
		(width 0.15)
		(layer "In7.Cu")
		(net 684)
	)
	(segment
		(start 107.018032 75.8375)
		(end 107.018032 74.976424)
		(width 0.15)
		(layer "In7.Cu")
		(net 684)
	)
	(segment
		(start 147.943044 74.4375)
		(end 184.143044 74.4375)
		(width 0.15)
		(layer "In7.Cu")
		(net 684)
	)
	(segment
		(start 128.966956 62.0475)
		(end 130.243044 62.0475)
		(width 0.15)
		(layer "In7.Cu")
		(net 684)
	)
	(segment
		(start 197.943044 80.5375)
		(end 200.693044 80.5375)
		(width 0.15)
		(layer "In7.Cu")
		(net 684)
	)
	(segment
		(start 147.3625 73.406956)
		(end 147.3625 73.856956)
		(width 0.15)
		(layer "In7.Cu")
		(net 684)
	)
	(segment
		(start 111.0375 73.106956)
		(end 111.0375 67.556956)
		(width 0.15)
		(layer "In7.Cu")
		(net 684)
	)
	(arc
		(start 112.15086 66.798007)
		(mid 112.187561 66.709403)
		(end 112.15086 66.6208)
		(width 0.15)
		(layer "In7.Cu")
		(net 684)
	)
	(arc
		(start 215.8625 119.233635)
		(mid 215.815637 119.120498)
		(end 215.7025 119.073635)
		(width 0.15)
		(layer "In7.Cu")
		(net 684)
	)
	(arc
		(start 111.549391 67.045065)
		(mid 111.637994 67.008364)
		(end 111.726597 67.045065)
		(width 0.15)
		(layer "In7.Cu")
		(net 684)
	)
	(arc
		(start 112.15086 66.6208)
		(mid 112.114159 66.532197)
		(end 112.15086 66.443593)
		(width 0.15)
		(layer "In7.Cu")
		(net 684)
	)
	(arc
		(start 111.726597 67.045065)
		(mid 111.8152 67.081766)
		(end 111.903803 67.045065)
		(width 0.15)
		(layer "In7.Cu")
		(net 684)
	)
	(arc
		(start 215.7025 118.673635)
		(mid 215.815637 118.626772)
		(end 215.8625 118.513635)
		(width 0.15)
		(layer "In7.Cu")
		(net 684)
	)
	(arc
		(start 215.5725 119.073635)
		(mid 215.459363 119.026772)
		(end 215.4125 118.913635)
		(width 0.15)
		(layer "In7.Cu")
		(net 684)
	)
	(arc
		(start 215.4125 118.833635)
		(mid 215.459363 118.720498)
		(end 215.5725 118.673635)
		(width 0.15)
		(layer "In7.Cu")
		(net 684)
	)
	(segment
		(start 155.25 77.95)
		(end 155.25 69.25)
		(width 0.1)
		(layer "F.Cu")
		(net 688)
	)
	(segment
		(start 153.475 80.975)
		(end 153.475 79.725)
		(width 0.1)
		(layer "F.Cu")
		(net 688)
	)
	(segment
		(start 153.475 79.725)
		(end 155.25 77.95)
		(width 0.1)
		(layer "F.Cu")
		(net 688)
	)
	(segment
		(start 153.5 81)
		(end 153.475 80.975)
		(width 0.1)
		(layer "F.Cu")
		(net 688)
	)
	(segment
		(start 140.630532 81.15)
		(end 140.625 81.15)
		(width 0.1)
		(layer "F.Cu")
		(net 688)
	)
	(via
		(at 155.25 69.25)
		(size 0.45)
		(drill 0.1)
		(layers "F.Cu" "B.Cu")
		(net 688)
	)
	(via
		(at 153.5 81)
		(size 0.45)
		(drill 0.1)
		(layers "F.Cu" "B.Cu")
		(net 688)
	)
	(via
		(at 140.625 81.15)
		(size 0.45)
		(drill 0.1)
		(layers "F.Cu" "B.Cu")
		(net 688)
	)
	(segment
		(start 156.67 68.55)
		(end 155.95 68.55)
		(width 0.1)
		(layer "B.Cu")
		(net 688)
	)
	(segment
		(start 155.95 68.55)
		(end 155.25 69.25)
		(width 0.1)
		(layer "B.Cu")
		(net 688)
	)
	(segment
		(start 140.95 81.15)
		(end 141.325 80.775)
		(width 0.1)
		(layer "In2.Cu")
		(net 688)
	)
	(segment
		(start 145.3 80.775)
		(end 146.025 81.5)
		(width 0.1)
		(layer "In2.Cu")
		(net 688)
	)
	(segment
		(start 148.275 81.5)
		(end 148.7 81.075)
		(width 0.1)
		(layer "In2.Cu")
		(net 688)
	)
	(segment
		(start 140.625 81.15)
		(end 140.95 81.15)
		(width 0.1)
		(layer "In2.Cu")
		(net 688)
	)
	(segment
		(start 148.7 81.075)
		(end 153.425 81.075)
		(width 0.1)
		(layer "In2.Cu")
		(net 688)
	)
	(segment
		(start 146.025 81.5)
		(end 148.275 81.5)
		(width 0.1)
		(layer "In2.Cu")
		(net 688)
	)
	(segment
		(start 153.425 81.075)
		(end 153.5 81)
		(width 0.1)
		(layer "In2.Cu")
		(net 688)
	)
	(segment
		(start 141.325 80.775)
		(end 145.3 80.775)
		(width 0.1)
		(layer "In2.Cu")
		(net 688)
	)
	(segment
		(start 121.7 90.85)
		(end 122.75 91.9)
		(width 0.1)
		(layer "F.Cu")
		(net 689)
	)
	(segment
		(start 93.730532 77.780532)
		(end 93.730532 78.15)
		(width 0.1)
		(layer "F.Cu")
		(net 689)
	)
	(segment
		(start 122.75 91.9)
		(end 124.7 91.9)
		(width 0.1)
		(layer "F.Cu")
		(net 689)
	)
	(segment
		(start 153.075 104.61)
		(end 155.475 104.61)
		(width 0.1)
		(layer "F.Cu")
		(net 689)
	)
	(segment
		(start 93.4 77.45)
		(end 93.730532 77.780532)
		(width 0.1)
		(layer "F.Cu")
		(net 689)
	)
	(segment
		(start 148.75 103.35)
		(end 145.8 103.35)
		(width 0.1)
		(layer "F.Cu")
		(net 689)
	)
	(segment
		(start 121.7 90.85)
		(end 121.7 89.65)
		(width 0.1)
		(layer "F.Cu")
		(net 689)
	)
	(segment
		(start 126 90.6)
		(end 133.05 90.6)
		(width 0.1)
		(layer "F.Cu")
		(net 689)
	)
	(segment
		(start 133.05 90.6)
		(end 145.8 103.35)
		(width 0.1)
		(layer "F.Cu")
		(net 689)
	)
	(segment
		(start 92 77.45)
		(end 93.4 77.45)
		(width 0.1)
		(layer "F.Cu")
		(net 689)
	)
	(segment
		(start 124.7 91.9)
		(end 126 90.6)
		(width 0.1)
		(layer "F.Cu")
		(net 689)
	)
	(via
		(at 90.6 86.28)
		(size 0.45)
		(drill 0.1)
		(layers "F.Cu" "B.Cu")
		(net 689)
	)
	(via
		(at 155.475 104.61)
		(size 0.45)
		(drill 0.1)
		(layers "F.Cu" "B.Cu")
		(net 689)
	)
	(via
		(at 92.8 88.75)
		(size 0.45)
		(drill 0.1)
		(layers "F.Cu" "B.Cu")
		(net 689)
	)
	(via
		(at 113.85 91.1)
		(size 0.45)
		(drill 0.1)
		(layers "F.Cu" "B.Cu")
		(net 689)
	)
	(via
		(at 148.75 103.35)
		(size 0.45)
		(drill 0.1)
		(layers "F.Cu" "B.Cu")
		(net 689)
	)
	(via
		(at 92 77.45)
		(size 0.45)
		(drill 0.1)
		(layers "F.Cu" "B.Cu")
		(net 689)
	)
	(via
		(at 121.7 89.65)
		(size 0.45)
		(drill 0.1)
		(layers "F.Cu" "B.Cu")
		(net 689)
	)
	(segment
		(start 115.3 89.65)
		(end 113.85 91.1)
		(width 0.1)
		(layer "B.Cu")
		(net 689)
	)
	(segment
		(start 121.7 89.65)
		(end 115.3 89.65)
		(width 0.1)
		(layer "B.Cu")
		(net 689)
	)
	(segment
		(start 113 89)
		(end 113.85 89.85)
		(width 0.1)
		(layer "In2.Cu")
		(net 689)
	)
	(segment
		(start 102.525 89.475)
		(end 95.425 89.475)
		(width 0.1)
		(layer "In2.Cu")
		(net 689)
	)
	(segment
		(start 94.8 91.8)
		(end 94.4 92.2)
		(width 0.1)
		(layer "In2.Cu")
		(net 689)
	)
	(segment
		(start 102.525 89.475)
		(end 103 89)
		(width 0.1)
		(layer "In2.Cu")
		(net 689)
	)
	(segment
		(start 113.85 89.85)
		(end 113.85 91.1)
		(width 0.1)
		(layer "In2.Cu")
		(net 689)
	)
	(segment
		(start 92.6 91.2)
		(end 93.6 92.2)
		(width 0.1)
		(layer "In2.Cu")
		(net 689)
	)
	(segment
		(start 94.4 92.2)
		(end 93.6 92.2)
		(width 0.1)
		(layer "In2.Cu")
		(net 689)
	)
	(segment
		(start 92.6 88.95)
		(end 92.8 88.75)
		(width 0.1)
		(layer "In2.Cu")
		(net 689)
	)
	(segment
		(start 94.8 90.1)
		(end 94.8 91.8)
		(width 0.1)
		(layer "In2.Cu")
		(net 689)
	)
	(segment
		(start 103 89)
		(end 113 89)
		(width 0.1)
		(layer "In2.Cu")
		(net 689)
	)
	(segment
		(start 95.425 89.475)
		(end 94.8 90.1)
		(width 0.1)
		(layer "In2.Cu")
		(net 689)
	)
	(segment
		(start 92.6 91.2)
		(end 92.6 88.95)
		(width 0.1)
		(layer "In2.Cu")
		(net 689)
	)
	(segment
		(start 91.8375 88.2125)
		(end 92.2625 88.2125)
		(width 0.1)
		(layer "In4.Cu")
		(net 689)
	)
	(segment
		(start 91.8375 88.2125)
		(end 90.6 86.975)
		(width 0.1)
		(layer "In4.Cu")
		(net 689)
	)
	(segment
		(start 90.6 86.975)
		(end 90.6 86.28)
		(width 0.1)
		(layer "In4.Cu")
		(net 689)
	)
	(segment
		(start 92.2625 88.2125)
		(end 92.8 88.75)
		(width 0.1)
		(layer "In4.Cu")
		(net 689)
	)
	(segment
		(start 157.65 108.3)
		(end 157.65 105.55)
		(width 0.1)
		(layer "In5.Cu")
		(net 689)
	)
	(segment
		(start 150.65 110.75)
		(end 155.2 110.75)
		(width 0.1)
		(layer "In5.Cu")
		(net 689)
	)
	(segment
		(start 156.71 104.61)
		(end 155.475 104.61)
		(width 0.1)
		(layer "In5.Cu")
		(net 689)
	)
	(segment
		(start 148.75 103.35)
		(end 148.75 109.7)
		(width 0.1)
		(layer "In5.Cu")
		(net 689)
	)
	(segment
		(start 149.95 110.05)
		(end 150.65 110.75)
		(width 0.1)
		(layer "In5.Cu")
		(net 689)
	)
	(segment
		(start 155.2 110.75)
		(end 157.65 108.3)
		(width 0.1)
		(layer "In5.Cu")
		(net 689)
	)
	(segment
		(start 149.1 110.05)
		(end 149.95 110.05)
		(width 0.1)
		(layer "In5.Cu")
		(net 689)
	)
	(segment
		(start 148.75 109.7)
		(end 149.1 110.05)
		(width 0.1)
		(layer "In5.Cu")
		(net 689)
	)
	(segment
		(start 157.65 105.55)
		(end 156.71 104.61)
		(width 0.1)
		(layer "In5.Cu")
		(net 689)
	)
	(segment
		(start 91.3 79.75)
		(end 92.4 78.65)
		(width 0.1)
		(layer "In7.Cu")
		(net 689)
	)
	(segment
		(start 90.65 86.25)
		(end 90.65 84.9)
		(width 0.1)
		(layer "In7.Cu")
		(net 689)
	)
	(segment
		(start 90.6 86.28)
		(end 90.62 86.28)
		(width 0.1)
		(layer "In7.Cu")
		(net 689)
	)
	(segment
		(start 91.3 84.25)
		(end 91.3 79.75)
		(width 0.1)
		(layer "In7.Cu")
		(net 689)
	)
	(segment
		(start 92.4 77.85)
		(end 92 77.45)
		(width 0.1)
		(layer "In7.Cu")
		(net 689)
	)
	(segment
		(start 90.62 86.28)
		(end 90.65 86.25)
		(width 0.1)
		(layer "In7.Cu")
		(net 689)
	)
	(segment
		(start 92.4 78.65)
		(end 92.4 77.85)
		(width 0.1)
		(layer "In7.Cu")
		(net 689)
	)
	(segment
		(start 90.65 84.9)
		(end 91.3 84.25)
		(width 0.1)
		(layer "In7.Cu")
		(net 689)
	)
	(segment
		(start 138.870859 77.75)
		(end 138.970859 77.75)
		(width 0.1)
		(layer "F.Cu")
		(net 690)
	)
	(segment
		(start 87.35 117.15)
		(end 86.4 116.2)
		(width 0.1)
		(layer "F.Cu")
		(net 690)
	)
	(segment
		(start 75.3 98.2)
		(end 75.3 95)
		(width 0.1)
		(layer "F.Cu")
		(net 690)
	)
	(segment
		(start 78.7 101)
		(end 76.2 98.5)
		(width 0.1)
		(layer "F.Cu")
		(net 690)
	)
	(segment
		(start 134.99033 77.3)
		(end 137.470859 77.3)
		(width 0.1)
		(layer "F.Cu")
		(net 690)
	)
	(segment
		(start 81.712131 110.987869)
		(end 81.712131 110.612131)
		(width 0.1)
		(layer "F.Cu")
		(net 690)
	)
	(segment
		(start 138.670859 77.175)
		(end 138.670859 77.55)
		(width 0.1)
		(layer "F.Cu")
		(net 690)
	)
	(segment
		(start 138.170859 77.55)
		(end 138.170859 77.175)
		(width 0.1)
		(layer "F.Cu")
		(net 690)
	)
	(segment
		(start 137.870859 77.75)
		(end 137.970859 77.75)
		(width 0.1)
		(layer "F.Cu")
		(net 690)
	)
	(segment
		(start 82.9 111.575738)
		(end 82.424264 111.100002)
		(width 0.1)
		(layer "F.Cu")
		(net 690)
	)
	(segment
		(start 133.9 78.5)
		(end 133.9 77.6)
		(width 0.1)
		(layer "F.Cu")
		(net 690)
	)
	(segment
		(start 81 109.9)
		(end 80.6 109.9)
		(width 0.1)
		(layer "F.Cu")
		(net 690)
	)
	(segment
		(start 82.9 116.05)
		(end 82.9 111.575738)
		(width 0.1)
		(layer "F.Cu")
		(net 690)
	)
	(segment
		(start 131.2 78.7)
		(end 133.7 78.7)
		(width 0.1)
		(layer "F.Cu")
		(net 690)
	)
	(segment
		(start 80.4 109.7)
		(end 80.4 101.5)
		(width 0.1)
		(layer "F.Cu")
		(net 690)
	)
	(segment
		(start 139.780532 77.3)
		(end 140.630532 78.15)
		(width 0.1)
		(layer "F.Cu")
		(net 690)
	)
	(segment
		(start 134.49033 77.5)
		(end 134.79033 77.5)
		(width 0.1)
		(layer "F.Cu")
		(net 690)
	)
	(segment
		(start 80.6 109.9)
		(end 80.4 109.7)
		(width 0.1)
		(layer "F.Cu")
		(net 690)
	)
	(segment
		(start 133.9 77.6)
		(end 134.2 77.3)
		(width 0.1)
		(layer "F.Cu")
		(net 690)
	)
	(segment
		(start 139.370859 77.3)
		(end 139.780532 77.3)
		(width 0.1)
		(layer "F.Cu")
		(net 690)
	)
	(segment
		(start 139.170859 77.55)
		(end 139.170859 77.5)
		(width 0.1)
		(layer "F.Cu")
		(net 690)
	)
	(segment
		(start 134.2 77.3)
		(end 134.29033 77.3)
		(width 0.1)
		(layer "F.Cu")
		(net 690)
	)
	(segment
		(start 81.824264 111.100002)
		(end 81.712131 110.987869)
		(width 0.1)
		(layer "F.Cu")
		(net 690)
	)
	(segment
		(start 76.2 98.5)
		(end 75.6 98.5)
		(width 0.1)
		(layer "F.Cu")
		(net 690)
	)
	(segment
		(start 83.05 116.2)
		(end 82.9 116.05)
		(width 0.1)
		(layer "F.Cu")
		(net 690)
	)
	(segment
		(start 75.6 98.5)
		(end 75.3 98.2)
		(width 0.1)
		(layer "F.Cu")
		(net 690)
	)
	(segment
		(start 82.424264 111.100002)
		(end 81.824264 111.100002)
		(width 0.1)
		(layer "F.Cu")
		(net 690)
	)
	(segment
		(start 81.712131 110.612131)
		(end 81 109.9)
		(width 0.1)
		(layer "F.Cu")
		(net 690)
	)
	(segment
		(start 138.295859 77.05)
		(end 138.545859 77.05)
		(width 0.1)
		(layer "F.Cu")
		(net 690)
	)
	(segment
		(start 133.7 78.7)
		(end 133.9 78.5)
		(width 0.1)
		(layer "F.Cu")
		(net 690)
	)
	(segment
		(start 79.9 101)
		(end 78.7 101)
		(width 0.1)
		(layer "F.Cu")
		(net 690)
	)
	(segment
		(start 75.3 95)
		(end 74.5 94.2)
		(width 0.1)
		(layer "F.Cu")
		(net 690)
	)
	(segment
		(start 80.4 101.5)
		(end 79.9 101)
		(width 0.1)
		(layer "F.Cu")
		(net 690)
	)
	(segment
		(start 86.4 116.2)
		(end 83.05 116.2)
		(width 0.1)
		(layer "F.Cu")
		(net 690)
	)
	(segment
		(start 137.670859 77.5)
		(end 137.670859 77.55)
		(width 0.1)
		(layer "F.Cu")
		(net 690)
	)
	(segment
		(start 87.35 117.55)
		(end 87.35 117.15)
		(width 0.1)
		(layer "F.Cu")
		(net 690)
	)
	(via
		(at 131.2 78.7)
		(size 0.45)
		(drill 0.1)
		(layers "F.Cu" "B.Cu")
		(net 690)
	)
	(via
		(at 115.1 106.9)
		(size 0.45)
		(drill 0.1)
		(layers "F.Cu" "B.Cu")
		(net 690)
	)
	(via
		(at 87.35 117.55)
		(size 0.45)
		(drill 0.1)
		(layers "F.Cu" "B.Cu")
		(net 690)
	)
	(via
		(at 74.5 94.2)
		(size 0.45)
		(drill 0.1)
		(layers "F.Cu" "B.Cu")
		(net 690)
	)
	(via
		(at 122.9 90.6)
		(size 0.45)
		(drill 0.1)
		(layers "F.Cu" "B.Cu")
		(net 690)
	)
	(arc
		(start 137.970859 77.75)
		(mid 138.11228 77.691421)
		(end 138.170859 77.55)
		(width 0.1)
		(layer "F.Cu")
		(net 690)
	)
	(arc
		(start 134.39033 77.4)
		(mid 134.419619 77.470711)
		(end 134.49033 77.5)
		(width 0.1)
		(layer "F.Cu")
		(net 690)
	)
	(arc
		(start 138.545859 77.05)
		(mid 138.634247 77.086612)
		(end 138.670859 77.175)
		(width 0.1)
		(layer "F.Cu")
		(net 690)
	)
	(arc
		(start 138.970859 77.75)
		(mid 139.11228 77.691421)
		(end 139.170859 77.55)
		(width 0.1)
		(layer "F.Cu")
		(net 690)
	)
	(arc
		(start 134.79033 77.5)
		(mid 134.861041 77.470711)
		(end 134.89033 77.4)
		(width 0.1)
		(layer "F.Cu")
		(net 690)
	)
	(arc
		(start 134.89033 77.4)
		(mid 134.919619 77.329289)
		(end 134.99033 77.3)
		(width 0.1)
		(layer "F.Cu")
		(net 690)
	)
	(arc
		(start 139.170859 77.5)
		(mid 139.229438 77.358579)
		(end 139.370859 77.3)
		(width 0.1)
		(layer "F.Cu")
		(net 690)
	)
	(arc
		(start 138.670859 77.55)
		(mid 138.729438 77.691421)
		(end 138.870859 77.75)
		(width 0.1)
		(layer "F.Cu")
		(net 690)
	)
	(arc
		(start 137.470859 77.3)
		(mid 137.61228 77.358579)
		(end 137.670859 77.5)
		(width 0.1)
		(layer "F.Cu")
		(net 690)
	)
	(arc
		(start 138.170859 77.175)
		(mid 138.207471 77.086612)
		(end 138.295859 77.05)
		(width 0.1)
		(layer "F.Cu")
		(net 690)
	)
	(arc
		(start 134.29033 77.3)
		(mid 134.361041 77.329289)
		(end 134.39033 77.4)
		(width 0.1)
		(layer "F.Cu")
		(net 690)
	)
	(arc
		(start 137.670859 77.55)
		(mid 137.729438 77.691421)
		(end 137.870859 77.75)
		(width 0.1)
		(layer "F.Cu")
		(net 690)
	)
	(segment
		(start 95.05 117.55)
		(end 100.45 112.15)
		(width 0.1)
		(layer "In5.Cu")
		(net 690)
	)
	(segment
		(start 103.75 107.75)
		(end 104.5 107.75)
		(width 0.1)
		(layer "In5.Cu")
		(net 690)
	)
	(segment
		(start 87.35 117.55)
		(end 95.05 117.55)
		(width 0.1)
		(layer "In5.Cu")
		(net 690)
	)
	(segment
		(start 104.5 107.75)
		(end 105.35 106.9)
		(width 0.1)
		(layer "In5.Cu")
		(net 690)
	)
	(segment
		(start 100.9 110.6)
		(end 103.75 107.75)
		(width 0.1)
		(layer "In5.Cu")
		(net 690)
	)
	(segment
		(start 130.730331 78.7)
		(end 130.430331 78.4)
		(width 0.1)
		(layer "In5.Cu")
		(net 690)
	)
	(segment
		(start 130 78.4)
		(end 129.9 78.5)
		(width 0.1)
		(layer "In5.Cu")
		(net 690)
	)
	(segment
		(start 100.55 111.25)
		(end 100.9 110.9)
		(width 0.1)
		(layer "In5.Cu")
		(net 690)
	)
	(segment
		(start 131.2 78.7)
		(end 130.730331 78.7)
		(width 0.1)
		(layer "In5.Cu")
		(net 690)
	)
	(segment
		(start 100.45 112.15)
		(end 100.45 112)
		(width 0.1)
		(layer "In5.Cu")
		(net 690)
	)
	(segment
		(start 100.9 110.9)
		(end 100.9 110.6)
		(width 0.1)
		(layer "In5.Cu")
		(net 690)
	)
	(segment
		(start 129.9 79.2)
		(end 130.1 79.4)
		(width 0.1)
		(layer "In5.Cu")
		(net 690)
	)
	(segment
		(start 125.8 90.6)
		(end 122.9 90.6)
		(width 0.1)
		(layer "In5.Cu")
		(net 690)
	)
	(segment
		(start 130.1 86.3)
		(end 125.8 90.6)
		(width 0.1)
		(layer "In5.Cu")
		(net 690)
	)
	(segment
		(start 105.35 106.9)
		(end 115.1 106.9)
		(width 0.1)
		(layer "In5.Cu")
		(net 690)
	)
	(segment
		(start 100.55 111.9)
		(end 100.55 111.25)
		(width 0.1)
		(layer "In5.Cu")
		(net 690)
	)
	(segment
		(start 130.1 79.4)
		(end 130.1 86.3)
		(width 0.1)
		(layer "In5.Cu")
		(net 690)
	)
	(segment
		(start 100.45 112)
		(end 100.55 111.9)
		(width 0.1)
		(layer "In5.Cu")
		(net 690)
	)
	(segment
		(start 130.430331 78.4)
		(end 130 78.4)
		(width 0.1)
		(layer "In5.Cu")
		(net 690)
	)
	(segment
		(start 129.9 78.5)
		(end 129.9 79.2)
		(width 0.1)
		(layer "In5.Cu")
		(net 690)
	)
	(segment
		(start 120.3 99.581435)
		(end 119.7 99.581435)
		(width 0.1)
		(layer "In7.Cu")
		(net 690)
	)
	(segment
		(start 115.1 106.9)
		(end 120.5 101.5)
		(width 0.1)
		(layer "In7.Cu")
		(net 690)
	)
	(segment
		(start 120.3 98.581435)
		(end 119.7 98.581435)
		(width 0.1)
		(layer "In7.Cu")
		(net 690)
	)
	(segment
		(start 120.5 101.281435)
		(end 120.5 101.5)
		(width 0.1)
		(layer "In7.Cu")
		(net 690)
	)
	(segment
		(start 120.5 92)
		(end 120.5 98.381435)
		(width 0.1)
		(layer "In7.Cu")
		(net 690)
	)
	(segment
		(start 119.5 100.781435)
		(end 119.5 100.881435)
		(width 0.1)
		(layer "In7.Cu")
		(net 690)
	)
	(segment
		(start 120.3 100.581435)
		(end 119.7 100.581435)
		(width 0.1)
		(layer "In7.Cu")
		(net 690)
	)
	(segment
		(start 122.9 90.6)
		(end 121.9 90.6)
		(width 0.1)
		(layer "In7.Cu")
		(net 690)
	)
	(segment
		(start 121.9 90.6)
		(end 120.5 92)
		(width 0.1)
		(layer "In7.Cu")
		(net 690)
	)
	(segment
		(start 119.5 99.781435)
		(end 119.5 99.881435)
		(width 0.1)
		(layer "In7.Cu")
		(net 690)
	)
	(segment
		(start 119.7 99.081435)
		(end 120.3 99.081435)
		(width 0.1)
		(layer "In7.Cu")
		(net 690)
	)
	(segment
		(start 119.5 98.781435)
		(end 119.5 98.881435)
		(width 0.1)
		(layer "In7.Cu")
		(net 690)
	)
	(segment
		(start 120.5 100.281435)
		(end 120.5 100.381435)
		(width 0.1)
		(layer "In7.Cu")
		(net 690)
	)
	(segment
		(start 119.7 101.081435)
		(end 120.3 101.081435)
		(width 0.1)
		(layer "In7.Cu")
		(net 690)
	)
	(segment
		(start 119.7 100.081435)
		(end 120.3 100.081435)
		(width 0.1)
		(layer "In7.Cu")
		(net 690)
	)
	(segment
		(start 120.5 99.281435)
		(end 120.5 99.381435)
		(width 0.1)
		(layer "In7.Cu")
		(net 690)
	)
	(arc
		(start 120.5 100.381435)
		(mid 120.441421 100.522856)
		(end 120.3 100.581435)
		(width 0.1)
		(layer "In7.Cu")
		(net 690)
	)
	(arc
		(start 120.3 100.081435)
		(mid 120.441421 100.140014)
		(end 120.5 100.281435)
		(width 0.1)
		(layer "In7.Cu")
		(net 690)
	)
	(arc
		(start 119.7 98.581435)
		(mid 119.558579 98.640014)
		(end 119.5 98.781435)
		(width 0.1)
		(layer "In7.Cu")
		(net 690)
	)
	(arc
		(start 120.5 98.381435)
		(mid 120.441421 98.522856)
		(end 120.3 98.581435)
		(width 0.1)
		(layer "In7.Cu")
		(net 690)
	)
	(arc
		(start 119.7 99.581435)
		(mid 119.558579 99.640014)
		(end 119.5 99.781435)
		(width 0.1)
		(layer "In7.Cu")
		(net 690)
	)
	(arc
		(start 120.3 99.081435)
		(mid 120.441421 99.140014)
		(end 120.5 99.281435)
		(width 0.1)
		(layer "In7.Cu")
		(net 690)
	)
	(arc
		(start 119.5 100.881435)
		(mid 119.558579 101.022856)
		(end 119.7 101.081435)
		(width 0.1)
		(layer "In7.Cu")
		(net 690)
	)
	(arc
		(start 119.5 98.881435)
		(mid 119.558579 99.022856)
		(end 119.7 99.081435)
		(width 0.1)
		(layer "In7.Cu")
		(net 690)
	)
	(arc
		(start 119.7 100.581435)
		(mid 119.558579 100.640014)
		(end 119.5 100.781435)
		(width 0.1)
		(layer "In7.Cu")
		(net 690)
	)
	(arc
		(start 120.5 99.381435)
		(mid 120.441421 99.522856)
		(end 120.3 99.581435)
		(width 0.1)
		(layer "In7.Cu")
		(net 690)
	)
	(arc
		(start 120.3 101.081435)
		(mid 120.441421 101.140014)
		(end 120.5 101.281435)
		(width 0.1)
		(layer "In7.Cu")
		(net 690)
	)
	(arc
		(start 119.5 99.881435)
		(mid 119.558579 100.022856)
		(end 119.7 100.081435)
		(width 0.1)
		(layer "In7.Cu")
		(net 690)
	)
	(segment
		(start 83.70663 98.445)
		(end 82.575532 98.445)
		(width 0.19)
		(layer "F.Cu")
		(net 691)
	)
	(segment
		(start 82.935 100.37663)
		(end 83.22663 100.085)
		(width 0.19)
		(layer "F.Cu")
		(net 691)
	)
	(segment
		(start 90.28 100.515)
		(end 88.22337 100.515)
		(width 0.19)
		(layer "F.Cu")
		(net 691)
	)
	(segment
		(start 84.235 99.62663)
		(end 84.235 98.97337)
		(width 0.19)
		(layer "F.Cu")
		(net 691)
	)
	(segment
		(start 86.47337 102.265)
		(end 83.22663 102.265)
		(width 0.19)
		(layer "F.Cu")
		(net 691)
	)
	(segment
		(start 82.575532 98.445)
		(end 82.125532 97.995)
		(width 0.19)
		(layer "F.Cu")
		(net 691)
	)
	(segment
		(start 82.935 101.97337)
		(end 82.935 100.37663)
		(width 0.19)
		(layer "F.Cu")
		(net 691)
	)
	(segment
		(start 90.62 100.2)
		(end 90.595 100.2)
		(width 0.19)
		(layer "F.Cu")
		(net 691)
	)
	(segment
		(start 83.22663 102.265)
		(end 82.935 101.97337)
		(width 0.19)
		(layer "F.Cu")
		(net 691)
	)
	(segment
		(start 88.22337 100.515)
		(end 86.47337 102.265)
		(width 0.19)
		(layer "F.Cu")
		(net 691)
	)
	(segment
		(start 90.595 100.2)
		(end 90.28 100.515)
		(width 0.19)
		(layer "F.Cu")
		(net 691)
	)
	(segment
		(start 83.22663 100.085)
		(end 83.77663 100.085)
		(width 0.19)
		(layer "F.Cu")
		(net 691)
	)
	(segment
		(start 84.235 98.97337)
		(end 83.70663 98.445)
		(width 0.19)
		(layer "F.Cu")
		(net 691)
	)
	(segment
		(start 83.77663 100.085)
		(end 84.235 99.62663)
		(width 0.19)
		(layer "F.Cu")
		(net 691)
	)
	(via
		(at 82.125532 97.995)
		(size 0.45)
		(drill 0.1)
		(layers "F.Cu" "B.Cu")
		(net 691)
	)
	(segment
		(start 127.65 86.5)
		(end 128.85 86.5)
		(width 0.1)
		(layer "F.Cu")
		(net 692)
	)
	(segment
		(start 133.365686 89.2)
		(end 145.965686 101.8)
		(width 0.1)
		(layer "F.Cu")
		(net 692)
	)
	(segment
		(start 131.55 89.2)
		(end 133.365686 89.2)
		(width 0.1)
		(layer "F.Cu")
		(net 692)
	)
	(segment
		(start 123 83.6)
		(end 123 85.2)
		(width 0.1)
		(layer "F.Cu")
		(net 692)
	)
	(segment
		(start 122.430532 83.030532)
		(end 123 83.6)
		(width 0.1)
		(layer "F.Cu")
		(net 692)
	)
	(segment
		(start 128.85 86.5)
		(end 131.55 89.2)
		(width 0.1)
		(layer "F.Cu")
		(net 692)
	)
	(segment
		(start 123 85.2)
		(end 122.9 85.3)
		(width 0.1)
		(layer "F.Cu")
		(net 692)
	)
	(segment
		(start 145.965686 101.8)
		(end 155.6 101.8)
		(width 0.1)
		(layer "F.Cu")
		(net 692)
	)
	(segment
		(start 155.6 101.8)
		(end 156.2 102.4)
		(width 0.1)
		(layer "F.Cu")
		(net 692)
	)
	(segment
		(start 122.9 86)
		(end 124.15 87.25)
		(width 0.1)
		(layer "F.Cu")
		(net 692)
	)
	(segment
		(start 155.59 103.81)
		(end 153.075 103.81)
		(width 0.1)
		(layer "F.Cu")
		(net 692)
	)
	(segment
		(start 126.9 87.25)
		(end 127.65 86.5)
		(width 0.1)
		(layer "F.Cu")
		(net 692)
	)
	(segment
		(start 122.9 85.3)
		(end 122.9 86)
		(width 0.1)
		(layer "F.Cu")
		(net 692)
	)
	(segment
		(start 122.430532 82.65)
		(end 122.430532 83.030532)
		(width 0.1)
		(layer "F.Cu")
		(net 692)
	)
	(segment
		(start 156.2 102.4)
		(end 156.2 103.2)
		(width 0.1)
		(layer "F.Cu")
		(net 692)
	)
	(segment
		(start 156.2 103.2)
		(end 155.59 103.81)
		(width 0.1)
		(layer "F.Cu")
		(net 692)
	)
	(segment
		(start 124.15 87.25)
		(end 126.9 87.25)
		(width 0.1)
		(layer "F.Cu")
		(net 692)
	)
	(segment
		(start 96.45 80.1)
		(end 96.9 79.65)
		(width 0.1)
		(layer "F.Cu")
		(net 694)
	)
	(segment
		(start 95.330532 79.65)
		(end 95.330532 79.680532)
		(width 0.1)
		(layer "F.Cu")
		(net 694)
	)
	(segment
		(start 95.75 80.1)
		(end 96.45 80.1)
		(width 0.1)
		(layer "F.Cu")
		(net 694)
	)
	(segment
		(start 95.330532 79.680532)
		(end 95.75 80.1)
		(width 0.1)
		(layer "F.Cu")
		(net 694)
	)
	(via
		(at 96.9 79.65)
		(size 0.45)
		(drill 0.1)
		(layers "F.Cu" "B.Cu")
		(net 694)
	)
	(via
		(at 80.65 97.3)
		(size 0.45)
		(drill 0.1)
		(layers "F.Cu" "B.Cu")
		(net 694)
	)
	(segment
		(start 80.855532 97.094468)
		(end 80.65 97.3)
		(width 0.1)
		(layer "B.Cu")
		(net 694)
	)
	(segment
		(start 80.855532 96.725)
		(end 80.855532 97.094468)
		(width 0.1)
		(layer "B.Cu")
		(net 694)
	)
	(segment
		(start 86.85 98.15)
		(end 86.25 98.75)
		(width 0.1)
		(layer "In5.Cu")
		(net 694)
	)
	(segment
		(start 85.2 94.2)
		(end 86.85 95.85)
		(width 0.1)
		(layer "In5.Cu")
		(net 694)
	)
	(segment
		(start 96.9 79.65)
		(end 96.9 80.7)
		(width 0.1)
		(layer "In5.Cu")
		(net 694)
	)
	(segment
		(start 87.424264 92)
		(end 86 92)
		(width 0.1)
		(layer "In5.Cu")
		(net 694)
	)
	(segment
		(start 93.287868 86.512132)
		(end 92.912132 86.512132)
		(width 0.1)
		(layer "In5.Cu")
		(net 694)
	)
	(segment
		(start 82.25 97.5)
		(end 82.05 97.3)
		(width 0.1)
		(layer "In5.Cu")
		(net 694)
	)
	(segment
		(start 86 92)
		(end 85.2 92.8)
		(width 0.1)
		(layer "In5.Cu")
		(net 694)
	)
	(segment
		(start 82.05 97.3)
		(end 80.65 97.3)
		(width 0.1)
		(layer "In5.Cu")
		(net 694)
	)
	(segment
		(start 94.412132 85.012132)
		(end 94.412132 83.687868)
		(width 0.1)
		(layer "In5.Cu")
		(net 694)
	)
	(segment
		(start 94.9 82.7)
		(end 94.9 83.2)
		(width 0.1)
		(layer "In5.Cu")
		(net 694)
	)
	(segment
		(start 94.412132 83.687868)
		(end 94.9 83.2)
		(width 0.1)
		(layer "In5.Cu")
		(net 694)
	)
	(segment
		(start 86.25 98.75)
		(end 85.05 98.75)
		(width 0.1)
		(layer "In5.Cu")
		(net 694)
	)
	(segment
		(start 85.2 92.8)
		(end 85.2 94.2)
		(width 0.1)
		(layer "In5.Cu")
		(net 694)
	)
	(segment
		(start 94.262132 85.162132)
		(end 94.262132 85.537868)
		(width 0.1)
		(layer "In5.Cu")
		(net 694)
	)
	(segment
		(start 94.412132 85.012132)
		(end 94.262132 85.162132)
		(width 0.1)
		(layer "In5.Cu")
		(net 694)
	)
	(segment
		(start 96.9 80.7)
		(end 94.9 82.7)
		(width 0.1)
		(layer "In5.Cu")
		(net 694)
	)
	(segment
		(start 86.85 95.85)
		(end 86.85 98.15)
		(width 0.1)
		(layer "In5.Cu")
		(net 694)
	)
	(segment
		(start 92.912132 86.512132)
		(end 87.424264 92)
		(width 0.1)
		(layer "In5.Cu")
		(net 694)
	)
	(segment
		(start 94.262132 85.537868)
		(end 93.287868 86.512132)
		(width 0.1)
		(layer "In5.Cu")
		(net 694)
	)
	(segment
		(start 83.8 97.5)
		(end 82.25 97.5)
		(width 0.1)
		(layer "In5.Cu")
		(net 694)
	)
	(segment
		(start 85.05 98.75)
		(end 83.8 97.5)
		(width 0.1)
		(layer "In5.Cu")
		(net 694)
	)
	(segment
		(start 222.675 101.785)
		(end 222.8 101.91)
		(width 0.17)
		(layer "F.Cu")
		(net 698)
	)
	(segment
		(start 221.754 101.86)
		(end 222.166501 101.86)
		(width 0.17)
		(layer "F.Cu")
		(net 698)
	)
	(segment
		(start 221.754 101.86)
		(end 220.982 101.86)
		(width 0.17)
		(layer "F.Cu")
		(net 698)
	)
	(segment
		(start 232.930532 99.860532)
		(end 232.92 99.85)
		(width 0.17)
		(layer "F.Cu")
		(net 698)
	)
	(segment
		(start 220.982 101.86)
		(end 220.569499 101.86)
		(width 0.17)
		(layer "F.Cu")
		(net 698)
	)
	(segment
		(start 222.241501 101.785)
		(end 222.675 101.785)
		(width 0.17)
		(layer "F.Cu")
		(net 698)
	)
	(segment
		(start 222.166501 101.86)
		(end 222.241501 101.785)
		(width 0.17)
		(layer "F.Cu")
		(net 698)
	)
	(segment
		(start 220.494499 101.785)
		(end 220.225 101.785)
		(width 0.17)
		(layer "F.Cu")
		(net 698)
	)
	(segment
		(start 220.569499 101.86)
		(end 220.494499 101.785)
		(width 0.17)
		(layer "F.Cu")
		(net 698)
	)
	(segment
		(start 97.330532 78.15)
		(end 97.055532 77.875)
		(width 0.17)
		(layer "F.Cu")
		(net 698)
	)
	(segment
		(start 232.930532 101.0725)
		(end 232.930532 99.860532)
		(width 0.17)
		(layer "F.Cu")
		(net 698)
	)
	(segment
		(start 97.055532 77.875)
		(end 97.055532 77.625)
		(width 0.17)
		(layer "F.Cu")
		(net 698)
	)
	(segment
		(start 232.430532 104.489468)
		(end 232.42 104.5)
		(width 0.17)
		(layer "F.Cu")
		(net 698)
	)
	(segment
		(start 220.225 101.785)
		(end 220.1 101.91)
		(width 0.17)
		(layer "F.Cu")
		(net 698)
	)
	(segment
		(start 97.055532 77.625)
		(end 97.180532 77.5)
		(width 0.17)
		(layer "F.Cu")
		(net 698)
	)
	(segment
		(start 232.430532 103.3475)
		(end 232.430532 104.489468)
		(width 0.17)
		(layer "F.Cu")
		(net 698)
	)
	(via
		(at 99.9125 69.35)
		(size 0.45)
		(drill 0.1)
		(layers "F.Cu" "B.Cu")
		(net 698)
	)
	(via
		(at 232.92 99.85)
		(size 0.45)
		(drill 0.1)
		(layers "F.Cu" "B.Cu")
		(net 698)
	)
	(via
		(at 232.42 104.5)
		(size 0.45)
		(drill 0.1)
		(layers "F.Cu" "B.Cu")
		(net 698)
	)
	(via
		(at 97.180532 77.5)
		(size 0.45)
		(drill 0.1)
		(layers "F.Cu" "B.Cu")
		(net 698)
	)
	(via
		(at 222.8 101.91)
		(size 0.45)
		(drill 0.1)
		(layers "F.Cu" "B.Cu")
		(net 698)
	)
	(via
		(at 220.1 101.91)
		(size 0.45)
		(drill 0.1)
		(layers "F.Cu" "B.Cu")
		(net 698)
	)
	(segment
		(start 100.735 71.645694)
		(end 100.735 71.555694)
		(width 0.17)
		(layer "B.Cu")
		(net 698)
	)
	(segment
		(start 100.735 72.545694)
		(end 100.735 72.455694)
		(width 0.17)
		(layer "B.Cu")
		(net 698)
	)
	(segment
		(start 100.025 69.4625)
		(end 99.9125 69.35)
		(width 0.17)
		(layer "B.Cu")
		(net 698)
	)
	(segment
		(start 100.47054 71.825694)
		(end 100.555 71.825694)
		(width 0.17)
		(layer "B.Cu")
		(net 698)
	)
	(segment
		(start 100.735 70.532488)
		(end 100.025 69.822488)
		(width 0.17)
		(layer "B.Cu")
		(net 698)
	)
	(segment
		(start 100.470525 72.725694)
		(end 100.555 72.725694)
		(width 0.17)
		(layer "B.Cu")
		(net 698)
	)
	(segment
		(start 97.180532 77.5)
		(end 97.055532 77.625)
		(width 0.17)
		(layer "B.Cu")
		(net 698)
	)
	(segment
		(start 97.522488 78.675)
		(end 98.377512 78.675)
		(width 0.17)
		(layer "B.Cu")
		(net 698)
	)
	(segment
		(start 100.29054 72.095694)
		(end 100.29054 72.005694)
		(width 0.17)
		(layer "B.Cu")
		(net 698)
	)
	(segment
		(start 98.675 78.377512)
		(end 98.675 77.027512)
		(width 0.17)
		(layer "B.Cu")
		(net 698)
	)
	(segment
		(start 97.055532 77.625)
		(end 97.055532 78.208044)
		(width 0.17)
		(layer "B.Cu")
		(net 698)
	)
	(segment
		(start 98.377512 78.675)
		(end 98.675 78.377512)
		(width 0.17)
		(layer "B.Cu")
		(net 698)
	)
	(segment
		(start 98.675 77.027512)
		(end 100.735 74.967512)
		(width 0.17)
		(layer "B.Cu")
		(net 698)
	)
	(segment
		(start 100.735 71.220633)
		(end 100.735 70.532488)
		(width 0.17)
		(layer "B.Cu")
		(net 698)
	)
	(segment
		(start 100.025 69.822488)
		(end 100.025 69.4625)
		(width 0.17)
		(layer "B.Cu")
		(net 698)
	)
	(segment
		(start 100.290525 72.995694)
		(end 100.290525 72.905694)
		(width 0.17)
		(layer "B.Cu")
		(net 698)
	)
	(segment
		(start 100.735 71.555694)
		(end 100.735 71.220633)
		(width 0.17)
		(layer "B.Cu")
		(net 698)
	)
	(segment
		(start 100.555 73.175694)
		(end 100.470525 73.175694)
		(width 0.17)
		(layer "B.Cu")
		(net 698)
	)
	(segment
		(start 100.735 74.967512)
		(end 100.735 73.355694)
		(width 0.17)
		(layer "B.Cu")
		(net 698)
	)
	(segment
		(start 97.055532 78.208044)
		(end 97.522488 78.675)
		(width 0.17)
		(layer "B.Cu")
		(net 698)
	)
	(segment
		(start 100.555 72.275694)
		(end 100.47054 72.275694)
		(width 0.17)
		(layer "B.Cu")
		(net 698)
	)
	(arc
		(start 100.47054 72.275694)
		(mid 100.343261 72.222973)
		(end 100.29054 72.095694)
		(width 0.17)
		(layer "B.Cu")
		(net 698)
	)
	(arc
		(start 100.735 72.455694)
		(mid 100.682279 72.328415)
		(end 100.555 72.275694)
		(width 0.17)
		(layer "B.Cu")
		(net 698)
	)
	(arc
		(start 100.555 72.725694)
		(mid 100.682279 72.672973)
		(end 100.735 72.545694)
		(width 0.17)
		(layer "B.Cu")
		(net 698)
	)
	(arc
		(start 100.29054 72.005694)
		(mid 100.343261 71.878415)
		(end 100.47054 71.825694)
		(width 0.17)
		(layer "B.Cu")
		(net 698)
	)
	(arc
		(start 100.735 73.355694)
		(mid 100.682279 73.228415)
		(end 100.555 73.175694)
		(width 0.17)
		(layer "B.Cu")
		(net 698)
	)
	(arc
		(start 100.470525 73.175694)
		(mid 100.343246 73.122973)
		(end 100.290525 72.995694)
		(width 0.17)
		(layer "B.Cu")
		(net 698)
	)
	(arc
		(start 100.290525 72.905694)
		(mid 100.343246 72.778415)
		(end 100.470525 72.725694)
		(width 0.17)
		(layer "B.Cu")
		(net 698)
	)
	(arc
		(start 100.555 71.825694)
		(mid 100.682279 71.772973)
		(end 100.735 71.645694)
		(width 0.17)
		(layer "B.Cu")
		(net 698)
	)
	(segment
		(start 232.92 101.85)
		(end 232.92 99.85)
		(width 0.125)
		(layer "In2.Cu")
		(net 698)
	)
	(segment
		(start 232.42 104.5)
		(end 232.42 102.35)
		(width 0.125)
		(layer "In2.Cu")
		(net 698)
	)
	(segment
		(start 232.42 102.35)
		(end 232.92 101.85)
		(width 0.125)
		(layer "In2.Cu")
		(net 698)
	)
	(segment
		(start 220.287499 101.722501)
		(end 220.586599 101.722501)
		(width 0.125)
		(layer "In7.Cu")
		(net 698)
	)
	(segment
		(start 221.1625 101.1466)
		(end 221.1625 85.6966)
		(width 0.125)
		(layer "In7.Cu")
		(net 698)
	)
	(segment
		(start 232.3734 103.6125)
		(end 226.3534 103.6125)
		(width 0.125)
		(layer "In7.Cu")
		(net 698)
	)
	(segment
		(start 216.4125 80.3534)
		(end 216.4125 77.7534)
		(width 0.125)
		(layer "In7.Cu")
		(net 698)
	)
	(segment
		(start 222.987499 101.722501)
		(end 222.8 101.91)
		(width 0.125)
		(layer "In7.Cu")
		(net 698)
	)
	(segment
		(start 189.7466 67.7875)
		(end 149.8466 67.7875)
		(width 0.125)
		(layer "In7.Cu")
		(net 698)
	)
	(segment
		(start 193.0466 71.0875)
		(end 189.7466 67.7875)
		(width 0.125)
		(layer "In7.Cu")
		(net 698)
	)
	(segment
		(start 218.4466 81.0875)
		(end 217.1466 81.0875)
		(width 0.125)
		(layer "In7.Cu")
		(net 698)
	)
	(segment
		(start 209.7466 71.0875)
		(end 193.0466 71.0875)
		(width 0.125)
		(layer "In7.Cu")
		(net 698)
	)
	(segment
		(start 226.3534 103.6125)
		(end 224.9534 102.2125)
		(width 0.125)
		(layer "In7.Cu")
		(net 698)
	)
	(segment
		(start 100.087499 67.083401)
		(end 100.087499 69.175001)
		(width 0.125)
		(layer "In7.Cu")
		(net 698)
	)
	(segment
		(start 149.8466 67.7875)
		(end 148.5125 66.4534)
		(width 0.125)
		(layer "In7.Cu")
		(net 698)
	)
	(segment
		(start 232.42 104.5)
		(end 232.582499 104.337501)
		(width 0.125)
		(layer "In7.Cu")
		(net 698)
	)
	(segment
		(start 110.0834 57.0875)
		(end 100.087499 67.083401)
		(width 0.125)
		(layer "In7.Cu")
		(net 698)
	)
	(segment
		(start 217.1466 81.0875)
		(end 216.4125 80.3534)
		(width 0.125)
		(layer "In7.Cu")
		(net 698)
	)
	(segment
		(start 232.582499 103.821599)
		(end 232.3734 103.6125)
		(width 0.125)
		(layer "In7.Cu")
		(net 698)
	)
	(segment
		(start 220.586599 101.722501)
		(end 221.1625 101.1466)
		(width 0.125)
		(layer "In7.Cu")
		(net 698)
	)
	(segment
		(start 220.1 101.91)
		(end 220.287499 101.722501)
		(width 0.125)
		(layer "In7.Cu")
		(net 698)
	)
	(segment
		(start 219.6466 82.2875)
		(end 218.4466 81.0875)
		(width 0.125)
		(layer "In7.Cu")
		(net 698)
	)
	(segment
		(start 232.582499 104.337501)
		(end 232.582499 103.821599)
		(width 0.125)
		(layer "In7.Cu")
		(net 698)
	)
	(segment
		(start 216.4125 77.7534)
		(end 209.7466 71.0875)
		(width 0.125)
		(layer "In7.Cu")
		(net 698)
	)
	(segment
		(start 140.4466 57.0875)
		(end 110.0834 57.0875)
		(width 0.125)
		(layer "In7.Cu")
		(net 698)
	)
	(segment
		(start 221.1625 85.6966)
		(end 222.4125 84.4466)
		(width 0.125)
		(layer "In7.Cu")
		(net 698)
	)
	(segment
		(start 222.4125 84.4466)
		(end 222.4125 83.0534)
		(width 0.125)
		(layer "In7.Cu")
		(net 698)
	)
	(segment
		(start 221.6466 82.2875)
		(end 219.6466 82.2875)
		(width 0.125)
		(layer "In7.Cu")
		(net 698)
	)
	(segment
		(start 100.087499 69.175001)
		(end 99.9125 69.35)
		(width 0.125)
		(layer "In7.Cu")
		(net 698)
	)
	(segment
		(start 223.463401 101.722501)
		(end 222.987499 101.722501)
		(width 0.125)
		(layer "In7.Cu")
		(net 698)
	)
	(segment
		(start 148.5125 66.4534)
		(end 148.5125 65.1534)
		(width 0.125)
		(layer "In7.Cu")
		(net 698)
	)
	(segment
		(start 223.9534 102.2125)
		(end 223.463401 101.722501)
		(width 0.125)
		(layer "In7.Cu")
		(net 698)
	)
	(segment
		(start 224.9534 102.2125)
		(end 223.9534 102.2125)
		(width 0.125)
		(layer "In7.Cu")
		(net 698)
	)
	(segment
		(start 148.5125 65.1534)
		(end 140.4466 57.0875)
		(width 0.125)
		(layer "In7.Cu")
		(net 698)
	)
	(segment
		(start 222.4125 83.0534)
		(end 221.6466 82.2875)
		(width 0.125)
		(layer "In7.Cu")
		(net 698)
	)
	(segment
		(start 107.065532 78.825)
		(end 107.180532 78.71)
		(width 0.19)
		(layer "F.Cu")
		(net 699)
	)
	(segment
		(start 107.330532 79.65)
		(end 107.065532 79.385)
		(width 0.19)
		(layer "F.Cu")
		(net 699)
	)
	(segment
		(start 107.065532 79.385)
		(end 107.065532 78.825)
		(width 0.19)
		(layer "F.Cu")
		(net 699)
	)
	(via
		(at 107.180532 78.71)
		(size 0.45)
		(drill 0.1)
		(layers "F.Cu" "B.Cu")
		(net 699)
	)
	(via
		(at 87.847739 106.072739)
		(size 0.45)
		(drill 0.1)
		(layers "F.Cu" "B.Cu")
		(net 699)
	)
	(segment
		(start 87.663891 106.072739)
		(end 87.847739 106.072739)
		(width 0.19)
		(layer "B.Cu")
		(net 699)
	)
	(segment
		(start 86.385532 106.435)
		(end 87.30163 106.435)
		(width 0.19)
		(layer "B.Cu")
		(net 699)
	)
	(segment
		(start 85.935532 106.885)
		(end 86.385532 106.435)
		(width 0.19)
		(layer "B.Cu")
		(net 699)
	)
	(segment
		(start 87.30163 106.435)
		(end 87.663891 106.072739)
		(width 0.19)
		(layer "B.Cu")
		(net 699)
	)
	(segment
		(start 97.206956 83.4875)
		(end 98.531956 83.4875)
		(width 0.15)
		(layer "In5.Cu")
		(net 699)
	)
	(segment
		(start 98.531956 83.4875)
		(end 100.2875 81.731956)
		(width 0.15)
		(layer "In5.Cu")
		(net 699)
	)
	(segment
		(start 99.8375 79.331956)
		(end 100.231956 78.9375)
		(width 0.15)
		(layer "In5.Cu")
		(net 699)
	)
	(segment
		(start 106.8 79.2)
		(end 107.180532 78.819468)
		(width 0.15)
		(layer "In5.Cu")
		(net 699)
	)
	(segment
		(start 87.847739 105.821716)
		(end 89.5375 104.131955)
		(width 0.15)
		(layer "In5.Cu")
		(net 699)
	)
	(segment
		(start 107.180532 78.819468)
		(end 107.180532 78.71)
		(width 0.15)
		(layer "In5.Cu")
		(net 699)
	)
	(segment
		(start 99.8375 80.068044)
		(end 99.8375 79.331956)
		(width 0.15)
		(layer "In5.Cu")
		(net 699)
	)
	(segment
		(start 87.847739 106.072739)
		(end 87.847739 105.821716)
		(width 0.15)
		(layer "In5.Cu")
		(net 699)
	)
	(segment
		(start 100.2875 81.731956)
		(end 100.2875 80.518044)
		(width 0.15)
		(layer "In5.Cu")
		(net 699)
	)
	(segment
		(start 89.5375 91.156956)
		(end 97.206956 83.4875)
		(width 0.15)
		(layer "In5.Cu")
		(net 699)
	)
	(segment
		(start 106.2 79.2)
		(end 106.8 79.2)
		(width 0.15)
		(layer "In5.Cu")
		(net 699)
	)
	(segment
		(start 100.2875 80.518044)
		(end 99.8375 80.068044)
		(width 0.15)
		(layer "In5.Cu")
		(net 699)
	)
	(segment
		(start 89.5375 104.131955)
		(end 89.5375 91.156956)
		(width 0.15)
		(layer "In5.Cu")
		(net 699)
	)
	(segment
		(start 100.231956 78.9375)
		(end 105.9375 78.9375)
		(width 0.15)
		(layer "In5.Cu")
		(net 699)
	)
	(segment
		(start 105.9375 78.9375)
		(end 106.2 79.2)
		(width 0.15)
		(layer "In5.Cu")
		(net 699)
	)
	(via
		(at 126.030532 70.65)
		(size 0.45)
		(drill 0.1)
		(layers "F.Cu" "B.Cu")
		(net 700)
	)
	(segment
		(start 126.030532 70.169468)
		(end 126.8 69.4)
		(width 0.1)
		(layer "B.Cu")
		(net 700)
	)
	(segment
		(start 126.030532 70.65)
		(end 126.030532 70.169468)
		(width 0.1)
		(layer "B.Cu")
		(net 700)
	)
	(segment
		(start 146.61 88.1975)
		(end 144.7875 86.375)
		(width 0.1)
		(layer "F.Cu")
		(net 701)
	)
	(segment
		(start 143.575 85.9)
		(end 143.575 85.125)
		(width 0.1)
		(layer "F.Cu")
		(net 701)
	)
	(segment
		(start 143.575 85.125)
		(end 143.330532 84.880532)
		(width 0.1)
		(layer "F.Cu")
		(net 701)
	)
	(segment
		(start 144.7875 86.375)
		(end 144.05 86.375)
		(width 0.1)
		(layer "F.Cu")
		(net 701)
	)
	(segment
		(start 146.61 88.225)
		(end 146.61 88.1975)
		(width 0.1)
		(layer "F.Cu")
		(net 701)
	)
	(segment
		(start 143.330532 84.880532)
		(end 143.330532 84.15)
		(width 0.1)
		(layer "F.Cu")
		(net 701)
	)
	(segment
		(start 144.05 86.375)
		(end 143.575 85.9)
		(width 0.1)
		(layer "F.Cu")
		(net 701)
	)
	(via
		(at 74.505532 97.995)
		(size 0.45)
		(drill 0.1)
		(layers "F.Cu" "B.Cu")
		(net 701)
	)
	(via
		(at 146.61 88.225)
		(size 0.45)
		(drill 0.1)
		(layers "F.Cu" "B.Cu")
		(net 701)
	)
	(segment
		(start 117.797596 131.852)
		(end 117.797596 131.148685)
		(width 0.1)
		(layer "In5.Cu")
		(net 701)
	)
	(segment
		(start 146.61 88.225)
		(end 146.625 88.225)
		(width 0.1)
		(layer "In5.Cu")
		(net 701)
	)
	(segment
		(start 147.7 97.116999)
		(end 147.7 97.216999)
		(width 0.1)
		(layer "In5.Cu")
		(net 701)
	)
	(segment
		(start 146.4 105.2)
		(end 146.4 106.9)
		(width 0.1)
		(layer "In5.Cu")
		(net 701)
	)
	(segment
		(start 119.869596 131.00071)
		(end 119.795596 131.00071)
		(width 0.1)
		(layer "In5.Cu")
		(net 701)
	)
	(segment
		(start 146.8 101.616999)
		(end 146.8 101.716999)
		(width 0.1)
		(layer "In5.Cu")
		(net 701)
	)
	(segment
		(start 147.7 101.116999)
		(end 147.7 101.216999)
		(width 0.1)
		(layer "In5.Cu")
		(net 701)
	)
	(segment
		(start 147 94.916999)
		(end 147.5 94.916999)
		(width 0.1)
		(layer "In5.Cu")
		(net 701)
	)
	(segment
		(start 116.169596 131.000685)
		(end 116.095596 131.000685)
		(width 0.1)
		(layer "In5.Cu")
		(net 701)
	)
	(segment
		(start 146.8 100.616999)
		(end 146.8 100.716999)
		(width 0.1)
		(layer "In5.Cu")
		(net 701)
	)
	(segment
		(start 114.245596 132)
		(end 114.22857 132)
		(width 0.1)
		(layer "In5.Cu")
		(net 701)
	)
	(segment
		(start 115.947596 131.148685)
		(end 115.947596 131.852)
		(width 0.1)
		(layer "In5.Cu")
		(net 701)
	)
	(segment
		(start 147.7 103.116999)
		(end 147.7 103.9)
		(width 0.1)
		(layer "In5.Cu")
		(net 701)
	)
	(segment
		(start 73.9375 109.4375)
		(end 74.7 110.2)
		(width 0.1)
		(layer "In5.Cu")
		(net 701)
	)
	(segment
		(start 147.5 101.416999)
		(end 147 101.416999)
		(width 0.1)
		(layer "In5.Cu")
		(net 701)
	)
	(segment
		(start 72.7625 98.4375)
		(end 72.7625 107.3875)
		(width 0.1)
		(layer "In5.Cu")
		(net 701)
	)
	(segment
		(start 96.6 134)
		(end 105.7 134)
		(width 0.1)
		(layer "In5.Cu")
		(net 701)
	)
	(segment
		(start 147.7 94.116999)
		(end 147.7 94.216999)
		(width 0.1)
		(layer "In5.Cu")
		(net 701)
	)
	(segment
		(start 147 100.916999)
		(end 147.5 100.916999)
		(width 0.1)
		(layer "In5.Cu")
		(net 701)
	)
	(segment
		(start 114.319596 132)
		(end 114.245596 132)
		(width 0.1)
		(layer "In5.Cu")
		(net 701)
	)
	(segment
		(start 146.4 106.9)
		(end 147 107.5)
		(width 0.1)
		(layer "In5.Cu")
		(net 701)
	)
	(segment
		(start 73.205 97.995)
		(end 72.7625 98.4375)
		(width 0.1)
		(layer "In5.Cu")
		(net 701)
	)
	(segment
		(start 114.467596 131.148685)
		(end 114.467596 131.852)
		(width 0.1)
		(layer "In5.Cu")
		(net 701)
	)
	(segment
		(start 92.2 138.4)
		(end 96.6 134)
		(width 0.1)
		(layer "In5.Cu")
		(net 701)
	)
	(segment
		(start 147.7 92.966999)
		(end 147.7 93.216999)
		(width 0.1)
		(layer "In5.Cu")
		(net 701)
	)
	(segment
		(start 147.7 99.116999)
		(end 147.7 99.216999)
		(width 0.1)
		(layer "In5.Cu")
		(net 701)
	)
	(segment
		(start 105.7 134)
		(end 107 132.7)
		(width 0.1)
		(layer "In5.Cu")
		(net 701)
	)
	(segment
		(start 147.5 97.416999)
		(end 147 97.416999)
		(width 0.1)
		(layer "In5.Cu")
		(net 701)
	)
	(segment
		(start 147.7 95.116999)
		(end 147.7 95.216999)
		(width 0.1)
		(layer "In5.Cu")
		(net 701)
	)
	(segment
		(start 115.059596 132)
		(end 114.985596 132)
		(width 0.1)
		(layer "In5.Cu")
		(net 701)
	)
	(segment
		(start 120.239596 132)
		(end 120.165596 132)
		(width 0.1)
		(layer "In5.Cu")
		(net 701)
	)
	(segment
		(start 80.8 129.15)
		(end 80.8 135.3)
		(width 0.1)
		(layer "In5.Cu")
		(net 701)
	)
	(segment
		(start 146.8 102.616999)
		(end 146.8 102.716999)
		(width 0.1)
		(layer "In5.Cu")
		(net 701)
	)
	(segment
		(start 107 132.7)
		(end 109 132.7)
		(width 0.1)
		(layer "In5.Cu")
		(net 701)
	)
	(segment
		(start 147 95.916999)
		(end 147.5 95.916999)
		(width 0.1)
		(layer "In5.Cu")
		(net 701)
	)
	(segment
		(start 80.375 128.725)
		(end 80.8 129.15)
		(width 0.1)
		(layer "In5.Cu")
		(net 701)
	)
	(segment
		(start 147 97.916999)
		(end 147.5 97.916999)
		(width 0.1)
		(layer "In5.Cu")
		(net 701)
	)
	(segment
		(start 80.375 125.575738)
		(end 80.375 128.725)
		(width 0.1)
		(layer "In5.Cu")
		(net 701)
	)
	(segment
		(start 83.9 138.4)
		(end 92.2 138.4)
		(width 0.1)
		(layer "In5.Cu")
		(net 701)
	)
	(segment
		(start 109.7 132)
		(end 114.22857 132)
		(width 0.1)
		(layer "In5.Cu")
		(net 701)
	)
	(segment
		(start 147 102.916999)
		(end 147.5 102.916999)
		(width 0.1)
		(layer "In5.Cu")
		(net 701)
	)
	(segment
		(start 147 107.5)
		(end 147 118.4)
		(width 0.1)
		(layer "In5.Cu")
		(net 701)
	)
	(segment
		(start 120.757596 131.852)
		(end 120.757596 131.148685)
		(width 0.1)
		(layer "In5.Cu")
		(net 701)
	)
	(segment
		(start 118.759596 132)
		(end 118.685596 132)
		(width 0.1)
		(layer "In5.Cu")
		(net 701)
	)
	(segment
		(start 72.7625 107.3875)
		(end 73.9375 108.5625)
		(width 0.1)
		(layer "In5.Cu")
		(net 701)
	)
	(segment
		(start 147.5 102.416999)
		(end 147 102.416999)
		(width 0.1)
		(layer "In5.Cu")
		(net 701)
	)
	(segment
		(start 74.7 110.2)
		(end 74.7 110.6)
		(width 0.1)
		(layer "In5.Cu")
		(net 701)
	)
	(segment
		(start 147.7 89.3)
		(end 147.7 91.216999)
		(width 0.1)
		(layer "In5.Cu")
		(net 701)
	)
	(segment
		(start 118.907596 131.148685)
		(end 118.907596 131.852)
		(width 0.1)
		(layer "In5.Cu")
		(net 701)
	)
	(segment
		(start 121.675738 132)
		(end 120.905596 132)
		(width 0.1)
		(layer "In5.Cu")
		(net 701)
	)
	(segment
		(start 109 132.7)
		(end 109.7 132)
		(width 0.1)
		(layer "In5.Cu")
		(net 701)
	)
	(segment
		(start 147.45 92.466999)
		(end 147.45 92.716999)
		(width 0.1)
		(layer "In5.Cu")
		(net 701)
	)
	(segment
		(start 124.575738 129.1)
		(end 121.675738 132)
		(width 0.1)
		(layer "In5.Cu")
		(net 701)
	)
	(segment
		(start 146.4 105.2)
		(end 147.7 103.9)
		(width 0.1)
		(layer "In5.Cu")
		(net 701)
	)
	(segment
		(start 146.8 95.616999)
		(end 146.8 95.716999)
		(width 0.1)
		(layer "In5.Cu")
		(net 701)
	)
	(segment
		(start 147 96.916999)
		(end 147.5 96.916999)
		(width 0.1)
		(layer "In5.Cu")
		(net 701)
	)
	(segment
		(start 147.5 100.416999)
		(end 147 100.416999)
		(width 0.1)
		(layer "In5.Cu")
		(net 701)
	)
	(segment
		(start 146.9 91.916999)
		(end 147.5 91.916999)
		(width 0.1)
		(layer "In5.Cu")
		(net 701)
	)
	(segment
		(start 115.429596 131.00071)
		(end 115.355596 131.00071)
		(width 0.1)
		(layer "In5.Cu")
		(net 701)
	)
	(segment
		(start 73.9375 108.5625)
		(end 73.9375 109.4375)
		(width 0.1)
		(layer "In5.Cu")
		(net 701)
	)
	(segment
		(start 120.387596 131.148685)
		(end 120.387596 131.852)
		(width 0.1)
		(layer "In5.Cu")
		(net 701)
	)
	(segment
		(start 120.017596 131.852)
		(end 120.017596 131.14871)
		(width 0.1)
		(layer "In5.Cu")
		(net 701)
	)
	(segment
		(start 147 101.916999)
		(end 147.5 101.916999)
		(width 0.1)
		(layer "In5.Cu")
		(net 701)
	)
	(segment
		(start 147.5 95.416999)
		(end 147 95.416999)
		(width 0.1)
		(layer "In5.Cu")
		(net 701)
	)
	(segment
		(start 117.649596 131.000685)
		(end 117.575596 131.000685)
		(width 0.1)
		(layer "In5.Cu")
		(net 701)
	)
	(segment
		(start 146.625 88.225)
		(end 147.7 89.3)
		(width 0.1)
		(layer "In5.Cu")
		(net 701)
	)
	(segment
		(start 146.8 97.616999)
		(end 146.8 97.716999)
		(width 0.1)
		(layer "In5.Cu")
		(net 701)
	)
	(segment
		(start 79.899264 125.100002)
		(end 80.375 125.575738)
		(width 0.1)
		(layer "In5.Cu")
		(net 701)
	)
	(segment
		(start 146.8 98.616999)
		(end 146.8 98.716999)
		(width 0.1)
		(layer "In5.Cu")
		(net 701)
	)
	(segment
		(start 74.7 110.6)
		(end 74 111.3)
		(width 0.1)
		(layer "In5.Cu")
		(net 701)
	)
	(segment
		(start 114.837596 131.852)
		(end 114.837596 131.148685)
		(width 0.1)
		(layer "In5.Cu")
		(net 701)
	)
	(segment
		(start 146.8 94.616999)
		(end 146.8 94.716999)
		(width 0.1)
		(layer "In5.Cu")
		(net 701)
	)
	(segment
		(start 147.5 93.416999)
		(end 147.15 93.416999)
		(width 0.1)
		(layer "In5.Cu")
		(net 701)
	)
	(segment
		(start 118.019596 132)
		(end 117.945596 132)
		(width 0.1)
		(layer "In5.Cu")
		(net 701)
	)
	(segment
		(start 115.799596 132)
		(end 115.725596 132)
		(width 0.1)
		(layer "In5.Cu")
		(net 701)
	)
	(segment
		(start 146.8 99.616999)
		(end 146.8 99.716999)
		(width 0.1)
		(layer "In5.Cu")
		(net 701)
	)
	(segment
		(start 114.689596 131.000685)
		(end 114.615596 131.000685)
		(width 0.1)
		(layer "In5.Cu")
		(net 701)
	)
	(segment
		(start 120.609596 131.000685)
		(end 120.535596 131.000685)
		(width 0.1)
		(layer "In5.Cu")
		(net 701)
	)
	(segment
		(start 146.8 96.616999)
		(end 146.8 96.716999)
		(width 0.1)
		(layer "In5.Cu")
		(net 701)
	)
	(segment
		(start 116.687596 131.14871)
		(end 116.687596 131.852)
		(width 0.1)
		(layer "In5.Cu")
		(net 701)
	)
	(segment
		(start 147 98.916999)
		(end 147.5 98.916999)
		(width 0.1)
		(layer "In5.Cu")
		(net 701)
	)
	(segment
		(start 115.207596 131.14871)
		(end 115.207596 131.852)
		(width 0.1)
		(layer "In5.Cu")
		(net 701)
	)
	(segment
		(start 74 124.175)
		(end 74.925002 125.100002)
		(width 0.1)
		(layer "In5.Cu")
		(net 701)
	)
	(segment
		(start 74 111.3)
		(end 74 124.175)
		(width 0.1)
		(layer "In5.Cu")
		(net 701)
	)
	(segment
		(start 115.577596 131.852)
		(end 115.577596 131.14871)
		(width 0.1)
		(layer "In5.Cu")
		(net 701)
	)
	(segment
		(start 147.7 102.116999)
		(end 147.7 102.216999)
		(width 0.1)
		(layer "In5.Cu")
		(net 701)
	)
	(segment
		(start 119.129596 131.000685)
		(end 119.055596 131.000685)
		(width 0.1)
		(layer "In5.Cu")
		(net 701)
	)
	(segment
		(start 119.277596 131.852)
		(end 119.277596 131.148685)
		(width 0.1)
		(layer "In5.Cu")
		(net 701)
	)
	(segment
		(start 117.427596 131.148685)
		(end 117.427596 131.852)
		(width 0.1)
		(layer "In5.Cu")
		(net 701)
	)
	(segment
		(start 74.925002 125.100002)
		(end 79.899264 125.100002)
		(width 0.1)
		(layer "In5.Cu")
		(net 701)
	)
	(segment
		(start 147.7 92.116999)
		(end 147.7 92.216999)
		(width 0.1)
		(layer "In5.Cu")
		(net 701)
	)
	(segment
		(start 147.5 94.416999)
		(end 147 94.416999)
		(width 0.1)
		(layer "In5.Cu")
		(net 701)
	)
	(segment
		(start 118.537596 131.852)
		(end 118.537596 131.14871)
		(width 0.1)
		(layer "In5.Cu")
		(net 701)
	)
	(segment
		(start 147.7 100.116999)
		(end 147.7 100.216999)
		(width 0.1)
		(layer "In5.Cu")
		(net 701)
	)
	(segment
		(start 147 118.4)
		(end 136.3 129.1)
		(width 0.1)
		(layer "In5.Cu")
		(net 701)
	)
	(segment
		(start 116.909596 131.00071)
		(end 116.835596 131.00071)
		(width 0.1)
		(layer "In5.Cu")
		(net 701)
	)
	(segment
		(start 146.95 93.616999)
		(end 146.95 93.716999)
		(width 0.1)
		(layer "In5.Cu")
		(net 701)
	)
	(segment
		(start 117.057596 131.852)
		(end 117.057596 131.14871)
		(width 0.1)
		(layer "In5.Cu")
		(net 701)
	)
	(segment
		(start 147.5 96.416999)
		(end 147 96.416999)
		(width 0.1)
		(layer "In5.Cu")
		(net 701)
	)
	(segment
		(start 119.647596 131.14871)
		(end 119.647596 131.852)
		(width 0.1)
		(layer "In5.Cu")
		(net 701)
	)
	(segment
		(start 116.317596 131.852)
		(end 116.317596 131.148685)
		(width 0.1)
		(layer "In5.Cu")
		(net 701)
	)
	(segment
		(start 118.389596 131.00071)
		(end 118.315596 131.00071)
		(width 0.1)
		(layer "In5.Cu")
		(net 701)
	)
	(segment
		(start 119.499596 132)
		(end 119.425596 132)
		(width 0.1)
		(layer "In5.Cu")
		(net 701)
	)
	(segment
		(start 147.5 98.416999)
		(end 147 98.416999)
		(width 0.1)
		(layer "In5.Cu")
		(net 701)
	)
	(segment
		(start 146.7 91.616999)
		(end 146.7 91.716999)
		(width 0.1)
		(layer "In5.Cu")
		(net 701)
	)
	(segment
		(start 74.505532 97.995)
		(end 73.205 97.995)
		(width 0.1)
		(layer "In5.Cu")
		(net 701)
	)
	(segment
		(start 116.539596 132)
		(end 116.465596 132)
		(width 0.1)
		(layer "In5.Cu")
		(net 701)
	)
	(segment
		(start 147.15 93.916999)
		(end 147.5 93.916999)
		(width 0.1)
		(layer "In5.Cu")
		(net 701)
	)
	(segment
		(start 118.167596 131.14871)
		(end 118.167596 131.852)
		(width 0.1)
		(layer "In5.Cu")
		(net 701)
	)
	(segment
		(start 147 99.916999)
		(end 147.5 99.916999)
		(width 0.1)
		(layer "In5.Cu")
		(net 701)
	)
	(segment
		(start 80.8 135.3)
		(end 83.9 138.4)
		(width 0.1)
		(layer "In5.Cu")
		(net 701)
	)
	(segment
		(start 147.5 91.416999)
		(end 146.9 91.416999)
		(width 0.1)
		(layer "In5.Cu")
		(net 701)
	)
	(segment
		(start 117.279596 132)
		(end 117.205596 132)
		(width 0.1)
		(layer "In5.Cu")
		(net 701)
	)
	(segment
		(start 147.7 96.116999)
		(end 147.7 96.216999)
		(width 0.1)
		(layer "In5.Cu")
		(net 701)
	)
	(segment
		(start 147.7 98.116999)
		(end 147.7 98.216999)
		(width 0.1)
		(layer "In5.Cu")
		(net 701)
	)
	(segment
		(start 147.5 99.416999)
		(end 147 99.416999)
		(width 0.1)
		(layer "In5.Cu")
		(net 701)
	)
	(segment
		(start 136.3 129.1)
		(end 124.575738 129.1)
		(width 0.1)
		(layer "In5.Cu")
		(net 701)
	)
	(arc
		(start 115.577596 131.14871)
		(mid 115.534248 131.044058)
		(end 115.429596 131.00071)
		(width 0.1)
		(layer "In5.Cu")
		(net 701)
	)
	(arc
		(start 147.7 94.216999)
		(mid 147.641421 94.35842)
		(end 147.5 94.416999)
		(width 0.1)
		(layer "In5.Cu")
		(net 701)
	)
	(arc
		(start 118.167596 131.852)
		(mid 118.124248 131.956652)
		(end 118.019596 132)
		(width 0.1)
		(layer "In5.Cu")
		(net 701)
	)
	(arc
		(start 117.205596 132)
		(mid 117.100944 131.956652)
		(end 117.057596 131.852)
		(width 0.1)
		(layer "In5.Cu")
		(net 701)
	)
	(arc
		(start 147.5 96.916999)
		(mid 147.641421 96.975578)
		(end 147.7 97.116999)
		(width 0.1)
		(layer "In5.Cu")
		(net 701)
	)
	(arc
		(start 147.5 101.916999)
		(mid 147.641421 101.975578)
		(end 147.7 102.116999)
		(width 0.1)
		(layer "In5.Cu")
		(net 701)
	)
	(arc
		(start 147.7 98.216999)
		(mid 147.641421 98.35842)
		(end 147.5 98.416999)
		(width 0.1)
		(layer "In5.Cu")
		(net 701)
	)
	(arc
		(start 147 94.416999)
		(mid 146.858579 94.475578)
		(end 146.8 94.616999)
		(width 0.1)
		(layer "In5.Cu")
		(net 701)
	)
	(arc
		(start 146.95 93.716999)
		(mid 147.008579 93.85842)
		(end 147.15 93.916999)
		(width 0.1)
		(layer "In5.Cu")
		(net 701)
	)
	(arc
		(start 147 98.416999)
		(mid 146.858579 98.475578)
		(end 146.8 98.616999)
		(width 0.1)
		(layer "In5.Cu")
		(net 701)
	)
	(arc
		(start 147.7 96.216999)
		(mid 147.641421 96.35842)
		(end 147.5 96.416999)
		(width 0.1)
		(layer "In5.Cu")
		(net 701)
	)
	(arc
		(start 114.985596 132)
		(mid 114.880944 131.956652)
		(end 114.837596 131.852)
		(width 0.1)
		(layer "In5.Cu")
		(net 701)
	)
	(arc
		(start 147.45 92.716999)
		(mid 147.486612 92.805387)
		(end 147.575 92.841999)
		(width 0.1)
		(layer "In5.Cu")
		(net 701)
	)
	(arc
		(start 120.905596 132)
		(mid 120.800944 131.956652)
		(end 120.757596 131.852)
		(width 0.1)
		(layer "In5.Cu")
		(net 701)
	)
	(arc
		(start 146.8 97.716999)
		(mid 146.858579 97.85842)
		(end 147 97.916999)
		(width 0.1)
		(layer "In5.Cu")
		(net 701)
	)
	(arc
		(start 147.5 91.916999)
		(mid 147.641421 91.975578)
		(end 147.7 92.116999)
		(width 0.1)
		(layer "In5.Cu")
		(net 701)
	)
	(arc
		(start 118.315596 131.00071)
		(mid 118.210944 131.044058)
		(end 118.167596 131.14871)
		(width 0.1)
		(layer "In5.Cu")
		(net 701)
	)
	(arc
		(start 118.685596 132)
		(mid 118.580944 131.956652)
		(end 118.537596 131.852)
		(width 0.1)
		(layer "In5.Cu")
		(net 701)
	)
	(arc
		(start 114.615596 131.000685)
		(mid 114.510944 131.044033)
		(end 114.467596 131.148685)
		(width 0.1)
		(layer "In5.Cu")
		(net 701)
	)
	(arc
		(start 147.5 93.916999)
		(mid 147.641421 93.975578)
		(end 147.7 94.116999)
		(width 0.1)
		(layer "In5.Cu")
		(net 701)
	)
	(arc
		(start 147.7 101.216999)
		(mid 147.641421 101.35842)
		(end 147.5 101.416999)
		(width 0.1)
		(layer "In5.Cu")
		(net 701)
	)
	(arc
		(start 147.5 95.916999)
		(mid 147.641421 95.975578)
		(end 147.7 96.116999)
		(width 0.1)
		(layer "In5.Cu")
		(net 701)
	)
	(arc
		(start 117.575596 131.000685)
		(mid 117.470944 131.044033)
		(end 117.427596 131.148685)
		(width 0.1)
		(layer "In5.Cu")
		(net 701)
	)
	(arc
		(start 147.15 93.416999)
		(mid 147.008579 93.475578)
		(end 146.95 93.616999)
		(width 0.1)
		(layer "In5.Cu")
		(net 701)
	)
	(arc
		(start 118.907596 131.852)
		(mid 118.864248 131.956652)
		(end 118.759596 132)
		(width 0.1)
		(layer "In5.Cu")
		(net 701)
	)
	(arc
		(start 147.7 100.216999)
		(mid 147.641421 100.35842)
		(end 147.5 100.416999)
		(width 0.1)
		(layer "In5.Cu")
		(net 701)
	)
	(arc
		(start 115.725596 132)
		(mid 115.620944 131.956652)
		(end 115.577596 131.852)
		(width 0.1)
		(layer "In5.Cu")
		(net 701)
	)
	(arc
		(start 120.757596 131.148685)
		(mid 120.714248 131.044033)
		(end 120.609596 131.000685)
		(width 0.1)
		(layer "In5.Cu")
		(net 701)
	)
	(arc
		(start 147.7 91.216999)
		(mid 147.641421 91.35842)
		(end 147.5 91.416999)
		(width 0.1)
		(layer "In5.Cu")
		(net 701)
	)
	(arc
		(start 119.277596 131.148685)
		(mid 119.234248 131.044033)
		(end 119.129596 131.000685)
		(width 0.1)
		(layer "In5.Cu")
		(net 701)
	)
	(arc
		(start 116.095596 131.000685)
		(mid 115.990944 131.044033)
		(end 115.947596 131.148685)
		(width 0.1)
		(layer "In5.Cu")
		(net 701)
	)
	(arc
		(start 147 96.416999)
		(mid 146.858579 96.475578)
		(end 146.8 96.616999)
		(width 0.1)
		(layer "In5.Cu")
		(net 701)
	)
	(arc
		(start 146.8 94.716999)
		(mid 146.858579 94.85842)
		(end 147 94.916999)
		(width 0.1)
		(layer "In5.Cu")
		(net 701)
	)
	(arc
		(start 119.647596 131.852)
		(mid 119.604248 131.956652)
		(end 119.499596 132)
		(width 0.1)
		(layer "In5.Cu")
		(net 701)
	)
	(arc
		(start 115.355596 131.00071)
		(mid 115.250944 131.044058)
		(end 115.207596 131.14871)
		(width 0.1)
		(layer "In5.Cu")
		(net 701)
	)
	(arc
		(start 147.7 102.216999)
		(mid 147.641421 102.35842)
		(end 147.5 102.416999)
		(width 0.1)
		(layer "In5.Cu")
		(net 701)
	)
	(arc
		(start 147 102.416999)
		(mid 146.858579 102.475578)
		(end 146.8 102.616999)
		(width 0.1)
		(layer "In5.Cu")
		(net 701)
	)
	(arc
		(start 147.5 99.916999)
		(mid 147.641421 99.975578)
		(end 147.7 100.116999)
		(width 0.1)
		(layer "In5.Cu")
		(net 701)
	)
	(arc
		(start 146.8 96.716999)
		(mid 146.858579 96.85842)
		(end 147 96.916999)
		(width 0.1)
		(layer "In5.Cu")
		(net 701)
	)
	(arc
		(start 147.7 92.216999)
		(mid 147.663388 92.305387)
		(end 147.575 92.341999)
		(width 0.1)
		(layer "In5.Cu")
		(net 701)
	)
	(arc
		(start 147.5 97.916999)
		(mid 147.641421 97.975578)
		(end 147.7 98.116999)
		(width 0.1)
		(layer "In5.Cu")
		(net 701)
	)
	(arc
		(start 147.5 100.916999)
		(mid 147.641421 100.975578)
		(end 147.7 101.116999)
		(width 0.1)
		(layer "In5.Cu")
		(net 701)
	)
	(arc
		(start 119.055596 131.000685)
		(mid 118.950944 131.044033)
		(end 118.907596 131.148685)
		(width 0.1)
		(layer "In5.Cu")
		(net 701)
	)
	(arc
		(start 117.797596 131.148685)
		(mid 117.754248 131.044033)
		(end 117.649596 131.000685)
		(width 0.1)
		(layer "In5.Cu")
		(net 701)
	)
	(arc
		(start 114.467596 131.852)
		(mid 114.424248 131.956652)
		(end 114.319596 132)
		(width 0.1)
		(layer "In5.Cu")
		(net 701)
	)
	(arc
		(start 119.795596 131.00071)
		(mid 119.690944 131.044058)
		(end 119.647596 131.14871)
		(width 0.1)
		(layer "In5.Cu")
		(net 701)
	)
	(arc
		(start 147 99.416999)
		(mid 146.858579 99.475578)
		(end 146.8 99.616999)
		(width 0.1)
		(layer "In5.Cu")
		(net 701)
	)
	(arc
		(start 147.575 92.841999)
		(mid 147.663388 92.878611)
		(end 147.7 92.966999)
		(width 0.1)
		(layer "In5.Cu")
		(net 701)
	)
	(arc
		(start 146.9 91.416999)
		(mid 146.758579 91.475578)
		(end 146.7 91.616999)
		(width 0.1)
		(layer "In5.Cu")
		(net 701)
	)
	(arc
		(start 146.7 91.716999)
		(mid 146.758579 91.85842)
		(end 146.9 91.916999)
		(width 0.1)
		(layer "In5.Cu")
		(net 701)
	)
	(arc
		(start 116.317596 131.148685)
		(mid 116.274248 131.044033)
		(end 116.169596 131.000685)
		(width 0.1)
		(layer "In5.Cu")
		(net 701)
	)
	(arc
		(start 118.537596 131.14871)
		(mid 118.494248 131.044058)
		(end 118.389596 131.00071)
		(width 0.1)
		(layer "In5.Cu")
		(net 701)
	)
	(arc
		(start 147.5 94.916999)
		(mid 147.641421 94.975578)
		(end 147.7 95.116999)
		(width 0.1)
		(layer "In5.Cu")
		(net 701)
	)
	(arc
		(start 120.387596 131.852)
		(mid 120.344248 131.956652)
		(end 120.239596 132)
		(width 0.1)
		(layer "In5.Cu")
		(net 701)
	)
	(arc
		(start 147.7 97.216999)
		(mid 147.641421 97.35842)
		(end 147.5 97.416999)
		(width 0.1)
		(layer "In5.Cu")
		(net 701)
	)
	(arc
		(start 117.057596 131.14871)
		(mid 117.014248 131.044058)
		(end 116.909596 131.00071)
		(width 0.1)
		(layer "In5.Cu")
		(net 701)
	)
	(arc
		(start 147.575 92.341999)
		(mid 147.486612 92.378611)
		(end 147.45 92.466999)
		(width 0.1)
		(layer "In5.Cu")
		(net 701)
	)
	(arc
		(start 146.8 95.716999)
		(mid 146.858579 95.85842)
		(end 147 95.916999)
		(width 0.1)
		(layer "In5.Cu")
		(net 701)
	)
	(arc
		(start 146.8 101.716999)
		(mid 146.858579 101.85842)
		(end 147 101.916999)
		(width 0.1)
		(layer "In5.Cu")
		(net 701)
	)
	(arc
		(start 146.8 100.716999)
		(mid 146.858579 100.85842)
		(end 147 100.916999)
		(width 0.1)
		(layer "In5.Cu")
		(net 701)
	)
	(arc
		(start 114.837596 131.148685)
		(mid 114.794248 131.044033)
		(end 114.689596 131.000685)
		(width 0.1)
		(layer "In5.Cu")
		(net 701)
	)
	(arc
		(start 147 100.416999)
		(mid 146.858579 100.475578)
		(end 146.8 100.616999)
		(width 0.1)
		(layer "In5.Cu")
		(net 701)
	)
	(arc
		(start 116.687596 131.852)
		(mid 116.644248 131.956652)
		(end 116.539596 132)
		(width 0.1)
		(layer "In5.Cu")
		(net 701)
	)
	(arc
		(start 147.7 93.216999)
		(mid 147.641421 93.35842)
		(end 147.5 93.416999)
		(width 0.1)
		(layer "In5.Cu")
		(net 701)
	)
	(arc
		(start 147.7 99.216999)
		(mid 147.641421 99.35842)
		(end 147.5 99.416999)
		(width 0.1)
		(layer "In5.Cu")
		(net 701)
	)
	(arc
		(start 116.465596 132)
		(mid 116.360944 131.956652)
		(end 116.317596 131.852)
		(width 0.1)
		(layer "In5.Cu")
		(net 701)
	)
	(arc
		(start 116.835596 131.00071)
		(mid 116.730944 131.044058)
		(end 116.687596 131.14871)
		(width 0.1)
		(layer "In5.Cu")
		(net 701)
	)
	(arc
		(start 147.7 95.216999)
		(mid 147.641421 95.35842)
		(end 147.5 95.416999)
		(width 0.1)
		(layer "In5.Cu")
		(net 701)
	)
	(arc
		(start 117.427596 131.852)
		(mid 117.384248 131.956652)
		(end 117.279596 132)
		(width 0.1)
		(layer "In5.Cu")
		(net 701)
	)
	(arc
		(start 147 101.416999)
		(mid 146.858579 101.475578)
		(end 146.8 101.616999)
		(width 0.1)
		(layer "In5.Cu")
		(net 701)
	)
	(arc
		(start 117.945596 132)
		(mid 117.840944 131.956652)
		(end 117.797596 131.852)
		(width 0.1)
		(layer "In5.Cu")
		(net 701)
	)
	(arc
		(start 147.5 102.916999)
		(mid 147.641421 102.975578)
		(end 147.7 103.116999)
		(width 0.1)
		(layer "In5.Cu")
		(net 701)
	)
	(arc
		(start 120.017596 131.14871)
		(mid 119.974248 131.044058)
		(end 119.869596 131.00071)
		(width 0.1)
		(layer "In5.Cu")
		(net 701)
	)
	(arc
		(start 146.8 98.716999)
		(mid 146.858579 98.85842)
		(end 147 98.916999)
		(width 0.1)
		(layer "In5.Cu")
		(net 701)
	)
	(arc
		(start 146.8 102.716999)
		(mid 146.858579 102.85842)
		(end 147 102.916999)
		(width 0.1)
		(layer "In5.Cu")
		(net 701)
	)
	(arc
		(start 115.207596 131.852)
		(mid 115.164248 131.956652)
		(end 115.059596 132)
		(width 0.1)
		(layer "In5.Cu")
		(net 701)
	)
	(arc
		(start 115.947596 131.852)
		(mid 115.904248 131.956652)
		(end 115.799596 132)
		(width 0.1)
		(layer "In5.Cu")
		(net 701)
	)
	(arc
		(start 119.425596 132)
		(mid 119.320944 131.956652)
		(end 119.277596 131.852)
		(width 0.1)
		(layer "In5.Cu")
		(net 701)
	)
	(arc
		(start 147 97.416999)
		(mid 146.858579 97.475578)
		(end 146.8 97.616999)
		(width 0.1)
		(layer "In5.Cu")
		(net 701)
	)
	(arc
		(start 146.8 99.716999)
		(mid 146.858579 99.85842)
		(end 147 99.916999)
		(width 0.1)
		(layer "In5.Cu")
		(net 701)
	)
	(arc
		(start 120.535596 131.000685)
		(mid 120.430944 131.044033)
		(end 120.387596 131.148685)
		(width 0.1)
		(layer "In5.Cu")
		(net 701)
	)
	(arc
		(start 147.5 98.916999)
		(mid 147.641421 98.975578)
		(end 147.7 99.116999)
		(width 0.1)
		(layer "In5.Cu")
		(net 701)
	)
	(arc
		(start 147 95.416999)
		(mid 146.858579 95.475578)
		(end 146.8 95.616999)
		(width 0.1)
		(layer "In5.Cu")
		(net 701)
	)
	(arc
		(start 120.165596 132)
		(mid 120.060944 131.956652)
		(end 120.017596 131.852)
		(width 0.1)
		(layer "In5.Cu")
		(net 701)
	)
	(segment
		(start 195.25 55.849)
		(end 195.25 56.77)
		(width 0.2)
		(layer "F.Cu")
		(net 702)
	)
	(segment
		(start 201.05 56.202001)
		(end 201.05 57.55)
		(width 0.2)
		(layer "F.Cu")
		(net 702)
	)
	(segment
		(start 141.480532 69.9)
		(end 141 69.9)
		(width 0.1)
		(layer "F.Cu")
		(net 702)
	)
	(segment
		(start 199.8 58.8)
		(end 199.8 60)
		(width 0.2)
		(layer "F.Cu")
		(net 702)
	)
	(segment
		(start 203.872 110.8)
		(end 204.49 110.8)
		(width 0.1)
		(layer "F.Cu")
		(net 702)
	)
	(segment
		(start 204.58799 96.59201)
		(end 203.87 95.87402)
		(width 0.1)
		(layer "F.Cu")
		(net 702)
	)
	(segment
		(start 201.6 111.1)
		(end 202.44 111.1)
		(width 0.1)
		(layer "F.Cu")
		(net 702)
	)
	(segment
		(start 205.59 101.91402)
		(end 205.59 97.59402)
		(width 0.1)
		(layer "F.Cu")
		(net 702)
	)
	(segment
		(start 206.66 102.98402)
		(end 205.59 101.91402)
		(width 0.1)
		(layer "F.Cu")
		(net 702)
	)
	(segment
		(start 195.25 55.849)
		(end 196.599 55.849)
		(width 0.2)
		(layer "F.Cu")
		(net 702)
	)
	(segment
		(start 205.59 97.59402)
		(end 204.58799 96.59201)
		(width 0.1)
		(layer "F.Cu")
		(net 702)
	)
	(segment
		(start 200.752001 56.5)
		(end 201.05 56.202001)
		(width 0.2)
		(layer "F.Cu")
		(net 702)
	)
	(segment
		(start 201.05 57.55)
		(end 199.8 58.8)
		(width 0.2)
		(layer "F.Cu")
		(net 702)
	)
	(segment
		(start 197.25 56.5)
		(end 200.752001 56.5)
		(width 0.2)
		(layer "F.Cu")
		(net 702)
	)
	(segment
		(start 196.599 55.849)
		(end 196.952 56.202)
		(width 0.2)
		(layer "F.Cu")
		(net 702)
	)
	(segment
		(start 196.952 56.202)
		(end 197.25 56.5)
		(width 0.2)
		(layer "F.Cu")
		(net 702)
	)
	(segment
		(start 206.66 108.63)
		(end 206.66 102.98402)
		(width 0.1)
		(layer "F.Cu")
		(net 702)
	)
	(segment
		(start 202.74 110.8)
		(end 203.872 110.8)
		(width 0.1)
		(layer "F.Cu")
		(net 702)
	)
	(segment
		(start 203.87 95.87402)
		(end 203.87 95.06)
		(width 0.1)
		(layer "F.Cu")
		(net 702)
	)
	(segment
		(start 202.44 111.1)
		(end 202.74 110.8)
		(width 0.1)
		(layer "F.Cu")
		(net 702)
	)
	(segment
		(start 142.230532 70.65)
		(end 141.480532 69.9)
		(width 0.1)
		(layer "F.Cu")
		(net 702)
	)
	(segment
		(start 204.49 110.8)
		(end 206.66 108.63)
		(width 0.1)
		(layer "F.Cu")
		(net 702)
	)
	(via
		(at 141 69.9)
		(size 0.45)
		(drill 0.1)
		(layers "F.Cu" "B.Cu")
		(net 702)
	)
	(via
		(at 194.19 64.41)
		(size 0.45)
		(drill 0.1)
		(layers "F.Cu" "B.Cu")
		(net 702)
	)
	(via
		(at 234.8 71.5)
		(size 0.45)
		(drill 0.1)
		(layers "F.Cu" "B.Cu")
		(net 702)
	)
	(via
		(at 199.8 60)
		(size 0.45)
		(drill 0.1)
		(layers "F.Cu" "B.Cu")
		(net 702)
	)
	(via
		(at 161.4 68.9)
		(size 0.45)
		(drill 0.1)
		(layers "F.Cu" "B.Cu")
		(net 702)
	)
	(via
		(at 203.87 95.06)
		(size 0.45)
		(drill 0.1)
		(layers "F.Cu" "B.Cu")
		(net 702)
	)
	(segment
		(start 234.8 71.5)
		(end 234 71.5)
		(width 0.3)
		(layer "B.Cu")
		(net 702)
	)
	(segment
		(start 234.8 71.5)
		(end 235.75 71.5)
		(width 0.3)
		(layer "B.Cu")
		(net 702)
	)
	(segment
		(start 143.9 68.4)
		(end 160.9 68.4)
		(width 0.1)
		(layer "In2.Cu")
		(net 702)
	)
	(segment
		(start 141 69.9)
		(end 142.5 68.4)
		(width 0.1)
		(layer "In2.Cu")
		(net 702)
	)
	(segment
		(start 160.9 68.4)
		(end 161.4 68.9)
		(width 0.1)
		(layer "In2.Cu")
		(net 702)
	)
	(segment
		(start 142.5 68.4)
		(end 143.9 68.4)
		(width 0.1)
		(layer "In2.Cu")
		(net 702)
	)
	(segment
		(start 195.234973 70.475025)
		(end 195.234973 63.055025)
		(width 0.1)
		(layer "In5.Cu")
		(net 702)
	)
	(segment
		(start 183.75 63.45)
		(end 183 64.2)
		(width 0.1)
		(layer "In5.Cu")
		(net 702)
	)
	(segment
		(start 196.795442 90.335442)
		(end 195.615442 90.335442)
		(width 0.1)
		(layer "In5.Cu")
		(net 702)
	)
	(segment
		(start 199.1 68)
		(end 197.5 68)
		(width 0.1)
		(layer "In5.Cu")
		(net 702)
	)
	(segment
		(start 203.4 67.3)
		(end 203 66.9)
		(width 0.1)
		(layer "In5.Cu")
		(net 702)
	)
	(segment
		(start 197.3 65.6)
		(end 198 64.9)
		(width 0.1)
		(layer "In5.Cu")
		(net 702)
	)
	(segment
		(start 190.35 63.45)
		(end 183.75 63.45)
		(width 0.1)
		(layer "In5.Cu")
		(net 702)
	)
	(segment
		(start 193.284973 78.825025)
		(end 193.284973 72.425025)
		(width 0.1)
		(layer "In5.Cu")
		(net 702)
	)
	(segment
		(start 199.8 60)
		(end 198.65 61.15)
		(width 0.1)
		(layer "In5.Cu")
		(net 702)
	)
	(segment
		(start 191.87 63.81)
		(end 193.59 63.81)
		(width 0.1)
		(layer "In5.Cu")
		(net 702)
	)
	(segment
		(start 160.8 64.7)
		(end 160.8 68.3)
		(width 0.1)
		(layer "In5.Cu")
		(net 702)
	)
	(segment
		(start 203.87 95.06)
		(end 201.52 95.06)
		(width 0.1)
		(layer "In5.Cu")
		(net 702)
	)
	(segment
		(start 192.794974 81.425026)
		(end 192.794974 79.315024)
		(width 0.1)
		(layer "In5.Cu")
		(net 702)
	)
	(segment
		(start 196.489998 61.8)
		(end 198 61.8)
		(width 0.1)
		(layer "In5.Cu")
		(net 702)
	)
	(segment
		(start 195.615442 90.335442)
		(end 192.104558 86.824558)
		(width 0.1)
		(layer "In5.Cu")
		(net 702)
	)
	(segment
		(start 161.3 64.2)
		(end 160.8 64.7)
		(width 0.1)
		(layer "In5.Cu")
		(net 702)
	)
	(segment
		(start 192.104558 86.824558)
		(end 192.104558 82.115442)
		(width 0.1)
		(layer "In5.Cu")
		(net 702)
	)
	(segment
		(start 198 61.8)
		(end 198.65 61.15)
		(width 0.1)
		(layer "In5.Cu")
		(net 702)
	)
	(segment
		(start 206 71.5)
		(end 203.4 68.9)
		(width 0.1)
		(layer "In5.Cu")
		(net 702)
	)
	(segment
		(start 201.52 95.06)
		(end 196.795442 90.335442)
		(width 0.1)
		(layer "In5.Cu")
		(net 702)
	)
	(segment
		(start 203 66.9)
		(end 200.2 66.9)
		(width 0.1)
		(layer "In5.Cu")
		(net 702)
	)
	(segment
		(start 234.8 71.5)
		(end 206 71.5)
		(width 0.1)
		(layer "In5.Cu")
		(net 702)
	)
	(segment
		(start 197.3 67.8)
		(end 197.3 65.6)
		(width 0.1)
		(layer "In5.Cu")
		(net 702)
	)
	(segment
		(start 192.104558 82.115442)
		(end 192.794974 81.425026)
		(width 0.1)
		(layer "In5.Cu")
		(net 702)
	)
	(segment
		(start 200.2 66.9)
		(end 199.1 68)
		(width 0.1)
		(layer "In5.Cu")
		(net 702)
	)
	(segment
		(start 203.4 68.9)
		(end 203.4 67.3)
		(width 0.1)
		(layer "In5.Cu")
		(net 702)
	)
	(segment
		(start 183 64.2)
		(end 161.3 64.2)
		(width 0.1)
		(layer "In5.Cu")
		(net 702)
	)
	(segment
		(start 193.284973 72.425025)
		(end 195.234973 70.475025)
		(width 0.1)
		(layer "In5.Cu")
		(net 702)
	)
	(segment
		(start 198 64.9)
		(end 198 61.8)
		(width 0.1)
		(layer "In5.Cu")
		(net 702)
	)
	(segment
		(start 195.234973 63.055025)
		(end 196.489998 61.8)
		(width 0.1)
		(layer "In5.Cu")
		(net 702)
	)
	(segment
		(start 192.794974 79.315024)
		(end 193.284973 78.825025)
		(width 0.1)
		(layer "In5.Cu")
		(net 702)
	)
	(segment
		(start 197.5 68)
		(end 197.3 67.8)
		(width 0.1)
		(layer "In5.Cu")
		(net 702)
	)
	(segment
		(start 190.71 63.81)
		(end 190.35 63.45)
		(width 0.1)
		(layer "In5.Cu")
		(net 702)
	)
	(segment
		(start 193.59 63.81)
		(end 194.19 64.41)
		(width 0.1)
		(layer "In5.Cu")
		(net 702)
	)
	(segment
		(start 191.87 63.81)
		(end 190.71 63.81)
		(width 0.1)
		(layer "In5.Cu")
		(net 702)
	)
	(segment
		(start 160.8 68.3)
		(end 161.4 68.9)
		(width 0.1)
		(layer "In5.Cu")
		(net 702)
	)
	(segment
		(start 197.02 55.9)
		(end 197.58 55.34)
		(width 0.1)
		(layer "In7.Cu")
		(net 702)
	)
	(segment
		(start 197.02 61.58)
		(end 197.02 55.9)
		(width 0.1)
		(layer "In7.Cu")
		(net 702)
	)
	(segment
		(start 199.19 55.34)
		(end 199.8 55.95)
		(width 0.1)
		(layer "In7.Cu")
		(net 702)
	)
	(segment
		(start 197.58 55.34)
		(end 199.19 55.34)
		(width 0.1)
		(layer "In7.Cu")
		(net 702)
	)
	(segment
		(start 199.8 55.95)
		(end 199.8 60)
		(width 0.1)
		(layer "In7.Cu")
		(net 702)
	)
	(segment
		(start 194.19 64.41)
		(end 197.02 61.58)
		(width 0.1)
		(layer "In7.Cu")
		(net 702)
	)
	(via
		(at 137.930532 84.15)
		(size 0.45)
		(drill 0.1)
		(layers "F.Cu" "B.Cu")
		(net 704)
	)
	(segment
		(start 140.430532 79.65)
		(end 140.425 79.65)
		(width 0.1)
		(layer "F.Cu")
		(net 706)
	)
	(segment
		(start 152.15 79.7)
		(end 152.15 70.6)
		(width 0.1)
		(layer "F.Cu")
		(net 706)
	)
	(segment
		(start 152.15 70.6)
		(end 153.75 69)
		(width 0.1)
		(layer "F.Cu")
		(net 706)
	)
	(via
		(at 152.15 79.7)
		(size 0.45)
		(drill 0.1)
		(layers "F.Cu" "B.Cu")
		(net 706)
	)
	(via
		(at 140.425 79.65)
		(size 0.45)
		(drill 0.1)
		(layers "F.Cu" "B.Cu")
		(net 706)
	)
	(via
		(at 153.75 69)
		(size 0.45)
		(drill 0.1)
		(layers "F.Cu" "B.Cu")
		(net 706)
	)
	(segment
		(start 153.75 67.5)
		(end 155.75 65.5)
		(width 0.1)
		(layer "B.Cu")
		(net 706)
	)
	(segment
		(start 153.75 67.5)
		(end 153.75 69)
		(width 0.1)
		(layer "B.Cu")
		(net 706)
	)
	(segment
		(start 156.66 65.5)
		(end 155.75 65.5)
		(width 0.1)
		(layer "B.Cu")
		(net 706)
	)
	(segment
		(start 141.975 80.025)
		(end 144.275 80.025)
		(width 0.1)
		(layer "In2.Cu")
		(net 706)
	)
	(segment
		(start 144.6 79.7)
		(end 152.15 79.7)
		(width 0.1)
		(layer "In2.Cu")
		(net 706)
	)
	(segment
		(start 140.425 79.65)
		(end 141.6 79.65)
		(width 0.1)
		(layer "In2.Cu")
		(net 706)
	)
	(segment
		(start 141.6 79.65)
		(end 141.975 80.025)
		(width 0.1)
		(layer "In2.Cu")
		(net 706)
	)
	(segment
		(start 144.275 80.025)
		(end 144.6 79.7)
		(width 0.1)
		(layer "In2.Cu")
		(net 706)
	)
	(segment
		(start 93.680001 105.02)
		(end 93.680001 104.995)
		(width 0.19)
		(layer "B.Cu")
		(net 707)
	)
	(segment
		(start 89.67663 95.915)
		(end 87.9 95.915)
		(width 0.19)
		(layer "B.Cu")
		(net 707)
	)
	(segment
		(start 93.365002 104.680001)
		(end 93.365002 102.403372)
		(width 0.19)
		(layer "B.Cu")
		(net 707)
	)
	(segment
		(start 91.485 100.52337)
		(end 91.485 97.72337)
		(width 0.19)
		(layer "B.Cu")
		(net 707)
	)
	(segment
		(start 93.680001 104.995)
		(end 93.365002 104.680001)
		(width 0.19)
		(layer "B.Cu")
		(net 707)
	)
	(segment
		(start 91.485 97.72337)
		(end 89.67663 95.915)
		(width 0.19)
		(layer "B.Cu")
		(net 707)
	)
	(segment
		(start 93.365002 102.403372)
		(end 91.485 100.52337)
		(width 0.19)
		(layer "B.Cu")
		(net 707)
	)
	(segment
		(start 86.385532 95.905)
		(end 85.935532 95.455)
		(width 0.19)
		(layer "B.Cu")
		(net 707)
	)
	(segment
		(start 87.89 95.905)
		(end 86.385532 95.905)
		(width 0.19)
		(layer "B.Cu")
		(net 707)
	)
	(segment
		(start 87.9 95.915)
		(end 87.89 95.905)
		(width 0.19)
		(layer "B.Cu")
		(net 707)
	)
	(segment
		(start 70.030532 120.25)
		(end 70.695532 119.585)
		(width 0.1)
		(layer "B.Cu")
		(net 709)
	)
	(segment
		(start 68 120.25)
		(end 70.030532 120.25)
		(width 0.1)
		(layer "B.Cu")
		(net 709)
	)
	(segment
		(start 66.250001 121.999999)
		(end 68 120.25)
		(width 0.1)
		(layer "B.Cu")
		(net 709)
	)
	(segment
		(start 63.5 121.999999)
		(end 66.250001 121.999999)
		(width 0.1)
		(layer "B.Cu")
		(net 709)
	)
	(segment
		(start 85.935532 101.805)
		(end 86.385532 101.355)
		(width 0.19)
		(layer "B.Cu")
		(net 713)
	)
	(segment
		(start 90.105001 104.689999)
		(end 89.8 104.995)
		(width 0.19)
		(layer "B.Cu")
		(net 713)
	)
	(segment
		(start 89.106685 103.268315)
		(end 90.105001 104.266631)
		(width 0.19)
		(layer "B.Cu")
		(net 713)
	)
	(segment
		(start 86.385532 101.355)
		(end 87.19337 101.355)
		(width 0.19)
		(layer "B.Cu")
		(net 713)
	)
	(segment
		(start 90.105001 104.266631)
		(end 90.105001 104.689999)
		(width 0.19)
		(layer "B.Cu")
		(net 713)
	)
	(segment
		(start 88.148734 103.035155)
		(end 88.233586 103.120007)
		(width 0.19)
		(layer "B.Cu")
		(net 713)
	)
	(segment
		(start 88.171719 102.67276)
		(end 88.148734 102.695744)
		(width 0.19)
		(layer "B.Cu")
		(net 713)
	)
	(segment
		(start 87.19337 101.355)
		(end 88.171719 102.333349)
		(width 0.19)
		(layer "B.Cu")
		(net 713)
	)
	(segment
		(start 89.8 104.995)
		(end 89.8 105.02)
		(width 0.19)
		(layer "B.Cu")
		(net 713)
	)
	(segment
		(start 88.572998 103.120007)
		(end 88.595982 103.097022)
		(width 0.19)
		(layer "B.Cu")
		(net 713)
	)
	(segment
		(start 88.935393 103.097022)
		(end 89.020247 103.181877)
		(width 0.19)
		(layer "B.Cu")
		(net 713)
	)
	(segment
		(start 89.020247 103.181877)
		(end 89.106685 103.268315)
		(width 0.19)
		(layer "B.Cu")
		(net 713)
	)
	(arc
		(start 88.595982 103.097022)
		(mid 88.765687 103.026728)
		(end 88.935393 103.097022)
		(width 0.19)
		(layer "B.Cu")
		(net 713)
	)
	(arc
		(start 88.233586 103.120007)
		(mid 88.403292 103.190302)
		(end 88.572998 103.120007)
		(width 0.19)
		(layer "B.Cu")
		(net 713)
	)
	(arc
		(start 88.148734 102.695744)
		(mid 88.07844 102.865449)
		(end 88.148734 103.035155)
		(width 0.19)
		(layer "B.Cu")
		(net 713)
	)
	(arc
		(start 88.171719 102.333349)
		(mid 88.242013 102.503055)
		(end 88.171719 102.67276)
		(width 0.19)
		(layer "B.Cu")
		(net 713)
	)
	(segment
		(start 153.1 84.2)
		(end 152.6 83.7)
		(width 0.1)
		(layer "F.Cu")
		(net 715)
	)
	(segment
		(start 154.25 75.45)
		(end 154.25 69.25)
		(width 0.1)
		(layer "F.Cu")
		(net 715)
	)
	(segment
		(start 153.4 84.2)
		(end 153.1 84.2)
		(width 0.1)
		(layer "F.Cu")
		(net 715)
	)
	(segment
		(start 152.6 83.7)
		(end 152.6 77.1)
		(width 0.1)
		(layer "F.Cu")
		(net 715)
	)
	(segment
		(start 152.6 77.1)
		(end 154.25 75.45)
		(width 0.1)
		(layer "F.Cu")
		(net 715)
	)
	(via
		(at 142.430532 84.15)
		(size 0.45)
		(drill 0.1)
		(layers "F.Cu" "B.Cu")
		(net 715)
	)
	(via
		(at 154.25 69.25)
		(size 0.45)
		(drill 0.1)
		(layers "F.Cu" "B.Cu")
		(net 715)
	)
	(via
		(at 153.4 84.2)
		(size 0.45)
		(drill 0.1)
		(layers "F.Cu" "B.Cu")
		(net 715)
	)
	(segment
		(start 154.25 67.75)
		(end 155.49 66.51)
		(width 0.1)
		(layer "B.Cu")
		(net 715)
	)
	(segment
		(start 156.67 66.51)
		(end 155.49 66.51)
		(width 0.1)
		(layer "B.Cu")
		(net 715)
	)
	(segment
		(start 154.25 67.75)
		(end 154.25 69.25)
		(width 0.1)
		(layer "B.Cu")
		(net 715)
	)
	(segment
		(start 153.4 84.2)
		(end 152.4 84.2)
		(width 0.1)
		(layer "In2.Cu")
		(net 715)
	)
	(segment
		(start 145.375 84.2)
		(end 145.05 84.525)
		(width 0.1)
		(layer "In2.Cu")
		(net 715)
	)
	(segment
		(start 142.805532 84.525)
		(end 142.430532 84.15)
		(width 0.1)
		(layer "In2.Cu")
		(net 715)
	)
	(segment
		(start 152.4 84.2)
		(end 152.1 84.5)
		(width 0.1)
		(layer "In2.Cu")
		(net 715)
	)
	(segment
		(start 145.05 84.525)
		(end 142.805532 84.525)
		(width 0.1)
		(layer "In2.Cu")
		(net 715)
	)
	(segment
		(start 150.4 84.2)
		(end 145.375 84.2)
		(width 0.1)
		(layer "In2.Cu")
		(net 715)
	)
	(segment
		(start 150.7 84.5)
		(end 150.4 84.2)
		(width 0.1)
		(layer "In2.Cu")
		(net 715)
	)
	(segment
		(start 152.1 84.5)
		(end 150.7 84.5)
		(width 0.1)
		(layer "In2.Cu")
		(net 715)
	)
	(segment
		(start 63 76.6)
		(end 69.6 76.6)
		(width 0.1)
		(layer "B.Cu")
		(net 717)
	)
	(segment
		(start 70.695532 77.695532)
		(end 69.6 76.6)
		(width 0.1)
		(layer "B.Cu")
		(net 717)
	)
	(segment
		(start 70.695532 78.945)
		(end 70.695532 77.695532)
		(width 0.1)
		(layer "B.Cu")
		(net 717)
	)
	(segment
		(start 89.4 122.7)
		(end 89.515 122.585)
		(width 0.19)
		(layer "F.Cu")
		(net 720)
	)
	(segment
		(start 96.385 147.47663)
		(end 94.983762 148.877868)
		(width 0.19)
		(layer "F.Cu")
		(net 720)
	)
	(segment
		(start 99.065532 80.185)
		(end 99.180532 80.3)
		(width 0.19)
		(layer "F.Cu")
		(net 720)
	)
	(segment
		(start 91.885 121.72337)
		(end 91.885 123.17663)
		(width 0.19)
		(layer "F.Cu")
		(net 720)
	)
	(segment
		(start 90.42337 121.015)
		(end 91.17663 121.015)
		(width 0.19)
		(layer "F.Cu")
		(net 720)
	)
	(segment
		(start 94.242133 148.877868)
		(end 93.940001 149.18)
		(width 0.19)
		(layer "F.Cu")
		(net 720)
	)
	(segment
		(start 93.940001 149.18)
		(end 93.46 149.18)
		(width 0.19)
		(layer "F.Cu")
		(net 720)
	)
	(segment
		(start 89.515 121.92337)
		(end 90.42337 121.015)
		(width 0.19)
		(layer "F.Cu")
		(net 720)
	)
	(segment
		(start 90.585 126.62337)
		(end 96.385 132.42337)
		(width 0.19)
		(layer "F.Cu")
		(net 720)
	)
	(segment
		(start 96.385 132.42337)
		(end 96.385 147.47663)
		(width 0.19)
		(layer "F.Cu")
		(net 720)
	)
	(segment
		(start 91.17663 121.015)
		(end 91.885 121.72337)
		(width 0.19)
		(layer "F.Cu")
		(net 720)
	)
	(segment
		(start 90.585 124.47663)
		(end 90.585 126.62337)
		(width 0.19)
		(layer "F.Cu")
		(net 720)
	)
	(segment
		(start 91.885 123.17663)
		(end 90.585 124.47663)
		(width 0.19)
		(layer "F.Cu")
		(net 720)
	)
	(segment
		(start 89.515 122.585)
		(end 89.515 121.92337)
		(width 0.19)
		(layer "F.Cu")
		(net 720)
	)
	(segment
		(start 94.983762 148.877868)
		(end 94.242133 148.877868)
		(width 0.19)
		(layer "F.Cu")
		(net 720)
	)
	(segment
		(start 99.330532 79.65)
		(end 99.065532 79.915)
		(width 0.19)
		(layer "F.Cu")
		(net 720)
	)
	(segment
		(start 99.065532 79.915)
		(end 99.065532 80.185)
		(width 0.19)
		(layer "F.Cu")
		(net 720)
	)
	(via
		(at 89.4 122.7)
		(size 0.45)
		(drill 0.1)
		(layers "F.Cu" "B.Cu")
		(net 720)
	)
	(via
		(at 93.4 149.2)
		(size 0.45)
		(drill 0.1)
		(layers "F.Cu" "B.Cu")
		(net 720)
	)
	(via
		(at 84.95 97.366373)
		(size 0.45)
		(drill 0.1)
		(layers "F.Cu" "B.Cu")
		(net 720)
	)
	(via
		(at 99.180532 80.3)
		(size 0.45)
		(drill 0.1)
		(layers "F.Cu" "B.Cu")
		(net 720)
	)
	(segment
		(start 93.35 149.209999)
		(end 93.390001 149.209999)
		(width 0.19)
		(layer "B.Cu")
		(net 720)
	)
	(segment
		(start 93.390001 149.209999)
		(end 93.4 149.2)
		(width 0.19)
		(layer "B.Cu")
		(net 720)
	)
	(segment
		(start 99.018032 79.573576)
		(end 99.018032 80.1375)
		(width 0.15)
		(layer "In5.Cu")
		(net 720)
	)
	(segment
		(start 84.843044 96.2375)
		(end 84.318044 96.2375)
		(width 0.15)
		(layer "In5.Cu")
		(net 720)
	)
	(segment
		(start 92.6625 84.948588)
		(end 92.6625 82.143044)
		(width 0.15)
		(layer "In5.Cu")
		(net 720)
	)
	(segment
		(start 92.6625 82.143044)
		(end 96.043044 78.7625)
		(width 0.15)
		(layer "In5.Cu")
		(net 720)
	)
	(segment
		(start 84.95 97.366373)
		(end 85.1125 97.203873)
		(width 0.15)
		(layer "In5.Cu")
		(net 720)
	)
	(segment
		(start 85.1125 96.506956)
		(end 84.843044 96.2375)
		(width 0.15)
		(layer "In5.Cu")
		(net 720)
	)
	(segment
		(start 83.8625 95.781956)
		(end 83.8625 91.468044)
		(width 0.15)
		(layer "In5.Cu")
		(net 720)
	)
	(segment
		(start 96.043044 78.7625)
		(end 98.206956 78.7625)
		(width 0.15)
		(layer "In5.Cu")
		(net 720)
	)
	(segment
		(start 85.1125 97.203873)
		(end 85.1125 96.506956)
		(width 0.15)
		(layer "In5.Cu")
		(net 720)
	)
	(segment
		(start 86.798588 90.8125)
		(end 92.6625 84.948588)
		(width 0.15)
		(layer "In5.Cu")
		(net 720)
	)
	(segment
		(start 98.206956 78.7625)
		(end 99.018032 79.573576)
		(width 0.15)
		(layer "In5.Cu")
		(net 720)
	)
	(segment
		(start 84.518044 90.8125)
		(end 86.798588 90.8125)
		(width 0.15)
		(layer "In5.Cu")
		(net 720)
	)
	(segment
		(start 83.8625 91.468044)
		(end 84.518044 90.8125)
		(width 0.15)
		(layer "In5.Cu")
		(net 720)
	)
	(segment
		(start 99.018032 80.1375)
		(end 99.180532 80.3)
		(width 0.15)
		(layer "In5.Cu")
		(net 720)
	)
	(segment
		(start 84.318044 96.2375)
		(end 83.8625 95.781956)
		(width 0.15)
		(layer "In5.Cu")
		(net 720)
	)
	(segment
		(start 85.1125 105.981956)
		(end 85.518044 106.3875)
		(width 0.15)
		(layer "In7.Cu")
		(net 720)
	)
	(segment
		(start 86.643044 106.3875)
		(end 88.4875 108.231956)
		(width 0.15)
		(layer "In7.Cu")
		(net 720)
	)
	(segment
		(start 85.1125 97.528873)
		(end 85.1125 105.981956)
		(width 0.15)
		(layer "In7.Cu")
		(net 720)
	)
	(segment
		(start 84.95 97.366373)
		(end 85.1125 97.528873)
		(width 0.15)
		(layer "In7.Cu")
		(net 720)
	)
	(segment
		(start 88.4875 108.231956)
		(end 88.4875 118.381956)
		(width 0.15)
		(layer "In7.Cu")
		(net 720)
	)
	(segment
		(start 89.5625 122.5375)
		(end 89.4 122.7)
		(width 0.15)
		(layer "In7.Cu")
		(net 720)
	)
	(segment
		(start 88.4875 118.381956)
		(end 89.5625 119.456956)
		(width 0.15)
		(layer "In7.Cu")
		(net 720)
	)
	(segment
		(start 85.518044 106.3875)
		(end 86.643044 106.3875)
		(width 0.15)
		(layer "In7.Cu")
		(net 720)
	)
	(segment
		(start 89.5625 119.456956)
		(end 89.5625 122.5375)
		(width 0.15)
		(layer "In7.Cu")
		(net 720)
	)
	(segment
		(start 97.065532 81.685)
		(end 97.180532 81.8)
		(width 0.19)
		(layer "F.Cu")
		(net 722)
	)
	(segment
		(start 97.330532 81.15)
		(end 97.065532 81.415)
		(width 0.19)
		(layer "F.Cu")
		(net 722)
	)
	(segment
		(start 97.065532 81.415)
		(end 97.065532 81.685)
		(width 0.19)
		(layer "F.Cu")
		(net 722)
	)
	(via
		(at 97.180532 81.8)
		(size 0.45)
		(drill 0.1)
		(layers "F.Cu" "B.Cu")
		(net 722)
	)
	(segment
		(start 97.065532 81.915)
		(end 97.065532 82.853902)
		(width 0.19)
		(layer "B.Cu")
		(net 722)
	)
	(segment
		(start 95.46663 116.595)
		(end 86.385532 116.595)
		(width 0.19)
		(layer "B.Cu")
		(net 722)
	)
	(segment
		(start 98.335 86.77663)
		(end 98.335 101.47337)
		(width 0.19)
		(layer "B.Cu")
		(net 722)
	)
	(segment
		(start 100.985 111.07663)
		(end 95.46663 116.595)
		(width 0.19)
		(layer "B.Cu")
		(net 722)
	)
	(segment
		(start 100.985 104.12337)
		(end 100.985 111.07663)
		(width 0.19)
		(layer "B.Cu")
		(net 722)
	)
	(segment
		(start 100.335 83.67337)
		(end 100.335 84.77663)
		(width 0.19)
		(layer "B.Cu")
		(net 722)
	)
	(segment
		(start 86.385532 116.595)
		(end 85.935532 117.045)
		(width 0.19)
		(layer "B.Cu")
		(net 722)
	)
	(segment
		(start 99.75163 83.09)
		(end 100.335 83.67337)
		(width 0.19)
		(layer "B.Cu")
		(net 722)
	)
	(segment
		(start 100.335 84.77663)
		(end 98.335 86.77663)
		(width 0.19)
		(layer "B.Cu")
		(net 722)
	)
	(segment
		(start 97.180532 81.8)
		(end 97.065532 81.915)
		(width 0.19)
		(layer "B.Cu")
		(net 722)
	)
	(segment
		(start 97.065532 82.853902)
		(end 97.30163 83.09)
		(width 0.19)
		(layer "B.Cu")
		(net 722)
	)
	(segment
		(start 97.30163 83.09)
		(end 99.75163 83.09)
		(width 0.19)
		(layer "B.Cu")
		(net 722)
	)
	(segment
		(start 98.335 101.47337)
		(end 100.985 104.12337)
		(width 0.19)
		(layer "B.Cu")
		(net 722)
	)
	(segment
		(start 108.695532 80.885)
		(end 108.695532 79.215)
		(width 0.19)
		(layer "F.Cu")
		(net 725)
	)
	(segment
		(start 108.695532 79.215)
		(end 108.580532 79.1)
		(width 0.19)
		(layer "F.Cu")
		(net 725)
	)
	(segment
		(start 108.430532 81.15)
		(end 108.695532 80.885)
		(width 0.19)
		(layer "F.Cu")
		(net 725)
	)
	(via
		(at 108.580532 79.1)
		(size 0.45)
		(drill 0.1)
		(layers "F.Cu" "B.Cu")
		(net 725)
	)
	(segment
		(start 104.715 81.32337)
		(end 104.715 83.62337)
		(width 0.19)
		(layer "B.Cu")
		(net 725)
	)
	(segment
		(start 106.097988 105.6845)
		(end 112.9945 105.6845)
		(width 0.19)
		(layer "B.Cu")
		(net 725)
	)
	(segment
		(start 100.830501 100.417013)
		(end 106.097988 105.6845)
		(width 0.19)
		(layer "B.Cu")
		(net 725)
	)
	(segment
		(start 108.32337 80.215)
		(end 105.82337 80.215)
		(width 0.19)
		(layer "B.Cu")
		(net 725)
	)
	(segment
		(start 108.695532 79.215)
		(end 108.695532 79.842838)
		(width 0.19)
		(layer "B.Cu")
		(net 725)
	)
	(segment
		(start 108.580532 79.1)
		(end 108.695532 79.215)
		(width 0.19)
		(layer "B.Cu")
		(net 725)
	)
	(segment
		(start 105.82337 80.215)
		(end 104.715 81.32337)
		(width 0.19)
		(layer "B.Cu")
		(net 725)
	)
	(segment
		(start 104.715 83.62337)
		(end 100.830501 87.507869)
		(width 0.19)
		(layer "B.Cu")
		(net 725)
	)
	(segment
		(start 100.830501 87.507869)
		(end 100.830501 100.417013)
		(width 0.19)
		(layer "B.Cu")
		(net 725)
	)
	(segment
		(start 108.695532 79.842838)
		(end 108.32337 80.215)
		(width 0.19)
		(layer "B.Cu")
		(net 725)
	)
	(segment
		(start 112.9945 105.6845)
		(end 113.06 105.75)
		(width 0.19)
		(layer "B.Cu")
		(net 725)
	)
	(segment
		(start 113.06 105.75)
		(end 113.685 105.75)
		(width 0.19)
		(layer "B.Cu")
		(net 725)
	)
	(segment
		(start 88.62 94.1)
		(end 88.595 94.1)
		(width 0.19)
		(layer "F.Cu")
		(net 726)
	)
	(segment
		(start 85.115 93.27663)
		(end 85.115 91.42663)
		(width 0.19)
		(layer "F.Cu")
		(net 726)
	)
	(segment
		(start 88.28 93.785)
		(end 85.62337 93.785)
		(width 0.19)
		(layer "F.Cu")
		(net 726)
	)
	(segment
		(start 84.45 91.185)
		(end 84.44 91.195)
		(width 0.19)
		(layer "F.Cu")
		(net 726)
	)
	(segment
		(start 84.87337 91.185)
		(end 84.45 91.185)
		(width 0.19)
		(layer "F.Cu")
		(net 726)
	)
	(segment
		(start 83.845532 91.195)
		(end 83.395532 91.645)
		(width 0.19)
		(layer "F.Cu")
		(net 726)
	)
	(segment
		(start 85.115 91.42663)
		(end 84.87337 91.185)
		(width 0.19)
		(layer "F.Cu")
		(net 726)
	)
	(segment
		(start 85.62337 93.785)
		(end 85.115 93.27663)
		(width 0.19)
		(layer "F.Cu")
		(net 726)
	)
	(segment
		(start 88.595 94.1)
		(end 88.28 93.785)
		(width 0.19)
		(layer "F.Cu")
		(net 726)
	)
	(segment
		(start 84.44 91.195)
		(end 83.845532 91.195)
		(width 0.19)
		(layer "F.Cu")
		(net 726)
	)
	(via
		(at 83.395532 91.645)
		(size 0.45)
		(drill 0.1)
		(layers "F.Cu" "B.Cu")
		(net 726)
	)
	(segment
		(start 92.195 118.1)
		(end 91.88 118.415)
		(width 0.19)
		(layer "F.Cu")
		(net 728)
	)
	(segment
		(start 88.34663 113.685)
		(end 85.115532 113.685)
		(width 0.19)
		(layer "F.Cu")
		(net 728)
	)
	(segment
		(start 85.115532 113.685)
		(end 84.665532 113.235)
		(width 0.19)
		(layer "F.Cu")
		(net 728)
	)
	(segment
		(start 89.885 115.22337)
		(end 88.34663 113.685)
		(width 0.19)
		(layer "F.Cu")
		(net 728)
	)
	(segment
		(start 91.88 118.415)
		(end 90.77663 118.415)
		(width 0.19)
		(layer "F.Cu")
		(net 728)
	)
	(segment
		(start 89.885 117.52337)
		(end 89.885 115.22337)
		(width 0.19)
		(layer "F.Cu")
		(net 728)
	)
	(segment
		(start 92.22 118.1)
		(end 92.195 118.1)
		(width 0.19)
		(layer "F.Cu")
		(net 728)
	)
	(segment
		(start 90.77663 118.415)
		(end 89.885 117.52337)
		(width 0.19)
		(layer "F.Cu")
		(net 728)
	)
	(via
		(at 84.665532 113.235)
		(size 0.45)
		(drill 0.1)
		(layers "F.Cu" "B.Cu")
		(net 728)
	)
	(segment
		(start 95.185 101.32337)
		(end 95.185 93.72337)
		(width 0.19)
		(layer "B.Cu")
		(net 729)
	)
	(segment
		(start 86.658408 90.815)
		(end 86.648408 90.825)
		(width 0.19)
		(layer "B.Cu")
		(net 729)
	)
	(segment
		(start 96.365 104.69)
		(end 96.365 102.50337)
		(width 0.19)
		(layer "B.Cu")
		(net 729)
	)
	(segment
		(start 92.27663 90.815)
		(end 86.658408 90.815)
		(width 0.19)
		(layer "B.Cu")
		(net 729)
	)
	(segment
		(start 96.365 102.50337)
		(end 95.185 101.32337)
		(width 0.19)
		(layer "B.Cu")
		(net 729)
	)
	(segment
		(start 86.648408 90.825)
		(end 86.385532 90.825)
		(width 0.19)
		(layer "B.Cu")
		(net 729)
	)
	(segment
		(start 96.68 105.005)
		(end 96.365 104.69)
		(width 0.19)
		(layer "B.Cu")
		(net 729)
	)
	(segment
		(start 86.385532 90.825)
		(end 85.935532 90.375)
		(width 0.19)
		(layer "B.Cu")
		(net 729)
	)
	(segment
		(start 96.68 105.03)
		(end 96.68 105.005)
		(width 0.19)
		(layer "B.Cu")
		(net 729)
	)
	(segment
		(start 95.185 93.72337)
		(end 92.27663 90.815)
		(width 0.19)
		(layer "B.Cu")
		(net 729)
	)
	(segment
		(start 111.330532 82.65)
		(end 111.065532 82.915)
		(width 0.19)
		(layer "F.Cu")
		(net 731)
	)
	(segment
		(start 111.065532 83.485)
		(end 111.180532 83.6)
		(width 0.19)
		(layer "F.Cu")
		(net 731)
	)
	(segment
		(start 111.065532 82.915)
		(end 111.065532 83.485)
		(width 0.19)
		(layer "F.Cu")
		(net 731)
	)
	(via
		(at 111.180532 83.6)
		(size 0.45)
		(drill 0.1)
		(layers "F.Cu" "B.Cu")
		(net 731)
	)
	(segment
		(start 107.473511 94.513815)
		(end 107.440999 94.513815)
		(width 0.19)
		(layer "B.Cu")
		(net 731)
	)
	(segment
		(start 111.785 87.87663)
		(end 111.17663 88.485)
		(width 0.19)
		(layer "B.Cu")
		(net 731)
	)
	(segment
		(start 111.065532 83.715)
		(end 111.065532 84.403902)
		(width 0.19)
		(layer "B.Cu")
		(net 731)
	)
	(segment
		(start 111.180532 83.6)
		(end 111.065532 83.715)
		(width 0.19)
		(layer "B.Cu")
		(net 731)
	)
	(segment
		(start 107.200999 94.273815)
		(end 107.200999 91.560631)
		(width 0.19)
		(layer "B.Cu")
		(net 731)
	)
	(segment
		(start 111.785 85.12337)
		(end 111.785 87.87663)
		(width 0.19)
		(layer "B.Cu")
		(net 731)
	)
	(segment
		(start 111.17663 88.485)
		(end 110.27663 88.485)
		(width 0.19)
		(layer "B.Cu")
		(net 731)
	)
	(segment
		(start 110.27663 88.485)
		(end 107.200999 91.560631)
		(width 0.19)
		(layer "B.Cu")
		(net 731)
	)
	(segment
		(start 107.713511 94.873815)
		(end 107.713511 94.753815)
		(width 0.19)
		(layer "B.Cu")
		(net 731)
	)
	(segment
		(start 112.995 99.314)
		(end 108.736734 99.314)
		(width 0.19)
		(layer "B.Cu")
		(net 731)
	)
	(segment
		(start 113.06 99.249)
		(end 112.995 99.314)
		(width 0.19)
		(layer "B.Cu")
		(net 731)
	)
	(segment
		(start 113.685 99.249)
		(end 113.06 99.249)
		(width 0.19)
		(layer "B.Cu")
		(net 731)
	)
	(segment
		(start 111.065532 84.403902)
		(end 111.785 85.12337)
		(width 0.19)
		(layer "B.Cu")
		(net 731)
	)
	(segment
		(start 107.440999 95.113815)
		(end 107.473511 95.113815)
		(width 0.19)
		(layer "B.Cu")
		(net 731)
	)
	(segment
		(start 108.736734 99.314)
		(end 107.200999 97.778265)
		(width 0.19)
		(layer "B.Cu")
		(net 731)
	)
	(segment
		(start 107.200999 97.778265)
		(end 107.200999 95.353815)
		(width 0.19)
		(layer "B.Cu")
		(net 731)
	)
	(arc
		(start 107.440999 94.513815)
		(mid 107.271293 94.443521)
		(end 107.200999 94.273815)
		(width 0.19)
		(layer "B.Cu")
		(net 731)
	)
	(arc
		(start 107.200999 95.353815)
		(mid 107.271293 95.184109)
		(end 107.440999 95.113815)
		(width 0.19)
		(layer "B.Cu")
		(net 731)
	)
	(arc
		(start 107.473511 95.113815)
		(mid 107.643217 95.043521)
		(end 107.713511 94.873815)
		(width 0.19)
		(layer "B.Cu")
		(net 731)
	)
	(arc
		(start 107.713511 94.753815)
		(mid 107.643217 94.584109)
		(end 107.473511 94.513815)
		(width 0.19)
		(layer "B.Cu")
		(net 731)
	)
	(segment
		(start 106.695532 78.825)
		(end 106.580532 78.71)
		(width 0.19)
		(layer "F.Cu")
		(net 732)
	)
	(segment
		(start 106.430532 79.65)
		(end 106.695532 79.385)
		(width 0.19)
		(layer "F.Cu")
		(net 732)
	)
	(segment
		(start 106.695532 79.385)
		(end 106.695532 78.825)
		(width 0.19)
		(layer "F.Cu")
		(net 732)
	)
	(via
		(at 106.580532 78.71)
		(size 0.45)
		(drill 0.1)
		(layers "F.Cu" "B.Cu")
		(net 732)
	)
	(via
		(at 87.402261 105.627261)
		(size 0.45)
		(drill 0.1)
		(layers "F.Cu" "B.Cu")
		(net 732)
	)
	(segment
		(start 86.385532 106.065)
		(end 87.14837 106.065)
		(width 0.19)
		(layer "B.Cu")
		(net 732)
	)
	(segment
		(start 85.935532 105.615)
		(end 86.385532 106.065)
		(width 0.19)
		(layer "B.Cu")
		(net 732)
	)
	(segment
		(start 87.14837 106.065)
		(end 87.402261 105.811109)
		(width 0.19)
		(layer "B.Cu")
		(net 732)
	)
	(segment
		(start 87.402261 105.811109)
		(end 87.402261 105.627261)
		(width 0.19)
		(layer "B.Cu")
		(net 732)
	)
	(segment
		(start 106.533032 78.6625)
		(end 105.794202 78.6625)
		(width 0.15)
		(layer "In5.Cu")
		(net 732)
	)
	(segment
		(start 99.5625 80.181956)
		(end 99.5625 79.218044)
		(width 0.15)
		(layer "In5.Cu")
		(net 732)
	)
	(segment
		(start 106.580532 78.71)
		(end 106.533032 78.6625)
		(width 0.15)
		(layer "In5.Cu")
		(net 732)
	)
	(segment
		(start 100.0125 81.618044)
		(end 100.0125 80.631956)
		(width 0.15)
		(layer "In5.Cu")
		(net 732)
	)
	(segment
		(start 99.5625 79.218044)
		(end 100.118044 78.6625)
		(width 0.15)
		(layer "In5.Cu")
		(net 732)
	)
	(segment
		(start 87.402261 105.627261)
		(end 87.653284 105.627261)
		(width 0.15)
		(layer "In5.Cu")
		(net 732)
	)
	(segment
		(start 87.653284 105.627261)
		(end 89.2625 104.018045)
		(width 0.15)
		(layer "In5.Cu")
		(net 732)
	)
	(segment
		(start 104.264202 78.448943)
		(end 104.264202 78.4825)
		(width 0.15)
		(layer "In5.Cu")
		(net 732)
	)
	(segment
		(start 97.093044 83.2125)
		(end 98.418044 83.2125)
		(width 0.15)
		(layer "In5.Cu")
		(net 732)
	)
	(segment
		(start 105.614202 78.4825)
		(end 105.614202 78.448951)
		(width 0.15)
		(layer "In5.Cu")
		(net 732)
	)
	(segment
		(start 105.164202 78.448951)
		(end 105.164202 78.4825)
		(width 0.15)
		(layer "In5.Cu")
		(net 732)
	)
	(segment
		(start 98.418044 83.2125)
		(end 100.0125 81.618044)
		(width 0.15)
		(layer "In5.Cu")
		(net 732)
	)
	(segment
		(start 104.714202 78.4825)
		(end 104.714202 78.448943)
		(width 0.15)
		(layer "In5.Cu")
		(net 732)
	)
	(segment
		(start 104.984202 78.6625)
		(end 104.894202 78.6625)
		(width 0.15)
		(layer "In5.Cu")
		(net 732)
	)
	(segment
		(start 100.0125 80.631956)
		(end 99.5625 80.181956)
		(width 0.15)
		(layer "In5.Cu")
		(net 732)
	)
	(segment
		(start 104.534202 78.268943)
		(end 104.444202 78.268943)
		(width 0.15)
		(layer "In5.Cu")
		(net 732)
	)
	(segment
		(start 105.434202 78.268951)
		(end 105.344202 78.268951)
		(width 0.15)
		(layer "In5.Cu")
		(net 732)
	)
	(segment
		(start 100.118044 78.6625)
		(end 104.084202 78.6625)
		(width 0.15)
		(layer "In5.Cu")
		(net 732)
	)
	(segment
		(start 89.2625 104.018045)
		(end 89.2625 91.043044)
		(width 0.15)
		(layer "In5.Cu")
		(net 732)
	)
	(segment
		(start 89.2625 91.043044)
		(end 97.093044 83.2125)
		(width 0.15)
		(layer "In5.Cu")
		(net 732)
	)
	(arc
		(start 105.164202 78.4825)
		(mid 105.111481 78.609779)
		(end 104.984202 78.6625)
		(width 0.15)
		(layer "In5.Cu")
		(net 732)
	)
	(arc
		(start 105.344202 78.268951)
		(mid 105.216923 78.321672)
		(end 105.164202 78.448951)
		(width 0.15)
		(layer "In5.Cu")
		(net 732)
	)
	(arc
		(start 104.264202 78.4825)
		(mid 104.211481 78.609779)
		(end 104.084202 78.6625)
		(width 0.15)
		(layer "In5.Cu")
		(net 732)
	)
	(arc
		(start 104.714202 78.448943)
		(mid 104.661481 78.321664)
		(end 104.534202 78.268943)
		(width 0.15)
		(layer "In5.Cu")
		(net 732)
	)
	(arc
		(start 104.894202 78.6625)
		(mid 104.766923 78.609779)
		(end 104.714202 78.4825)
		(width 0.15)
		(layer "In5.Cu")
		(net 732)
	)
	(arc
		(start 105.794202 78.6625)
		(mid 105.666923 78.609779)
		(end 105.614202 78.4825)
		(width 0.15)
		(layer "In5.Cu")
		(net 732)
	)
	(arc
		(start 104.444202 78.268943)
		(mid 104.316923 78.321664)
		(end 104.264202 78.448943)
		(width 0.15)
		(layer "In5.Cu")
		(net 732)
	)
	(arc
		(start 105.614202 78.448951)
		(mid 105.561481 78.321672)
		(end 105.434202 78.268951)
		(width 0.15)
		(layer "In5.Cu")
		(net 732)
	)
	(segment
		(start 86.285 93.715)
		(end 86.3 93.73)
		(width 0.19)
		(layer "B.Cu")
		(net 733)
	)
	(segment
		(start 90.958396 95.559437)
		(end 90.933896 95.583936)
		(width 0.19)
		(layer "B.Cu")
		(net 733)
	)
	(segment
		(start 94.180001 103.095)
		(end 94.180001 103.12)
		(width 0.19)
		(layer "B.Cu")
		(net 733)
	)
	(segment
		(start 85.135532 93.715)
		(end 86.285 93.715)
		(width 0.1)
		(layer "B.Cu")
		(net 733)
	)
	(segment
		(start 94.495001 102.78)
		(end 94.180001 103.095)
		(width 0.19)
		(layer "B.Cu")
		(net 733)
	)
	(segment
		(start 90.933896 95.923347)
		(end 91.018748 96.008199)
		(width 0.19)
		(layer "B.Cu")
		(net 733)
	)
	(segment
		(start 91.72207 95.983699)
		(end 91.806924 96.068554)
		(width 0.19)
		(layer "B.Cu")
		(net 733)
	)
	(segment
		(start 91.35816 96.008199)
		(end 91.382659 95.983699)
		(width 0.19)
		(layer "B.Cu")
		(net 733)
	)
	(segment
		(start 84.665532 94.185)
		(end 85.135532 93.715)
		(width 0.1)
		(layer "B.Cu")
		(net 733)
	)
	(segment
		(start 93.715 97.97663)
		(end 93.715 101.72663)
		(width 0.19)
		(layer "B.Cu")
		(net 733)
	)
	(segment
		(start 89.46837 93.73)
		(end 90.958396 95.220026)
		(width 0.19)
		(layer "B.Cu")
		(net 733)
	)
	(segment
		(start 93.715 101.72663)
		(end 94.495001 102.506631)
		(width 0.19)
		(layer "B.Cu")
		(net 733)
	)
	(segment
		(start 94.495001 102.506631)
		(end 94.495001 102.78)
		(width 0.19)
		(layer "B.Cu")
		(net 733)
	)
	(segment
		(start 86.3 93.73)
		(end 89.46837 93.73)
		(width 0.19)
		(layer "B.Cu")
		(net 733)
	)
	(segment
		(start 92.255532 96.517162)
		(end 93.715 97.97663)
		(width 0.19)
		(layer "B.Cu")
		(net 733)
	)
	(segment
		(start 91.949408 96.211038)
		(end 92.255532 96.517162)
		(width 0.19)
		(layer "B.Cu")
		(net 733)
	)
	(segment
		(start 91.806924 96.068554)
		(end 91.949408 96.211038)
		(width 0.19)
		(layer "B.Cu")
		(net 733)
	)
	(arc
		(start 91.382659 95.983699)
		(mid 91.552364 95.913405)
		(end 91.72207 95.983699)
		(width 0.19)
		(layer "B.Cu")
		(net 733)
	)
	(arc
		(start 91.018748 96.008199)
		(mid 91.188454 96.078494)
		(end 91.35816 96.008199)
		(width 0.19)
		(layer "B.Cu")
		(net 733)
	)
	(arc
		(start 90.933896 95.583936)
		(mid 90.863602 95.753641)
		(end 90.933896 95.923347)
		(width 0.19)
		(layer "B.Cu")
		(net 733)
	)
	(arc
		(start 90.958396 95.220026)
		(mid 91.02869 95.389732)
		(end 90.958396 95.559437)
		(width 0.19)
		(layer "B.Cu")
		(net 733)
	)
	(segment
		(start 84.92337 98.785)
		(end 83.67337 97.535)
		(width 0.19)
		(layer "F.Cu")
		(net 736)
	)
	(segment
		(start 80.065 93.82337)
		(end 80.52337 93.365)
		(width 0.19)
		(layer "F.Cu")
		(net 736)
	)
	(segment
		(start 83.67337 97.535)
		(end 81.72337 97.535)
		(width 0.19)
		(layer "F.Cu")
		(net 736)
	)
	(segment
		(start 87.22663 97.985)
		(end 86.42663 98.785)
		(width 0.19)
		(layer "F.Cu")
		(net 736)
	)
	(segment
		(start 80.065 94.77663)
		(end 80.065 93.82337)
		(width 0.19)
		(layer "F.Cu")
		(net 736)
	)
	(segment
		(start 81.72337 97.535)
		(end 81.165 96.97663)
		(width 0.19)
		(layer "F.Cu")
		(net 736)
	)
	(segment
		(start 81.165 95.87663)
		(end 80.065 94.77663)
		(width 0.19)
		(layer "F.Cu")
		(net 736)
	)
	(segment
		(start 90.28 97.985)
		(end 87.22663 97.985)
		(width 0.19)
		(layer "F.Cu")
		(net 736)
	)
	(segment
		(start 90.595 98.3)
		(end 90.28 97.985)
		(width 0.19)
		(layer "F.Cu")
		(net 736)
	)
	(segment
		(start 90.62 98.3)
		(end 90.595 98.3)
		(width 0.19)
		(layer "F.Cu")
		(net 736)
	)
	(segment
		(start 86.42663 98.785)
		(end 84.92337 98.785)
		(width 0.19)
		(layer "F.Cu")
		(net 736)
	)
	(segment
		(start 81.165 96.97663)
		(end 81.165 95.87663)
		(width 0.19)
		(layer "F.Cu")
		(net 736)
	)
	(segment
		(start 80.52337 93.365)
		(end 81.675532 93.365)
		(width 0.19)
		(layer "F.Cu")
		(net 736)
	)
	(segment
		(start 81.675532 93.365)
		(end 82.125532 92.915)
		(width 0.19)
		(layer "F.Cu")
		(net 736)
	)
	(via
		(at 82.125532 92.915)
		(size 0.45)
		(drill 0.1)
		(layers "F.Cu" "B.Cu")
		(net 736)
	)
	(segment
		(start 88.615 90.45)
		(end 88.325 90.74)
		(width 0.19)
		(layer "F.Cu")
		(net 737)
	)
	(segment
		(start 88.64 90.45)
		(end 88.615 90.45)
		(width 0.19)
		(layer "F.Cu")
		(net 737)
	)
	(segment
		(start 86.00663 85.745)
		(end 83.845532 85.745)
		(width 0.19)
		(layer "F.Cu")
		(net 737)
	)
	(segment
		(start 87.085 90.12337)
		(end 87.085 86.82337)
		(width 0.19)
		(layer "F.Cu")
		(net 737)
	)
	(segment
		(start 88.325 90.74)
		(end 87.70163 90.74)
		(width 0.19)
		(layer "F.Cu")
		(net 737)
	)
	(segment
		(start 87.085 86.82337)
		(end 86.00663 85.745)
		(width 0.19)
		(layer "F.Cu")
		(net 737)
	)
	(segment
		(start 83.845532 85.745)
		(end 83.395532 85.295)
		(width 0.19)
		(layer "F.Cu")
		(net 737)
	)
	(segment
		(start 87.70163 90.74)
		(end 87.085 90.12337)
		(width 0.19)
		(layer "F.Cu")
		(net 737)
	)
	(via
		(at 83.395532 85.295)
		(size 0.45)
		(drill 0.1)
		(layers "F.Cu" "B.Cu")
		(net 737)
	)
	(segment
		(start 92.12337 91.185)
		(end 94.815 93.87663)
		(width 0.19)
		(layer "B.Cu")
		(net 738)
	)
	(segment
		(start 86.385532 91.195)
		(end 86.79 91.195)
		(width 0.19)
		(layer "B.Cu")
		(net 738)
	)
	(segment
		(start 94.815 97.09333)
		(end 94.815 101.47663)
		(width 0.19)
		(layer "B.Cu")
		(net 738)
	)
	(segment
		(start 86.8 91.185)
		(end 92.12337 91.185)
		(width 0.19)
		(layer "B.Cu")
		(net 738)
	)
	(segment
		(start 85.935532 91.645)
		(end 86.385532 91.195)
		(width 0.19)
		(layer "B.Cu")
		(net 738)
	)
	(segment
		(start 94.815 101.47663)
		(end 95.995 102.65663)
		(width 0.19)
		(layer "B.Cu")
		(net 738)
	)
	(segment
		(start 94.815 95.47422)
		(end 94.815 97.09333)
		(width 0.19)
		(layer "B.Cu")
		(net 738)
	)
	(segment
		(start 94.30244 94.75422)
		(end 94.30244 94.87422)
		(width 0.19)
		(layer "B.Cu")
		(net 738)
	)
	(segment
		(start 95.995 102.65663)
		(end 95.995 104.69)
		(width 0.19)
		(layer "B.Cu")
		(net 738)
	)
	(segment
		(start 94.54244 95.11422)
		(end 94.575 95.11422)
		(width 0.19)
		(layer "B.Cu")
		(net 738)
	)
	(segment
		(start 95.995 104.69)
		(end 95.68 105.005)
		(width 0.19)
		(layer "B.Cu")
		(net 738)
	)
	(segment
		(start 86.79 91.195)
		(end 86.8 91.185)
		(width 0.19)
		(layer "B.Cu")
		(net 738)
	)
	(segment
		(start 94.575 94.51422)
		(end 94.54244 94.51422)
		(width 0.19)
		(layer "B.Cu")
		(net 738)
	)
	(segment
		(start 94.815 95.35422)
		(end 94.815 95.47422)
		(width 0.19)
		(layer "B.Cu")
		(net 738)
	)
	(segment
		(start 94.815 93.87663)
		(end 94.815 94.27422)
		(width 0.19)
		(layer "B.Cu")
		(net 738)
	)
	(segment
		(start 95.68 105.005)
		(end 95.68 105.03)
		(width 0.19)
		(layer "B.Cu")
		(net 738)
	)
	(arc
		(start 94.54244 94.51422)
		(mid 94.372734 94.584514)
		(end 94.30244 94.75422)
		(width 0.19)
		(layer "B.Cu")
		(net 738)
	)
	(arc
		(start 94.30244 94.87422)
		(mid 94.372734 95.043926)
		(end 94.54244 95.11422)
		(width 0.19)
		(layer "B.Cu")
		(net 738)
	)
	(arc
		(start 94.575 95.11422)
		(mid 94.744706 95.184514)
		(end 94.815 95.35422)
		(width 0.19)
		(layer "B.Cu")
		(net 738)
	)
	(arc
		(start 94.815 94.27422)
		(mid 94.744706 94.443926)
		(end 94.575 94.51422)
		(width 0.19)
		(layer "B.Cu")
		(net 738)
	)
	(segment
		(start 89.930532 76.65)
		(end 89.95 76.65)
		(width 0.1)
		(layer "F.Cu")
		(net 739)
	)
	(via
		(at 89.95 76.65)
		(size 0.45)
		(drill 0.1)
		(layers "F.Cu" "B.Cu")
		(net 739)
	)
	(segment
		(start 140.430532 70.65)
		(end 140.430532 71.219468)
		(width 0.1)
		(layer "F.Cu")
		(net 741)
	)
	(segment
		(start 140.430532 71.219468)
		(end 140.35 71.3)
		(width 0.1)
		(layer "F.Cu")
		(net 741)
	)
	(via
		(at 140.35 71.3)
		(size 0.45)
		(drill 0.1)
		(layers "F.Cu" "B.Cu")
		(net 741)
	)
	(segment
		(start 86.51663 95.905)
		(end 83.845532 95.905)
		(width 0.19)
		(layer "F.Cu")
		(net 742)
	)
	(segment
		(start 88.595 95.9)
		(end 88.28 96.215)
		(width 0.19)
		(layer "F.Cu")
		(net 742)
	)
	(segment
		(start 88.62 95.9)
		(end 88.595 95.9)
		(width 0.19)
		(layer "F.Cu")
		(net 742)
	)
	(segment
		(start 88.28 96.215)
		(end 86.82663 96.215)
		(width 0.19)
		(layer "F.Cu")
		(net 742)
	)
	(segment
		(start 86.82663 96.215)
		(end 86.51663 95.905)
		(width 0.19)
		(layer "F.Cu")
		(net 742)
	)
	(segment
		(start 83.845532 95.905)
		(end 83.395532 95.455)
		(width 0.19)
		(layer "F.Cu")
		(net 742)
	)
	(via
		(at 83.395532 95.455)
		(size 0.45)
		(drill 0.1)
		(layers "F.Cu" "B.Cu")
		(net 742)
	)
	(segment
		(start 154.75 76.65)
		(end 154.75 69)
		(width 0.1)
		(layer "F.Cu")
		(net 743)
	)
	(segment
		(start 144.55 86.9)
		(end 143 86.9)
		(width 0.1)
		(layer "F.Cu")
		(net 743)
	)
	(segment
		(start 152.9 82.475)
		(end 152.9 78.5)
		(width 0.1)
		(layer "F.Cu")
		(net 743)
	)
	(segment
		(start 142.230532 86.130532)
		(end 142.230532 85.65)
		(width 0.1)
		(layer "F.Cu")
		(net 743)
	)
	(segment
		(start 143 86.9)
		(end 142.230532 86.130532)
		(width 0.1)
		(layer "F.Cu")
		(net 743)
	)
	(segment
		(start 156.45 86.025)
		(end 152.9 82.475)
		(width 0.1)
		(layer "F.Cu")
		(net 743)
	)
	(segment
		(start 156.45 86.925)
		(end 156.45 86.025)
		(width 0.1)
		(layer "F.Cu")
		(net 743)
	)
	(segment
		(start 152.9 78.5)
		(end 154.75 76.65)
		(width 0.1)
		(layer "F.Cu")
		(net 743)
	)
	(via
		(at 154.75 69)
		(size 0.45)
		(drill 0.1)
		(layers "F.Cu" "B.Cu")
		(net 743)
	)
	(via
		(at 144.55 86.9)
		(size 0.45)
		(drill 0.1)
		(layers "F.Cu" "B.Cu")
		(net 743)
	)
	(via
		(at 156.45 86.925)
		(size 0.45)
		(drill 0.1)
		(layers "F.Cu" "B.Cu")
		(net 743)
	)
	(segment
		(start 154.75 68)
		(end 154.75 69)
		(width 0.1)
		(layer "B.Cu")
		(net 743)
	)
	(segment
		(start 156.67 67.53)
		(end 155.22 67.53)
		(width 0.1)
		(layer "B.Cu")
		(net 743)
	)
	(segment
		(start 155.22 67.53)
		(end 154.75 68)
		(width 0.1)
		(layer "B.Cu")
		(net 743)
	)
	(segment
		(start 156.05 87.325)
		(end 156.45 86.925)
		(width 0.1)
		(layer "In2.Cu")
		(net 743)
	)
	(segment
		(start 144.975 87.325)
		(end 156.05 87.325)
		(width 0.1)
		(layer "In2.Cu")
		(net 743)
	)
	(segment
		(start 144.55 86.9)
		(end 144.975 87.325)
		(width 0.1)
		(layer "In2.Cu")
		(net 743)
	)
	(segment
		(start 88.62 93.1)
		(end 88.595 93.1)
		(width 0.19)
		(layer "F.Cu")
		(net 744)
	)
	(segment
		(start 83.845532 90.825)
		(end 83.395532 90.375)
		(width 0.19)
		(layer "F.Cu")
		(net 744)
	)
	(segment
		(start 85.77663 93.415)
		(end 85.485 93.12337)
		(width 0.19)
		(layer "F.Cu")
		(net 744)
	)
	(segment
		(start 85.485 91.27337)
		(end 85.02663 90.815)
		(width 0.19)
		(layer "F.Cu")
		(net 744)
	)
	(segment
		(start 84.298408 90.825)
		(end 83.845532 90.825)
		(width 0.19)
		(layer "F.Cu")
		(net 744)
	)
	(segment
		(start 85.485 93.12337)
		(end 85.485 91.27337)
		(width 0.19)
		(layer "F.Cu")
		(net 744)
	)
	(segment
		(start 85.02663 90.815)
		(end 84.308408 90.815)
		(width 0.19)
		(layer "F.Cu")
		(net 744)
	)
	(segment
		(start 84.308408 90.815)
		(end 84.298408 90.825)
		(width 0.19)
		(layer "F.Cu")
		(net 744)
	)
	(segment
		(start 88.28 93.415)
		(end 85.77663 93.415)
		(width 0.19)
		(layer "F.Cu")
		(net 744)
	)
	(segment
		(start 88.595 93.1)
		(end 88.28 93.415)
		(width 0.19)
		(layer "F.Cu")
		(net 744)
	)
	(via
		(at 83.395532 90.375)
		(size 0.45)
		(drill 0.1)
		(layers "F.Cu" "B.Cu")
		(net 744)
	)
	(segment
		(start 205.93 91.785856)
		(end 203.315 91.785856)
		(width 0.19)
		(layer "F.Cu")
		(net 746)
	)
	(segment
		(start 206.27 91.470856)
		(end 206.245 91.470856)
		(width 0.19)
		(layer "F.Cu")
		(net 746)
	)
	(segment
		(start 203.315 91.785856)
		(end 203.2 91.670856)
		(width 0.19)
		(layer "F.Cu")
		(net 746)
	)
	(segment
		(start 206.245 91.470856)
		(end 205.93 91.785856)
		(width 0.19)
		(layer "F.Cu")
		(net 746)
	)
	(via
		(at 134.130532 82.65)
		(size 0.45)
		(drill 0.1)
		(layers "F.Cu" "B.Cu")
		(net 746)
	)
	(via
		(at 203.2 91.670856)
		(size 0.45)
		(drill 0.1)
		(layers "F.Cu" "B.Cu")
		(net 746)
	)
	(segment
		(start 131.942636 85.183677)
		(end 131.8975 85.183677)
		(width 0.15)
		(layer "In7.Cu")
		(net 746)
	)
	(segment
		(start 131.7375 85.843044)
		(end 133.556956 87.6625)
		(width 0.15)
		(layer "In7.Cu")
		(net 746)
	)
	(segment
		(start 134.130532 82.65)
		(end 133.818032 82.9625)
		(width 0.15)
		(layer "In7.Cu")
		(net 746)
	)
	(segment
		(start 133.818032 83.076424)
		(end 133.356956 83.5375)
		(width 0.15)
		(layer "In7.Cu")
		(net 746)
	)
	(segment
		(start 131.7375 85.343677)
		(end 131.7375 85.843044)
		(width 0.15)
		(layer "In7.Cu")
		(net 746)
	)
	(segment
		(start 141.127812 91.833356)
		(end 203.0375 91.833356)
		(width 0.15)
		(layer "In7.Cu")
		(net 746)
	)
	(segment
		(start 131.7375 84.256956)
		(end 131.7375 84.623677)
		(width 0.15)
		(layer "In7.Cu")
		(net 746)
	)
	(segment
		(start 132.102636 84.943677)
		(end 132.102636 85.023677)
		(width 0.15)
		(layer "In7.Cu")
		(net 746)
	)
	(segment
		(start 133.818032 82.9625)
		(end 133.818032 83.076424)
		(width 0.15)
		(layer "In7.Cu")
		(net 746)
	)
	(segment
		(start 203.0375 91.833356)
		(end 203.2 91.670856)
		(width 0.15)
		(layer "In7.Cu")
		(net 746)
	)
	(segment
		(start 131.8975 84.783677)
		(end 131.942636 84.783677)
		(width 0.15)
		(layer "In7.Cu")
		(net 746)
	)
	(segment
		(start 133.356956 83.5375)
		(end 132.456956 83.5375)
		(width 0.15)
		(layer "In7.Cu")
		(net 746)
	)
	(segment
		(start 132.456956 83.5375)
		(end 131.7375 84.256956)
		(width 0.15)
		(layer "In7.Cu")
		(net 746)
	)
	(segment
		(start 133.556956 87.6625)
		(end 136.956956 87.6625)
		(width 0.15)
		(layer "In7.Cu")
		(net 746)
	)
	(segment
		(start 136.956956 87.6625)
		(end 141.127812 91.833356)
		(width 0.15)
		(layer "In7.Cu")
		(net 746)
	)
	(arc
		(start 131.942636 84.783677)
		(mid 132.055773 84.83054)
		(end 132.102636 84.943677)
		(width 0.15)
		(layer "In7.Cu")
		(net 746)
	)
	(arc
		(start 131.7375 84.623677)
		(mid 131.784363 84.736814)
		(end 131.8975 84.783677)
		(width 0.15)
		(layer "In7.Cu")
		(net 746)
	)
	(arc
		(start 132.102636 85.023677)
		(mid 132.055773 85.136814)
		(end 131.942636 85.183677)
		(width 0.15)
		(layer "In7.Cu")
		(net 746)
	)
	(arc
		(start 131.8975 85.183677)
		(mid 131.784363 85.23054)
		(end 131.7375 85.343677)
		(width 0.15)
		(layer "In7.Cu")
		(net 746)
	)
	(segment
		(start 104.06 70.1)
		(end 103.880532 70.1)
		(width 0.1)
		(layer "F.Cu")
		(net 751)
	)
	(segment
		(start 103.880532 70.1)
		(end 103.330532 70.65)
		(width 0.1)
		(layer "F.Cu")
		(net 751)
	)
	(segment
		(start 127.95 89.25)
		(end 128.45 89.75)
		(width 0.1)
		(layer "F.Cu")
		(net 751)
	)
	(segment
		(start 127.95 87.05)
		(end 127.95 89.25)
		(width 0.1)
		(layer "F.Cu")
		(net 751)
	)
	(via
		(at 127.95 87.05)
		(size 0.45)
		(drill 0.1)
		(layers "F.Cu" "B.Cu")
		(net 751)
	)
	(via
		(at 126 107.8)
		(size 0.45)
		(drill 0.1)
		(layers "F.Cu" "B.Cu")
		(net 751)
	)
	(via
		(at 104.06 70.1)
		(size 0.45)
		(drill 0.1)
		(layers "F.Cu" "B.Cu")
		(net 751)
	)
	(via
		(at 128.45 89.75)
		(size 0.45)
		(drill 0.1)
		(layers "F.Cu" "B.Cu")
		(net 751)
	)
	(segment
		(start 125.08 107.8)
		(end 126 107.8)
		(width 0.1)
		(layer "B.Cu")
		(net 751)
	)
	(segment
		(start 128.85 82.45)
		(end 128.85 84.5)
		(width 0.1)
		(layer "In4.Cu")
		(net 751)
	)
	(segment
		(start 130.1 73.432846)
		(end 130.1 74.25)
		(width 0.1)
		(layer "In4.Cu")
		(net 751)
	)
	(segment
		(start 129.567157 68.782841)
		(end 130.117159 69.332843)
		(width 0.1)
		(layer "In4.Cu")
		(net 751)
	)
	(segment
		(start 128.25 85.1)
		(end 128.25 86.75)
		(width 0.1)
		(layer "In4.Cu")
		(net 751)
	)
	(segment
		(start 108.668634 69.6)
		(end 108.968634 69.9)
		(width 0.1)
		(layer "In4.Cu")
		(net 751)
	)
	(segment
		(start 104.06 70.1)
		(end 104.2 70.1)
		(width 0.1)
		(layer "In4.Cu")
		(net 751)
	)
	(segment
		(start 129.1 81.3)
		(end 129.1 82.2)
		(width 0.1)
		(layer "In4.Cu")
		(net 751)
	)
	(segment
		(start 128.45 80.65)
		(end 129.1 81.3)
		(width 0.1)
		(layer "In4.Cu")
		(net 751)
	)
	(segment
		(start 129.3625 72.695346)
		(end 130.1 73.432846)
		(width 0.1)
		(layer "In4.Cu")
		(net 751)
	)
	(segment
		(start 128.85 84.5)
		(end 128.25 85.1)
		(width 0.1)
		(layer "In4.Cu")
		(net 751)
	)
	(segment
		(start 122.532843 69.732841)
		(end 127.882843 69.732841)
		(width 0.1)
		(layer "In4.Cu")
		(net 751)
	)
	(segment
		(start 129.2 79.2)
		(end 128.45 79.95)
		(width 0.1)
		(layer "In4.Cu")
		(net 751)
	)
	(segment
		(start 105.3 70.3)
		(end 106 69.6)
		(width 0.1)
		(layer "In4.Cu")
		(net 751)
	)
	(segment
		(start 104.2 70.1)
		(end 104.4 70.3)
		(width 0.1)
		(layer "In4.Cu")
		(net 751)
	)
	(segment
		(start 104.4 70.3)
		(end 105.3 70.3)
		(width 0.1)
		(layer "In4.Cu")
		(net 751)
	)
	(segment
		(start 122.365684 69.9)
		(end 122.532843 69.732841)
		(width 0.1)
		(layer "In4.Cu")
		(net 751)
	)
	(segment
		(start 106 69.6)
		(end 108.668634 69.6)
		(width 0.1)
		(layer "In4.Cu")
		(net 751)
	)
	(segment
		(start 130.117159 70.932841)
		(end 129.3625 71.6875)
		(width 0.1)
		(layer "In4.Cu")
		(net 751)
	)
	(segment
		(start 128.45 79.95)
		(end 128.45 80.65)
		(width 0.1)
		(layer "In4.Cu")
		(net 751)
	)
	(segment
		(start 108.968634 69.9)
		(end 122.365684 69.9)
		(width 0.1)
		(layer "In4.Cu")
		(net 751)
	)
	(segment
		(start 128.832843 68.782841)
		(end 129.567157 68.782841)
		(width 0.1)
		(layer "In4.Cu")
		(net 751)
	)
	(segment
		(start 129.3625 71.6875)
		(end 129.3625 72.695346)
		(width 0.1)
		(layer "In4.Cu")
		(net 751)
	)
	(segment
		(start 130.1 74.25)
		(end 129.2 75.15)
		(width 0.1)
		(layer "In4.Cu")
		(net 751)
	)
	(segment
		(start 129.2 75.15)
		(end 129.2 79.2)
		(width 0.1)
		(layer "In4.Cu")
		(net 751)
	)
	(segment
		(start 127.882843 69.732841)
		(end 128.832843 68.782841)
		(width 0.1)
		(layer "In4.Cu")
		(net 751)
	)
	(segment
		(start 129.1 82.2)
		(end 128.85 82.45)
		(width 0.1)
		(layer "In4.Cu")
		(net 751)
	)
	(segment
		(start 130.117159 69.332843)
		(end 130.117159 70.932841)
		(width 0.1)
		(layer "In4.Cu")
		(net 751)
	)
	(segment
		(start 128.25 86.75)
		(end 127.95 87.05)
		(width 0.1)
		(layer "In4.Cu")
		(net 751)
	)
	(segment
		(start 127.2 107.8)
		(end 130.6 104.4)
		(width 0.1)
		(layer "In7.Cu")
		(net 751)
	)
	(segment
		(start 130.6 91.9)
		(end 128.45 89.75)
		(width 0.1)
		(layer "In7.Cu")
		(net 751)
	)
	(segment
		(start 130.6 104.4)
		(end 130.6 91.9)
		(width 0.1)
		(layer "In7.Cu")
		(net 751)
	)
	(segment
		(start 126 107.8)
		(end 127.2 107.8)
		(width 0.1)
		(layer "In7.Cu")
		(net 751)
	)
	(segment
		(start 97.065532 84.985)
		(end 97.180532 85.1)
		(width 0.19)
		(layer "F.Cu")
		(net 752)
	)
	(segment
		(start 97.065532 84.415)
		(end 97.065532 84.985)
		(width 0.19)
		(layer "F.Cu")
		(net 752)
	)
	(segment
		(start 97.330532 84.15)
		(end 97.065532 84.415)
		(width 0.19)
		(layer "F.Cu")
		(net 752)
	)
	(via
		(at 97.180532 85.1)
		(size 0.45)
		(drill 0.1)
		(layers "F.Cu" "B.Cu")
		(net 752)
	)
	(segment
		(start 97.065532 98.246098)
		(end 97.065532 85.215)
		(width 0.19)
		(layer "B.Cu")
		(net 752)
	)
	(segment
		(start 97.585 102.12337)
		(end 96.335 100.87337)
		(width 0.19)
		(layer "B.Cu")
		(net 752)
	)
	(segment
		(start 90.52337 114.985)
		(end 95.27663 114.985)
		(width 0.19)
		(layer "B.Cu")
		(net 752)
	)
	(segment
		(start 96.335 100.87337)
		(end 96.335 98.97663)
		(width 0.19)
		(layer "B.Cu")
		(net 752)
	)
	(segment
		(start 97.065532 85.215)
		(end 97.180532 85.1)
		(width 0.19)
		(layer "B.Cu")
		(net 752)
	)
	(segment
		(start 87.05337 111.515)
		(end 90.52337 114.985)
		(width 0.19)
		(layer "B.Cu")
		(net 752)
	)
	(segment
		(start 99.185 111.07663)
		(end 99.185 104.72337)
		(width 0.19)
		(layer "B.Cu")
		(net 752)
	)
	(segment
		(start 95.27663 114.985)
		(end 99.185 111.07663)
		(width 0.19)
		(layer "B.Cu")
		(net 752)
	)
	(segment
		(start 97.585 103.12337)
		(end 97.585 102.12337)
		(width 0.19)
		(layer "B.Cu")
		(net 752)
	)
	(segment
		(start 96.335 98.97663)
		(end 97.065532 98.246098)
		(width 0.19)
		(layer "B.Cu")
		(net 752)
	)
	(segment
		(start 85.935532 111.965)
		(end 86.385532 111.515)
		(width 0.19)
		(layer "B.Cu")
		(net 752)
	)
	(segment
		(start 99.185 104.72337)
		(end 97.585 103.12337)
		(width 0.19)
		(layer "B.Cu")
		(net 752)
	)
	(segment
		(start 86.385532 111.515)
		(end 87.05337 111.515)
		(width 0.19)
		(layer "B.Cu")
		(net 752)
	)
	(segment
		(start 69.8 74.8)
		(end 63 74.8)
		(width 0.1)
		(layer "B.Cu")
		(net 753)
	)
	(segment
		(start 71.965532 76.965532)
		(end 69.8 74.8)
		(width 0.1)
		(layer "B.Cu")
		(net 753)
	)
	(segment
		(start 71.965532 78.945)
		(end 71.965532 76.965532)
		(width 0.1)
		(layer "B.Cu")
		(net 753)
	)
	(segment
		(start 88.62 96.9)
		(end 88.595 96.9)
		(width 0.19)
		(layer "F.Cu")
		(net 756)
	)
	(segment
		(start 83.845532 96.275)
		(end 83.395532 96.725)
		(width 0.19)
		(layer "F.Cu")
		(net 756)
	)
	(segment
		(start 88.595 96.9)
		(end 88.28 96.585)
		(width 0.19)
		(layer "F.Cu")
		(net 756)
	)
	(segment
		(start 86.36337 96.275)
		(end 83.845532 96.275)
		(width 0.19)
		(layer "F.Cu")
		(net 756)
	)
	(segment
		(start 86.67337 96.585)
		(end 86.36337 96.275)
		(width 0.19)
		(layer "F.Cu")
		(net 756)
	)
	(segment
		(start 88.28 96.585)
		(end 86.67337 96.585)
		(width 0.19)
		(layer "F.Cu")
		(net 756)
	)
	(via
		(at 83.395532 96.725)
		(size 0.45)
		(drill 0.1)
		(layers "F.Cu" "B.Cu")
		(net 756)
	)
	(via
		(at 142.430532 75.15)
		(size 0.45)
		(drill 0.1)
		(layers "F.Cu" "B.Cu")
		(net 758)
	)
	(segment
		(start 142.430532 75.15)
		(end 142.430532 75.41)
		(width 0.1)
		(layer "B.Cu")
		(net 758)
	)
	(segment
		(start 142.430532 75.41)
		(end 142.830532 75.81)
		(width 0.1)
		(layer "B.Cu")
		(net 758)
	)
	(segment
		(start 141.330532 70.730532)
		(end 141.330532 70.65)
		(width 0.1)
		(layer "F.Cu")
		(net 760)
	)
	(segment
		(start 141.8 71.17)
		(end 141.77 71.17)
		(width 0.1)
		(layer "F.Cu")
		(net 760)
	)
	(segment
		(start 141.77 71.17)
		(end 141.330532 70.730532)
		(width 0.1)
		(layer "F.Cu")
		(net 760)
	)
	(via
		(at 141.8 71.17)
		(size 0.45)
		(drill 0.1)
		(layers "F.Cu" "B.Cu")
		(net 760)
	)
	(segment
		(start 74.5 79.28)
		(end 74.5 80.2)
		(width 0.1)
		(layer "F.Cu")
		(net 761)
	)
	(via
		(at 74.5 80.2)
		(size 0.45)
		(drill 0.1)
		(layers "F.Cu" "B.Cu")
		(net 761)
	)
	(segment
		(start 74.505532 80.215)
		(end 74.505532 80.205532)
		(width 0.1)
		(layer "B.Cu")
		(net 761)
	)
	(segment
		(start 74.505532 80.205532)
		(end 74.5 80.2)
		(width 0.1)
		(layer "B.Cu")
		(net 761)
	)
	(segment
		(start 140 75.75)
		(end 140 77)
		(width 0.1)
		(layer "F.Cu")
		(net 762)
	)
	(segment
		(start 142.925 84.475)
		(end 142.925 83.4)
		(width 0.1)
		(layer "F.Cu")
		(net 762)
	)
	(segment
		(start 142.5 77.35)
		(end 142.9 77.75)
		(width 0.1)
		(layer "F.Cu")
		(net 762)
	)
	(segment
		(start 127.4 74)
		(end 127.9 74.5)
		(width 0.1)
		(layer "F.Cu")
		(net 762)
	)
	(segment
		(start 127.9 74.5)
		(end 140.05 74.5)
		(width 0.1)
		(layer "F.Cu")
		(net 762)
	)
	(segment
		(start 142.9 78.4)
		(end 142.7 78.6)
		(width 0.1)
		(layer "F.Cu")
		(net 762)
	)
	(segment
		(start 127.4 72.65)
		(end 127.4 74)
		(width 0.1)
		(layer "F.Cu")
		(net 762)
	)
	(segment
		(start 140.15 74.6)
		(end 140.15 75.6)
		(width 0.1)
		(layer "F.Cu")
		(net 762)
	)
	(segment
		(start 123.75 71.5)
		(end 123.9 71.35)
		(width 0.1)
		(layer "F.Cu")
		(net 762)
	)
	(segment
		(start 140.05 74.5)
		(end 140.15 74.6)
		(width 0.1)
		(layer "F.Cu")
		(net 762)
	)
	(segment
		(start 142.65 81.85)
		(end 142.65 83.125)
		(width 0.1)
		(layer "F.Cu")
		(net 762)
	)
	(segment
		(start 142.9 81.6)
		(end 142.65 81.85)
		(width 0.1)
		(layer "F.Cu")
		(net 762)
	)
	(segment
		(start 142.7 78.6)
		(end 142.7 80.05)
		(width 0.1)
		(layer "F.Cu")
		(net 762)
	)
	(segment
		(start 140 77)
		(end 140.35 77.35)
		(width 0.1)
		(layer "F.Cu")
		(net 762)
	)
	(segment
		(start 142.9 77.75)
		(end 142.9 78.4)
		(width 0.1)
		(layer "F.Cu")
		(net 762)
	)
	(segment
		(start 127.2 71.35)
		(end 127.55 71.7)
		(width 0.1)
		(layer "F.Cu")
		(net 762)
	)
	(segment
		(start 143.130532 84.680532)
		(end 142.925 84.475)
		(width 0.1)
		(layer "F.Cu")
		(net 762)
	)
	(segment
		(start 142.65 83.125)
		(end 142.925 83.4)
		(width 0.1)
		(layer "F.Cu")
		(net 762)
	)
	(segment
		(start 142.9 80.25)
		(end 142.9 81.6)
		(width 0.1)
		(layer "F.Cu")
		(net 762)
	)
	(segment
		(start 140.15 75.6)
		(end 140 75.75)
		(width 0.1)
		(layer "F.Cu")
		(net 762)
	)
	(segment
		(start 127.55 71.7)
		(end 127.55 72.5)
		(width 0.1)
		(layer "F.Cu")
		(net 762)
	)
	(segment
		(start 143.130532 85.65)
		(end 143.130532 84.680532)
		(width 0.1)
		(layer "F.Cu")
		(net 762)
	)
	(segment
		(start 127.55 72.5)
		(end 127.4 72.65)
		(width 0.1)
		(layer "F.Cu")
		(net 762)
	)
	(segment
		(start 140.35 77.35)
		(end 142.5 77.35)
		(width 0.1)
		(layer "F.Cu")
		(net 762)
	)
	(segment
		(start 142.7 80.05)
		(end 142.9 80.25)
		(width 0.1)
		(layer "F.Cu")
		(net 762)
	)
	(segment
		(start 123.9 71.35)
		(end 127.2 71.35)
		(width 0.1)
		(layer "F.Cu")
		(net 762)
	)
	(via
		(at 123.75 71.5)
		(size 0.45)
		(drill 0.1)
		(layers "F.Cu" "B.Cu")
		(net 762)
	)
	(segment
		(start 124.5 72.25)
		(end 123.75 71.5)
		(width 0.1)
		(layer "B.Cu")
		(net 762)
	)
	(segment
		(start 124.5 72.6)
		(end 124.5 72.25)
		(width 0.1)
		(layer "B.Cu")
		(net 762)
	)
	(segment
		(start 221.754 101.36)
		(end 222.166501 101.36)
		(width 0.17)
		(layer "F.Cu")
		(net 766)
	)
	(segment
		(start 220.982 101.36)
		(end 221.754 101.36)
		(width 0.17)
		(layer "F.Cu")
		(net 766)
	)
	(segment
		(start 222.166501 101.36)
		(end 222.241501 101.435)
		(width 0.17)
		(layer "F.Cu")
		(net 766)
	)
	(segment
		(start 96.705532 77.875)
		(end 96.705532 77.625)
		(width 0.17)
		(layer "F.Cu")
		(net 766)
	)
	(segment
		(start 222.241501 101.435)
		(end 222.675 101.435)
		(width 0.17)
		(layer "F.Cu")
		(net 766)
	)
	(segment
		(start 220.569499 101.36)
		(end 220.494499 101.435)
		(width 0.17)
		(layer "F.Cu")
		(net 766)
	)
	(segment
		(start 96.705532 77.625)
		(end 96.580532 77.5)
		(width 0.17)
		(layer "F.Cu")
		(net 766)
	)
	(segment
		(start 232.430532 101.0725)
		(end 232.430532 102.110532)
		(width 0.17)
		(layer "F.Cu")
		(net 766)
	)
	(segment
		(start 220.494499 101.435)
		(end 220.225 101.435)
		(width 0.17)
		(layer "F.Cu")
		(net 766)
	)
	(segment
		(start 232.930532 103.3475)
		(end 232.930532 104.460532)
		(width 0.17)
		(layer "F.Cu")
		(net 766)
	)
	(segment
		(start 232.930532 102.610532)
		(end 232.930532 103.3475)
		(width 0.17)
		(layer "F.Cu")
		(net 766)
	)
	(segment
		(start 232.930532 104.460532)
		(end 232.97 104.5)
		(width 0.17)
		(layer "F.Cu")
		(net 766)
	)
	(segment
		(start 220.225 101.435)
		(end 220.1 101.31)
		(width 0.17)
		(layer "F.Cu")
		(net 766)
	)
	(segment
		(start 222.675 101.435)
		(end 222.8 101.31)
		(width 0.17)
		(layer "F.Cu")
		(net 766)
	)
	(segment
		(start 232.430532 102.110532)
		(end 232.930532 102.610532)
		(width 0.17)
		(layer "F.Cu")
		(net 766)
	)
	(segment
		(start 220.982 101.36)
		(end 220.569499 101.36)
		(width 0.17)
		(layer "F.Cu")
		(net 766)
	)
	(segment
		(start 96.430532 78.15)
		(end 96.705532 77.875)
		(width 0.17)
		(layer "F.Cu")
		(net 766)
	)
	(via
		(at 222.8 101.31)
		(size 0.45)
		(drill 0.1)
		(layers "F.Cu" "B.Cu")
		(net 766)
	)
	(via
		(at 232.97 104.5)
		(size 0.45)
		(drill 0.1)
		(layers "F.Cu" "B.Cu")
		(net 766)
	)
	(via
		(at 220.1 101.31)
		(size 0.45)
		(drill 0.1)
		(layers "F.Cu" "B.Cu")
		(net 766)
	)
	(via
		(at 96.580532 77.5)
		(size 0.45)
		(drill 0.1)
		(layers "F.Cu" "B.Cu")
		(net 766)
	)
	(via
		(at 100.4875 69.35)
		(size 0.45)
		(drill 0.1)
		(layers "F.Cu" "B.Cu")
		(net 766)
	)
	(segment
		(start 97.377512 79.025)
		(end 98.522488 79.025)
		(width 0.17)
		(layer "B.Cu")
		(net 766)
	)
	(segment
		(start 99.025 77.172488)
		(end 101.085 75.112488)
		(width 0.17)
		(layer "B.Cu")
		(net 766)
	)
	(segment
		(start 96.580532 77.5)
		(end 96.705532 77.625)
		(width 0.17)
		(layer "B.Cu")
		(net 766)
	)
	(segment
		(start 100.375 69.4625)
		(end 100.4875 69.35)
		(width 0.17)
		(layer "B.Cu")
		(net 766)
	)
	(segment
		(start 101.085 75.112488)
		(end 101.085 70.387512)
		(width 0.17)
		(layer "B.Cu")
		(net 766)
	)
	(segment
		(start 96.705532 78.35302)
		(end 97.377512 79.025)
		(width 0.17)
		(layer "B.Cu")
		(net 766)
	)
	(segment
		(start 98.522488 79.025)
		(end 99.025 78.522488)
		(width 0.17)
		(layer "B.Cu")
		(net 766)
	)
	(segment
		(start 99.025 78.522488)
		(end 99.025 77.172488)
		(width 0.17)
		(layer "B.Cu")
		(net 766)
	)
	(segment
		(start 100.375 69.677512)
		(end 100.375 69.4625)
		(width 0.17)
		(layer "B.Cu")
		(net 766)
	)
	(segment
		(start 96.705532 77.625)
		(end 96.705532 78.35302)
		(width 0.17)
		(layer "B.Cu")
		(net 766)
	)
	(segment
		(start 101.085 70.387512)
		(end 100.375 69.677512)
		(width 0.17)
		(layer "B.Cu")
		(net 766)
	)
	(segment
		(start 223.556599 101.497499)
		(end 222.987499 101.497499)
		(width 0.125)
		(layer "In7.Cu")
		(net 766)
	)
	(segment
		(start 229.866549 103.066855)
		(end 229.866549 103.2275)
		(width 0.125)
		(layer "In7.Cu")
		(net 766)
	)
	(segment
		(start 148.2875 65.2466)
		(end 148.2875 66.5466)
		(width 0.125)
		(layer "In7.Cu")
		(net 766)
	)
	(segment
		(start 189.6534 68.0125)
		(end 192.9534 71.3125)
		(width 0.125)
		(layer "In7.Cu")
		(net 766)
	)
	(segment
		(start 222.987499 101.497499)
		(end 222.8 101.31)
		(width 0.125)
		(layer "In7.Cu")
		(net 766)
	)
	(segment
		(start 232.4666 103.3875)
		(end 232.026549 103.3875)
		(width 0.125)
		(layer "In7.Cu")
		(net 766)
	)
	(segment
		(start 220.287499 101.497499)
		(end 220.493401 101.497499)
		(width 0.125)
		(layer "In7.Cu")
		(net 766)
	)
	(segment
		(start 111.58 57.3125)
		(end 140.3534 57.3125)
		(width 0.125)
		(layer "In7.Cu")
		(net 766)
	)
	(segment
		(start 230.106549 102.906855)
		(end 230.026549 102.906855)
		(width 0.125)
		(layer "In7.Cu")
		(net 766)
	)
	(segment
		(start 220.9375 99.317756)
		(end 220.9375 85.685101)
		(width 0.125)
		(layer "In7.Cu")
		(net 766)
	)
	(segment
		(start 220.9375 99.943994)
		(end 220.9375 99.863994)
		(width 0.125)
		(layer "In7.Cu")
		(net 766)
	)
	(segment
		(start 229.131773 103.3875)
		(end 226.4466 103.3875)
		(width 0.125)
		(layer "In7.Cu")
		(net 766)
	)
	(segment
		(start 221.488253 84.590891)
		(end 221.41861 84.660533)
		(width 0.125)
		(layer "In7.Cu")
		(net 766)
	)
	(segment
		(start 221.41861 85.122288)
		(end 221.348968 85.191931)
		(width 0.125)
		(layer "In7.Cu")
		(net 766)
	)
	(segment
		(start 110.732769 57.4725)
		(end 110.732769 57.476204)
		(width 0.125)
		(layer "In7.Cu")
		(net 766)
	)
	(segment
		(start 218.3534 81.3125)
		(end 219.5534 82.5125)
		(width 0.125)
		(layer "In7.Cu")
		(net 766)
	)
	(segment
		(start 140.3534 57.3125)
		(end 148.2875 65.2466)
		(width 0.125)
		(layer "In7.Cu")
		(net 766)
	)
	(segment
		(start 230.906549 102.906855)
		(end 230.826549 102.906855)
		(width 0.125)
		(layer "In7.Cu")
		(net 766)
	)
	(segment
		(start 220.9375 85.6034)
		(end 220.9375 85.685101)
		(width 0.125)
		(layer "In7.Cu")
		(net 766)
	)
	(segment
		(start 231.866549 103.2275)
		(end 231.866549 103.066855)
		(width 0.125)
		(layer "In7.Cu")
		(net 766)
	)
	(segment
		(start 111.372769 57.3125)
		(end 111.58 57.3125)
		(width 0.125)
		(layer "In7.Cu")
		(net 766)
	)
	(segment
		(start 100.312501 69.175001)
		(end 100.312501 67.176599)
		(width 0.125)
		(layer "In7.Cu")
		(net 766)
	)
	(segment
		(start 216.1875 80.4466)
		(end 217.0534 81.3125)
		(width 0.125)
		(layer "In7.Cu")
		(net 766)
	)
	(segment
		(start 226.4466 103.3875)
		(end 225.0466 101.9875)
		(width 0.125)
		(layer "In7.Cu")
		(net 766)
	)
	(segment
		(start 231.466549 103.066855)
		(end 231.466549 103.2275)
		(width 0.125)
		(layer "In7.Cu")
		(net 766)
	)
	(segment
		(start 148.2875 66.5466)
		(end 149.7534 68.0125)
		(width 0.125)
		(layer "In7.Cu")
		(net 766)
	)
	(segment
		(start 110.892769 57.636204)
		(end 110.972769 57.636204)
		(width 0.125)
		(layer "In7.Cu")
		(net 766)
	)
	(segment
		(start 229.706549 103.3875)
		(end 229.626549 103.3875)
		(width 0.125)
		(layer "In7.Cu")
		(net 766)
	)
	(segment
		(start 219.5534 82.5125)
		(end 221.5534 82.5125)
		(width 0.125)
		(layer "In7.Cu")
		(net 766)
	)
	(segment
		(start 100.4875 69.35)
		(end 100.312501 69.175001)
		(width 0.125)
		(layer "In7.Cu")
		(net 766)
	)
	(segment
		(start 192.9534 71.3125)
		(end 209.6534 71.3125)
		(width 0.125)
		(layer "In7.Cu")
		(net 766)
	)
	(segment
		(start 225.0466 101.9875)
		(end 224.0466 101.9875)
		(width 0.125)
		(layer "In7.Cu")
		(net 766)
	)
	(segment
		(start 220.773644 100.103994)
		(end 220.7775 100.103994)
		(width 0.125)
		(layer "In7.Cu")
		(net 766)
	)
	(segment
		(start 230.266549 103.2275)
		(end 230.266549 103.066855)
		(width 0.125)
		(layer "In7.Cu")
		(net 766)
	)
	(segment
		(start 220.613644 100.343994)
		(end 220.613644 100.263994)
		(width 0.125)
		(layer "In7.Cu")
		(net 766)
	)
	(segment
		(start 221.5534 82.5125)
		(end 222.1875 83.1466)
		(width 0.125)
		(layer "In7.Cu")
		(net 766)
	)
	(segment
		(start 230.506549 103.3875)
		(end 230.426549 103.3875)
		(width 0.125)
		(layer "In7.Cu")
		(net 766)
	)
	(segment
		(start 216.1875 77.8466)
		(end 216.1875 80.4466)
		(width 0.125)
		(layer "In7.Cu")
		(net 766)
	)
	(segment
		(start 231.306549 103.3875)
		(end 231.226549 103.3875)
		(width 0.125)
		(layer "In7.Cu")
		(net 766)
	)
	(segment
		(start 220.7775 100.503994)
		(end 220.773644 100.503994)
		(width 0.125)
		(layer "In7.Cu")
		(net 766)
	)
	(segment
		(start 217.0534 81.3125)
		(end 218.3534 81.3125)
		(width 0.125)
		(layer "In7.Cu")
		(net 766)
	)
	(segment
		(start 231.706549 102.906855)
		(end 231.626549 102.906855)
		(width 0.125)
		(layer "In7.Cu")
		(net 766)
	)
	(segment
		(start 229.626549 103.3875)
		(end 229.131773 103.3875)
		(width 0.125)
		(layer "In7.Cu")
		(net 766)
	)
	(segment
		(start 231.066549 103.2275)
		(end 231.066549 103.066855)
		(width 0.125)
		(layer "In7.Cu")
		(net 766)
	)
	(segment
		(start 149.7534 68.0125)
		(end 189.6534 68.0125)
		(width 0.125)
		(layer "In7.Cu")
		(net 766)
	)
	(segment
		(start 220.9375 99.863994)
		(end 220.9375 99.317756)
		(width 0.125)
		(layer "In7.Cu")
		(net 766)
	)
	(segment
		(start 111.292769 57.3125)
		(end 111.372769 57.3125)
		(width 0.125)
		(layer "In7.Cu")
		(net 766)
	)
	(segment
		(start 220.9375 101.0534)
		(end 220.9375 100.663994)
		(width 0.125)
		(layer "In7.Cu")
		(net 766)
	)
	(segment
		(start 224.0466 101.9875)
		(end 223.556599 101.497499)
		(width 0.125)
		(layer "In7.Cu")
		(net 766)
	)
	(segment
		(start 232.807501 104.337501)
		(end 232.807501 103.728401)
		(width 0.125)
		(layer "In7.Cu")
		(net 766)
	)
	(segment
		(start 222.1875 83.1466)
		(end 222.1875 84.3534)
		(width 0.125)
		(layer "In7.Cu")
		(net 766)
	)
	(segment
		(start 230.666549 103.066855)
		(end 230.666549 103.2275)
		(width 0.125)
		(layer "In7.Cu")
		(net 766)
	)
	(segment
		(start 222.1875 84.3534)
		(end 221.950009 84.590891)
		(width 0.125)
		(layer "In7.Cu")
		(net 766)
	)
	(segment
		(start 232.97 104.5)
		(end 232.807501 104.337501)
		(width 0.125)
		(layer "In7.Cu")
		(net 766)
	)
	(segment
		(start 221.348968 85.191931)
		(end 220.9375 85.6034)
		(width 0.125)
		(layer "In7.Cu")
		(net 766)
	)
	(segment
		(start 220.493401 101.497499)
		(end 220.9375 101.0534)
		(width 0.125)
		(layer "In7.Cu")
		(net 766)
	)
	(segment
		(start 220.1 101.31)
		(end 220.287499 101.497499)
		(width 0.125)
		(layer "In7.Cu")
		(net 766)
	)
	(segment
		(start 100.312501 67.176599)
		(end 110.1766 57.3125)
		(width 0.125)
		(layer "In7.Cu")
		(net 766)
	)
	(segment
		(start 209.6534 71.3125)
		(end 216.1875 77.8466)
		(width 0.125)
		(layer "In7.Cu")
		(net 766)
	)
	(segment
		(start 111.132769 57.476204)
		(end 111.132769 57.4725)
		(width 0.125)
		(layer "In7.Cu")
		(net 766)
	)
	(segment
		(start 232.807501 103.728401)
		(end 232.4666 103.3875)
		(width 0.125)
		(layer "In7.Cu")
		(net 766)
	)
	(segment
		(start 110.1766 57.3125)
		(end 110.572769 57.3125)
		(width 0.125)
		(layer "In7.Cu")
		(net 766)
	)
	(arc
		(start 230.266549 103.066855)
		(mid 230.219686 102.953718)
		(end 230.106549 102.906855)
		(width 0.125)
		(layer "In7.Cu")
		(net 766)
	)
	(arc
		(start 221.719131 84.590891)
		(mid 221.603692 84.543075)
		(end 221.488253 84.590891)
		(width 0.125)
		(layer "In7.Cu")
		(net 766)
	)
	(arc
		(start 220.773644 100.503994)
		(mid 220.660507 100.457131)
		(end 220.613644 100.343994)
		(width 0.125)
		(layer "In7.Cu")
		(net 766)
	)
	(arc
		(start 110.572769 57.3125)
		(mid 110.685906 57.359363)
		(end 110.732769 57.4725)
		(width 0.125)
		(layer "In7.Cu")
		(net 766)
	)
	(arc
		(start 111.132769 57.4725)
		(mid 111.179632 57.359363)
		(end 111.292769 57.3125)
		(width 0.125)
		(layer "In7.Cu")
		(net 766)
	)
	(arc
		(start 230.666549 103.2275)
		(mid 230.619686 103.340637)
		(end 230.506549 103.3875)
		(width 0.125)
		(layer "In7.Cu")
		(net 766)
	)
	(arc
		(start 229.866549 103.2275)
		(mid 229.819686 103.340637)
		(end 229.706549 103.3875)
		(width 0.125)
		(layer "In7.Cu")
		(net 766)
	)
	(arc
		(start 232.026549 103.3875)
		(mid 231.913412 103.340637)
		(end 231.866549 103.2275)
		(width 0.125)
		(layer "In7.Cu")
		(net 766)
	)
	(arc
		(start 230.026549 102.906855)
		(mid 229.913412 102.953718)
		(end 229.866549 103.066855)
		(width 0.125)
		(layer "In7.Cu")
		(net 766)
	)
	(arc
		(start 110.732769 57.476204)
		(mid 110.779632 57.589341)
		(end 110.892769 57.636204)
		(width 0.125)
		(layer "In7.Cu")
		(net 766)
	)
	(arc
		(start 221.950009 84.590891)
		(mid 221.83457 84.638707)
		(end 221.719131 84.590891)
		(width 0.125)
		(layer "In7.Cu")
		(net 766)
	)
	(arc
		(start 220.7775 100.103994)
		(mid 220.890637 100.057131)
		(end 220.9375 99.943994)
		(width 0.125)
		(layer "In7.Cu")
		(net 766)
	)
	(arc
		(start 231.466549 103.2275)
		(mid 231.419686 103.340637)
		(end 231.306549 103.3875)
		(width 0.125)
		(layer "In7.Cu")
		(net 766)
	)
	(arc
		(start 231.066549 103.066855)
		(mid 231.019686 102.953718)
		(end 230.906549 102.906855)
		(width 0.125)
		(layer "In7.Cu")
		(net 766)
	)
	(arc
		(start 231.866549 103.066855)
		(mid 231.819686 102.953718)
		(end 231.706549 102.906855)
		(width 0.125)
		(layer "In7.Cu")
		(net 766)
	)
	(arc
		(start 221.41861 84.660533)
		(mid 221.370794 84.775972)
		(end 221.41861 84.891411)
		(width 0.125)
		(layer "In7.Cu")
		(net 766)
	)
	(arc
		(start 220.9375 100.663994)
		(mid 220.890637 100.550857)
		(end 220.7775 100.503994)
		(width 0.125)
		(layer "In7.Cu")
		(net 766)
	)
	(arc
		(start 220.613644 100.263994)
		(mid 220.660507 100.150857)
		(end 220.773644 100.103994)
		(width 0.125)
		(layer "In7.Cu")
		(net 766)
	)
	(arc
		(start 110.972769 57.636204)
		(mid 111.085906 57.589341)
		(end 111.132769 57.476204)
		(width 0.125)
		(layer "In7.Cu")
		(net 766)
	)
	(arc
		(start 230.826549 102.906855)
		(mid 230.713412 102.953718)
		(end 230.666549 103.066855)
		(width 0.125)
		(layer "In7.Cu")
		(net 766)
	)
	(arc
		(start 221.41861 84.891411)
		(mid 221.466426 85.00685)
		(end 221.41861 85.122288)
		(width 0.125)
		(layer "In7.Cu")
		(net 766)
	)
	(arc
		(start 230.426549 103.3875)
		(mid 230.313412 103.340637)
		(end 230.266549 103.2275)
		(width 0.125)
		(layer "In7.Cu")
		(net 766)
	)
	(arc
		(start 231.226549 103.3875)
		(mid 231.113412 103.340637)
		(end 231.066549 103.2275)
		(width 0.125)
		(layer "In7.Cu")
		(net 766)
	)
	(arc
		(start 231.626549 102.906855)
		(mid 231.513412 102.953718)
		(end 231.466549 103.066855)
		(width 0.125)
		(layer "In7.Cu")
		(net 766)
	)
	(segment
		(start 206.205 135.61)
		(end 206.205 135.885)
		(width 0.19)
		(layer "F.Cu")
		(net 770)
	)
	(segment
		(start 107.330532 82.65)
		(end 107.065532 82.385)
		(width 0.19)
		(layer "F.Cu")
		(net 770)
	)
	(segment
		(start 107.065532 82.385)
		(end 107.065532 81.915)
		(width 0.19)
		(layer "F.Cu")
		(net 770)
	)
	(segment
		(start 107.065532 81.915)
		(end 107.180532 81.8)
		(width 0.19)
		(layer "F.Cu")
		(net 770)
	)
	(segment
		(start 205.9 135.305)
		(end 206.205 135.61)
		(width 0.19)
		(layer "F.Cu")
		(net 770)
	)
	(segment
		(start 205.9 135.28)
		(end 205.9 135.305)
		(width 0.19)
		(layer "F.Cu")
		(net 770)
	)
	(segment
		(start 206.205 135.885)
		(end 206.09 136)
		(width 0.19)
		(layer "F.Cu")
		(net 770)
	)
	(via
		(at 206.09 136)
		(size 0.45)
		(drill 0.1)
		(layers "F.Cu" "B.Cu")
		(net 770)
	)
	(via
		(at 107.180532 81.8)
		(size 0.45)
		(drill 0.1)
		(layers "F.Cu" "B.Cu")
		(net 770)
	)
	(segment
		(start 114.9375 73.693044)
		(end 112.9375 71.693044)
		(width 0.15)
		(layer "In7.Cu")
		(net 770)
	)
	(segment
		(start 182.843044 76.0375)
		(end 186.243044 79.4375)
		(width 0.15)
		(layer "In7.Cu")
		(net 770)
	)
	(segment
		(start 110.756956 80.4375)
		(end 114.9375 76.256956)
		(width 0.15)
		(layer "In7.Cu")
		(net 770)
	)
	(segment
		(start 107.018032 80.926424)
		(end 107.506956 80.4375)
		(width 0.15)
		(layer "In7.Cu")
		(net 770)
	)
	(segment
		(start 188.793044 79.4375)
		(end 189.193044 79.8375)
		(width 0.15)
		(layer "In7.Cu")
		(net 770)
	)
	(segment
		(start 116.514304 64.480152)
		(end 136.330152 64.480152)
		(width 0.15)
		(layer "In7.Cu")
		(net 770)
	)
	(segment
		(start 198.243044 81.9875)
		(end 201.293044 81.9875)
		(width 0.15)
		(layer "In7.Cu")
		(net 770)
	)
	(segment
		(start 189.193044 79.8375)
		(end 196.093044 79.8375)
		(width 0.15)
		(layer "In7.Cu")
		(net 770)
	)
	(segment
		(start 186.243044 79.4375)
		(end 188.793044 79.4375)
		(width 0.15)
		(layer "In7.Cu")
		(net 770)
	)
	(segment
		(start 209.993044 124.3625)
		(end 212.643044 124.3625)
		(width 0.15)
		(layer "In7.Cu")
		(net 770)
	)
	(segment
		(start 217.3625 94.656956)
		(end 218.0625 95.356956)
		(width 0.15)
		(layer "In7.Cu")
		(net 770)
	)
	(segment
		(start 108.734287 80.4375)
		(end 110.756956 80.4375)
		(width 0.15)
		(layer "In7.Cu")
		(net 770)
	)
	(segment
		(start 218.0625 95.356956)
		(end 218.0625 107.543044)
		(width 0.15)
		(layer "In7.Cu")
		(net 770)
	)
	(segment
		(start 213.2625 123.743044)
		(end 213.2625 120.58818)
		(width 0.15)
		(layer "In7.Cu")
		(net 770)
	)
	(segment
		(start 136.330152 64.480152)
		(end 147.8875 76.0375)
		(width 0.15)
		(layer "In7.Cu")
		(net 770)
	)
	(segment
		(start 147.8875 76.0375)
		(end 182.843044 76.0375)
		(width 0.15)
		(layer "In7.Cu")
		(net 770)
	)
	(segment
		(start 201.843044 82.5375)
		(end 207.843044 82.5375)
		(width 0.15)
		(layer "In7.Cu")
		(net 770)
	)
	(segment
		(start 213.2625 119.95818)
		(end 213.2625 112.343044)
		(width 0.15)
		(layer "In7.Cu")
		(net 770)
	)
	(segment
		(start 206.2525 135.8375)
		(end 206.2525 128.103044)
		(width 0.15)
		(layer "In7.Cu")
		(net 770)
	)
	(segment
		(start 112.9375 71.693044)
		(end 112.9375 68.056956)
		(width 0.15)
		(layer "In7.Cu")
		(net 770)
	)
	(segment
		(start 114.9375 76.256956)
		(end 114.9375 73.693044)
		(width 0.15)
		(layer "In7.Cu")
		(net 770)
	)
	(segment
		(start 112.9375 68.056956)
		(end 116.514304 64.480152)
		(width 0.15)
		(layer "In7.Cu")
		(net 770)
	)
	(segment
		(start 213.0525 120.09818)
		(end 213.1225 120.09818)
		(width 0.15)
		(layer "In7.Cu")
		(net 770)
	)
	(segment
		(start 212.9125 120.30818)
		(end 212.9125 120.23818)
		(width 0.15)
		(layer "In7.Cu")
		(net 770)
	)
	(segment
		(start 207.843044 82.5375)
		(end 217.3625 92.056956)
		(width 0.15)
		(layer "In7.Cu")
		(net 770)
	)
	(segment
		(start 201.293044 81.9875)
		(end 201.843044 82.5375)
		(width 0.15)
		(layer "In7.Cu")
		(net 770)
	)
	(segment
		(start 196.093044 79.8375)
		(end 198.243044 81.9875)
		(width 0.15)
		(layer "In7.Cu")
		(net 770)
	)
	(segment
		(start 206.09 136)
		(end 206.2525 135.8375)
		(width 0.15)
		(layer "In7.Cu")
		(net 770)
	)
	(segment
		(start 218.0625 107.543044)
		(end 213.2625 112.343044)
		(width 0.15)
		(layer "In7.Cu")
		(net 770)
	)
	(segment
		(start 107.018032 81.6375)
		(end 107.018032 80.926424)
		(width 0.15)
		(layer "In7.Cu")
		(net 770)
	)
	(segment
		(start 217.3625 92.056956)
		(end 217.3625 94.656956)
		(width 0.15)
		(layer "In7.Cu")
		(net 770)
	)
	(segment
		(start 108.104287 80.6175)
		(end 108.104287 80.637772)
		(width 0.15)
		(layer "In7.Cu")
		(net 770)
	)
	(segment
		(start 108.554287 80.637772)
		(end 108.554287 80.6175)
		(width 0.15)
		(layer "In7.Cu")
		(net 770)
	)
	(segment
		(start 108.284287 80.817772)
		(end 108.374287 80.817772)
		(width 0.15)
		(layer "In7.Cu")
		(net 770)
	)
	(segment
		(start 107.506956 80.4375)
		(end 107.924287 80.4375)
		(width 0.15)
		(layer "In7.Cu")
		(net 770)
	)
	(segment
		(start 213.1225 120.44818)
		(end 213.0525 120.44818)
		(width 0.15)
		(layer "In7.Cu")
		(net 770)
	)
	(segment
		(start 206.2525 128.103044)
		(end 209.993044 124.3625)
		(width 0.15)
		(layer "In7.Cu")
		(net 770)
	)
	(segment
		(start 107.180532 81.8)
		(end 107.018032 81.6375)
		(width 0.15)
		(layer "In7.Cu")
		(net 770)
	)
	(segment
		(start 212.643044 124.3625)
		(end 213.2625 123.743044)
		(width 0.15)
		(layer "In7.Cu")
		(net 770)
	)
	(arc
		(start 213.0525 120.44818)
		(mid 212.953505 120.407175)
		(end 212.9125 120.30818)
		(width 0.15)
		(layer "In7.Cu")
		(net 770)
	)
	(arc
		(start 108.554287 80.6175)
		(mid 108.607008 80.490221)
		(end 108.734287 80.4375)
		(width 0.15)
		(layer "In7.Cu")
		(net 770)
	)
	(arc
		(start 107.924287 80.4375)
		(mid 108.051566 80.490221)
		(end 108.104287 80.6175)
		(width 0.15)
		(layer "In7.Cu")
		(net 770)
	)
	(arc
		(start 108.104287 80.637772)
		(mid 108.157008 80.765051)
		(end 108.284287 80.817772)
		(width 0.15)
		(layer "In7.Cu")
		(net 770)
	)
	(arc
		(start 108.374287 80.817772)
		(mid 108.501566 80.765051)
		(end 108.554287 80.637772)
		(width 0.15)
		(layer "In7.Cu")
		(net 770)
	)
	(arc
		(start 213.1225 120.09818)
		(mid 213.221495 120.057175)
		(end 213.2625 119.95818)
		(width 0.15)
		(layer "In7.Cu")
		(net 770)
	)
	(arc
		(start 213.2625 120.58818)
		(mid 213.221495 120.489185)
		(end 213.1225 120.44818)
		(width 0.15)
		(layer "In7.Cu")
		(net 770)
	)
	(arc
		(start 212.9125 120.23818)
		(mid 212.953505 120.139185)
		(end 213.0525 120.09818)
		(width 0.15)
		(layer "In7.Cu")
		(net 770)
	)
	(segment
		(start 87.34663 100.985)
		(end 90.475 104.11337)
		(width 0.19)
		(layer "B.Cu")
		(net 771)
	)
	(segment
		(start 85.935532 100.535)
		(end 86.385532 100.985)
		(width 0.19)
		(layer "B.Cu")
		(net 771)
	)
	(segment
		(start 90.780001 104.995)
		(end 90.780001 105.02)
		(width 0.19)
		(layer "B.Cu")
		(net 771)
	)
	(segment
		(start 90.475 104.11337)
		(end 90.475 104.689999)
		(width 0.19)
		(layer "B.Cu")
		(net 771)
	)
	(segment
		(start 90.475 104.689999)
		(end 90.780001 104.995)
		(width 0.19)
		(layer "B.Cu")
		(net 771)
	)
	(segment
		(start 86.385532 100.985)
		(end 87.34663 100.985)
		(width 0.19)
		(layer "B.Cu")
		(net 771)
	)
	(segment
		(start 128.7 89.1)
		(end 129 89.4)
		(width 0.1)
		(layer "F.Cu")
		(net 775)
	)
	(segment
		(start 128.7 86.95)
		(end 128.7 89.1)
		(width 0.1)
		(layer "F.Cu")
		(net 775)
	)
	(segment
		(start 102.430532 70.65)
		(end 102.430532 69.630532)
		(width 0.1)
		(layer "F.Cu")
		(net 775)
	)
	(segment
		(start 102.430532 69.630532)
		(end 102.4 69.6)
		(width 0.1)
		(layer "F.Cu")
		(net 775)
	)
	(via
		(at 129 89.4)
		(size 0.45)
		(drill 0.1)
		(layers "F.Cu" "B.Cu")
		(net 775)
	)
	(via
		(at 102.4 69.6)
		(size 0.45)
		(drill 0.1)
		(layers "F.Cu" "B.Cu")
		(net 775)
	)
	(via
		(at 126 106.8)
		(size 0.45)
		(drill 0.1)
		(layers "F.Cu" "B.Cu")
		(net 775)
	)
	(via
		(at 128.7 86.95)
		(size 0.45)
		(drill 0.1)
		(layers "F.Cu" "B.Cu")
		(net 775)
	)
	(segment
		(start 125.08 106.8)
		(end 126 106.8)
		(width 0.1)
		(layer "B.Cu")
		(net 775)
	)
	(segment
		(start 129.45 82.25)
		(end 129.255532 82.444468)
		(width 0.1)
		(layer "In4.Cu")
		(net 775)
	)
	(segment
		(start 129.6 79.150201)
		(end 128.7 80.050201)
		(width 0.1)
		(layer "In4.Cu")
		(net 775)
	)
	(segment
		(start 128.749999 68.582839)
		(end 129.650001 68.582839)
		(width 0.1)
		(layer "In4.Cu")
		(net 775)
	)
	(segment
		(start 130.1 77.55)
		(end 129.6 78.05)
		(width 0.1)
		(layer "In4.Cu")
		(net 775)
	)
	(segment
		(start 103.399997 69.6)
		(end 103.6 69.399997)
		(width 0.1)
		(layer "In4.Cu")
		(net 775)
	)
	(segment
		(start 130.317161 72.667161)
		(end 130.95 73.3)
		(width 0.1)
		(layer "In4.Cu")
		(net 775)
	)
	(segment
		(start 129.45 81.3)
		(end 129.45 82.25)
		(width 0.1)
		(layer "In4.Cu")
		(net 775)
	)
	(segment
		(start 130.95 74)
		(end 130.1 74.85)
		(width 0.1)
		(layer "In4.Cu")
		(net 775)
	)
	(segment
		(start 129.25 86.4)
		(end 128.7 86.95)
		(width 0.1)
		(layer "In4.Cu")
		(net 775)
	)
	(segment
		(start 102.4 69.6)
		(end 103.399997 69.6)
		(width 0.1)
		(layer "In4.Cu")
		(net 775)
	)
	(segment
		(start 129.255532 86.094468)
		(end 129.25 86.1)
		(width 0.1)
		(layer "In4.Cu")
		(net 775)
	)
	(segment
		(start 128.7 80.55)
		(end 129.45 81.3)
		(width 0.1)
		(layer "In4.Cu")
		(net 775)
	)
	(segment
		(start 130.1 74.85)
		(end 130.1 77.55)
		(width 0.1)
		(layer "In4.Cu")
		(net 775)
	)
	(segment
		(start 129.255532 82.444468)
		(end 129.255532 86.094468)
		(width 0.1)
		(layer "In4.Cu")
		(net 775)
	)
	(segment
		(start 130.95 73.3)
		(end 130.95 74)
		(width 0.1)
		(layer "In4.Cu")
		(net 775)
	)
	(segment
		(start 129.25 86.1)
		(end 129.25 86.4)
		(width 0.1)
		(layer "In4.Cu")
		(net 775)
	)
	(segment
		(start 108.884316 69.53284)
		(end 127.799998 69.53284)
		(width 0.1)
		(layer "In4.Cu")
		(net 775)
	)
	(segment
		(start 128.7 80.050201)
		(end 128.7 80.55)
		(width 0.1)
		(layer "In4.Cu")
		(net 775)
	)
	(segment
		(start 129.6 78.05)
		(end 129.6 79.150201)
		(width 0.1)
		(layer "In4.Cu")
		(net 775)
	)
	(segment
		(start 129.650001 68.582839)
		(end 130.317161 69.249999)
		(width 0.1)
		(layer "In4.Cu")
		(net 775)
	)
	(segment
		(start 103.6 69.399997)
		(end 108.751473 69.399997)
		(width 0.1)
		(layer "In4.Cu")
		(net 775)
	)
	(segment
		(start 130.317161 69.249999)
		(end 130.317161 72.667161)
		(width 0.1)
		(layer "In4.Cu")
		(net 775)
	)
	(segment
		(start 108.751473 69.399997)
		(end 108.884316 69.53284)
		(width 0.1)
		(layer "In4.Cu")
		(net 775)
	)
	(segment
		(start 127.799998 69.53284)
		(end 128.749999 68.582839)
		(width 0.1)
		(layer "In4.Cu")
		(net 775)
	)
	(segment
		(start 125.6 108.4)
		(end 125.4 108.2)
		(width 0.1)
		(layer "In7.Cu")
		(net 775)
	)
	(segment
		(start 131 104.6)
		(end 127.2 108.4)
		(width 0.1)
		(layer "In7.Cu")
		(net 775)
	)
	(segment
		(start 127.2 108.4)
		(end 125.6 108.4)
		(width 0.1)
		(layer "In7.Cu")
		(net 775)
	)
	(segment
		(start 125.4 108.2)
		(end 125.4 107)
		(width 0.1)
		(layer "In7.Cu")
		(net 775)
	)
	(segment
		(start 125.4 107)
		(end 125.6 106.8)
		(width 0.1)
		(layer "In7.Cu")
		(net 775)
	)
	(segment
		(start 131 91.4)
		(end 131 104.6)
		(width 0.1)
		(layer "In7.Cu")
		(net 775)
	)
	(segment
		(start 129 89.4)
		(end 131 91.4)
		(width 0.1)
		(layer "In7.Cu")
		(net 775)
	)
	(segment
		(start 125.6 106.8)
		(end 126 106.8)
		(width 0.1)
		(layer "In7.Cu")
		(net 775)
	)
	(segment
		(start 88.62 101.6)
		(end 88.595 101.6)
		(width 0.19)
		(layer "F.Cu")
		(net 776)
	)
	(segment
		(start 82.575532 103.525)
		(end 82.125532 103.075)
		(width 0.19)
		(layer "F.Cu")
		(net 776)
	)
	(segment
		(start 85.648408 103.525)
		(end 82.575532 103.525)
		(width 0.19)
		(layer "F.Cu")
		(net 776)
	)
	(segment
		(start 87.415 102.92337)
		(end 86.82337 103.515)
		(width 0.19)
		(layer "F.Cu")
		(net 776)
	)
	(segment
		(start 88.595 101.6)
		(end 88.28 101.915)
		(width 0.19)
		(layer "F.Cu")
		(net 776)
	)
	(segment
		(start 88.28 101.915)
		(end 88.02337 101.915)
		(width 0.19)
		(layer "F.Cu")
		(net 776)
	)
	(segment
		(start 87.415 102.52337)
		(end 87.415 102.92337)
		(width 0.19)
		(layer "F.Cu")
		(net 776)
	)
	(segment
		(start 85.658408 103.515)
		(end 85.648408 103.525)
		(width 0.19)
		(layer "F.Cu")
		(net 776)
	)
	(segment
		(start 86.82337 103.515)
		(end 85.658408 103.515)
		(width 0.19)
		(layer "F.Cu")
		(net 776)
	)
	(segment
		(start 88.02337 101.915)
		(end 87.415 102.52337)
		(width 0.19)
		(layer "F.Cu")
		(net 776)
	)
	(via
		(at 82.125532 103.075)
		(size 0.45)
		(drill 0.1)
		(layers "F.Cu" "B.Cu")
		(net 776)
	)
	(via
		(at 82.125532 128.475)
		(size 0.45)
		(drill 0.1)
		(layers "F.Cu" "B.Cu")
		(net 777)
	)
	(segment
		(start 155.39 103.01)
		(end 155.4 103)
		(width 0.1)
		(layer "F.Cu")
		(net 780)
	)
	(segment
		(start 153.375 103.01)
		(end 155.39 103.01)
		(width 0.1)
		(layer "F.Cu")
		(net 780)
	)
	(via
		(at 155.4 103)
		(size 0.45)
		(drill 0.1)
		(layers "F.Cu" "B.Cu")
		(net 780)
	)
	(via
		(at 91.730532 73.65)
		(size 0.45)
		(drill 0.1)
		(layers "F.Cu" "B.Cu")
		(net 780)
	)
	(segment
		(start 96.8 71.45)
		(end 97.4 71.45)
		(width 0.1)
		(layer "In4.Cu")
		(net 780)
	)
	(segment
		(start 101.901474 68.65)
		(end 108.85 68.65)
		(width 0.1)
		(layer "In4.Cu")
		(net 780)
	)
	(segment
		(start 94.45 73.1)
		(end 94.925 72.625)
		(width 0.1)
		(layer "In4.Cu")
		(net 780)
	)
	(segment
		(start 152.5 104.9)
		(end 154.4 103)
		(width 0.1)
		(layer "In4.Cu")
		(net 780)
	)
	(segment
		(start 132.05 82.25)
		(end 131.85 82.45)
		(width 0.1)
		(layer "In4.Cu")
		(net 780)
	)
	(segment
		(start 98 70.85)
		(end 98 70.45)
		(width 0.1)
		(layer "In4.Cu")
		(net 780)
	)
	(segment
		(start 93.455331 72.875)
		(end 93.825 72.875)
		(width 0.1)
		(layer "In4.Cu")
		(net 780)
	)
	(segment
		(start 132.95 78.05)
		(end 132.95 80.1)
		(width 0.1)
		(layer "In4.Cu")
		(net 780)
	)
	(segment
		(start 132.95 73.9)
		(end 133.85 74.8)
		(width 0.1)
		(layer "In4.Cu")
		(net 780)
	)
	(segment
		(start 100.701474 69.85)
		(end 101.901474 68.65)
		(width 0.1)
		(layer "In4.Cu")
		(net 780)
	)
	(segment
		(start 130.666421 85.733579)
		(end 130.666421 87.583579)
		(width 0.1)
		(layer "In4.Cu")
		(net 780)
	)
	(segment
		(start 127.5 68.80858)
		(end 128.45 67.85858)
		(width 0.1)
		(layer "In4.Cu")
		(net 780)
	)
	(segment
		(start 94.05 73.1)
		(end 94.45 73.1)
		(width 0.1)
		(layer "In4.Cu")
		(net 780)
	)
	(segment
		(start 130.666421 87.583579)
		(end 147.982842 104.9)
		(width 0.1)
		(layer "In4.Cu")
		(net 780)
	)
	(segment
		(start 132.05 81)
		(end 132.05 82.25)
		(width 0.1)
		(layer "In4.Cu")
		(net 780)
	)
	(segment
		(start 154.4 103)
		(end 155.4 103)
		(width 0.1)
		(layer "In4.Cu")
		(net 780)
	)
	(segment
		(start 132.95 80.1)
		(end 132.05 81)
		(width 0.1)
		(layer "In4.Cu")
		(net 780)
	)
	(segment
		(start 109.00858 68.80858)
		(end 127.5 68.80858)
		(width 0.1)
		(layer "In4.Cu")
		(net 780)
	)
	(segment
		(start 92.280532 73.1)
		(end 93.230331 73.1)
		(width 0.1)
		(layer "In4.Cu")
		(net 780)
	)
	(segment
		(start 133.65 76.05)
		(end 133.65 77.35)
		(width 0.1)
		(layer "In4.Cu")
		(net 780)
	)
	(segment
		(start 133.85 75.85)
		(end 133.65 76.05)
		(width 0.1)
		(layer "In4.Cu")
		(net 780)
	)
	(segment
		(start 98.6 69.85)
		(end 100.701474 69.85)
		(width 0.1)
		(layer "In4.Cu")
		(net 780)
	)
	(segment
		(start 133.65 77.35)
		(end 132.95 78.05)
		(width 0.1)
		(layer "In4.Cu")
		(net 780)
	)
	(segment
		(start 98 70.45)
		(end 98.6 69.85)
		(width 0.1)
		(layer "In4.Cu")
		(net 780)
	)
	(segment
		(start 108.85 68.65)
		(end 109.00858 68.80858)
		(width 0.1)
		(layer "In4.Cu")
		(net 780)
	)
	(segment
		(start 131.85 82.45)
		(end 131.85 84.55)
		(width 0.1)
		(layer "In4.Cu")
		(net 780)
	)
	(segment
		(start 133.85 74.8)
		(end 133.85 75.85)
		(width 0.1)
		(layer "In4.Cu")
		(net 780)
	)
	(segment
		(start 128.45 67.85858)
		(end 129.95 67.85858)
		(width 0.1)
		(layer "In4.Cu")
		(net 780)
	)
	(segment
		(start 131.85 84.55)
		(end 130.666421 85.733579)
		(width 0.1)
		(layer "In4.Cu")
		(net 780)
	)
	(segment
		(start 147.982842 104.9)
		(end 152.5 104.9)
		(width 0.1)
		(layer "In4.Cu")
		(net 780)
	)
	(segment
		(start 131.04142 68.95)
		(end 131.04142 70.69142)
		(width 0.1)
		(layer "In4.Cu")
		(net 780)
	)
	(segment
		(start 93.230331 73.1)
		(end 93.455331 72.875)
		(width 0.1)
		(layer "In4.Cu")
		(net 780)
	)
	(segment
		(start 94.925 72.625)
		(end 95.625 72.625)
		(width 0.1)
		(layer "In4.Cu")
		(net 780)
	)
	(segment
		(start 91.730532 73.65)
		(end 92.280532 73.1)
		(width 0.1)
		(layer "In4.Cu")
		(net 780)
	)
	(segment
		(start 97.4 71.45)
		(end 98 70.85)
		(width 0.1)
		(layer "In4.Cu")
		(net 780)
	)
	(segment
		(start 132.95 72.6)
		(end 132.95 73.9)
		(width 0.1)
		(layer "In4.Cu")
		(net 780)
	)
	(segment
		(start 129.95 67.85858)
		(end 131.04142 68.95)
		(width 0.1)
		(layer "In4.Cu")
		(net 780)
	)
	(segment
		(start 95.625 72.625)
		(end 96.8 71.45)
		(width 0.1)
		(layer "In4.Cu")
		(net 780)
	)
	(segment
		(start 93.825 72.875)
		(end 94.05 73.1)
		(width 0.1)
		(layer "In4.Cu")
		(net 780)
	)
	(segment
		(start 131.04142 70.69142)
		(end 132.95 72.6)
		(width 0.1)
		(layer "In4.Cu")
		(net 780)
	)
	(segment
		(start 90.4 85.4)
		(end 91.430532 84.369468)
		(width 0.1)
		(layer "F.Cu")
		(net 781)
	)
	(segment
		(start 92 83.2)
		(end 101.880532 83.2)
		(width 0.1)
		(layer "F.Cu")
		(net 781)
	)
	(segment
		(start 89.63033 86.6)
		(end 90.4 85.830331)
		(width 0.1)
		(layer "F.Cu")
		(net 781)
	)
	(segment
		(start 91.430532 83.769468)
		(end 91.430532 84.369468)
		(width 0.1)
		(layer "F.Cu")
		(net 781)
	)
	(segment
		(start 91.430532 83.769468)
		(end 92 83.2)
		(width 0.1)
		(layer "F.Cu")
		(net 781)
	)
	(segment
		(start 102.430532 82.65)
		(end 101.880532 83.2)
		(width 0.1)
		(layer "F.Cu")
		(net 781)
	)
	(segment
		(start 90.4 85.4)
		(end 90.4 85.830331)
		(width 0.1)
		(layer "F.Cu")
		(net 781)
	)
	(segment
		(start 89.63033 86.6)
		(end 89.3 86.6)
		(width 0.1)
		(layer "F.Cu")
		(net 781)
	)
	(via
		(at 89.3 86.6)
		(size 0.45)
		(drill 0.1)
		(layers "F.Cu" "B.Cu")
		(net 781)
	)
	(segment
		(start 80.855532 100.535)
		(end 81.5 99.890532)
		(width 0.1)
		(layer "B.Cu")
		(net 781)
	)
	(segment
		(start 89.05 87.85)
		(end 89.05 86.85)
		(width 0.1)
		(layer "B.Cu")
		(net 781)
	)
	(segment
		(start 89.05 86.85)
		(end 89.3 86.6)
		(width 0.1)
		(layer "B.Cu")
		(net 781)
	)
	(segment
		(start 88.45 88.45)
		(end 89.05 87.85)
		(width 0.1)
		(layer "B.Cu")
		(net 781)
	)
	(segment
		(start 81.5 99.890532)
		(end 81.5 88.8)
		(width 0.1)
		(layer "B.Cu")
		(net 781)
	)
	(segment
		(start 81.5 88.8)
		(end 81.85 88.45)
		(width 0.1)
		(layer "B.Cu")
		(net 781)
	)
	(segment
		(start 81.85 88.45)
		(end 88.45 88.45)
		(width 0.1)
		(layer "B.Cu")
		(net 781)
	)
	(segment
		(start 96.695532 81.685)
		(end 96.580532 81.8)
		(width 0.19)
		(layer "F.Cu")
		(net 782)
	)
	(segment
		(start 96.430532 81.15)
		(end 96.695532 81.415)
		(width 0.19)
		(layer "F.Cu")
		(net 782)
	)
	(segment
		(start 96.695532 81.415)
		(end 96.695532 81.685)
		(width 0.19)
		(layer "F.Cu")
		(net 782)
	)
	(via
		(at 96.580532 81.8)
		(size 0.45)
		(drill 0.1)
		(layers "F.Cu" "B.Cu")
		(net 782)
	)
	(segment
		(start 100.615 107.619628)
		(end 100.615 104.56547)
		(width 0.19)
		(layer "B.Cu")
		(net 782)
	)
	(segment
		(start 96.695532 83.007162)
		(end 96.695532 81.915)
		(width 0.19)
		(layer "B.Cu")
		(net 782)
	)
	(segment
		(start 95.31337 116.225)
		(end 100.615 110.92337)
		(width 0.19)
		(layer "B.Cu")
		(net 782)
	)
	(segment
		(start 100.119664 108.279628)
		(end 100.119664 108.169628)
		(width 0.19)
		(layer "B.Cu")
		(net 782)
	)
	(segment
		(start 97.14837 83.46)
		(end 96.695532 83.007162)
		(width 0.19)
		(layer "B.Cu")
		(net 782)
	)
	(segment
		(start 97.965 86.62337)
		(end 99.965 84.62337)
		(width 0.19)
		(layer "B.Cu")
		(net 782)
	)
	(segment
		(start 99.965 83.82663)
		(end 99.59837 83.46)
		(width 0.19)
		(layer "B.Cu")
		(net 782)
	)
	(segment
		(start 97.965 101.62663)
		(end 97.965 86.62337)
		(width 0.19)
		(layer "B.Cu")
		(net 782)
	)
	(segment
		(start 86.385532 116.225)
		(end 95.31337 116.225)
		(width 0.19)
		(layer "B.Cu")
		(net 782)
	)
	(segment
		(start 100.615 110.92337)
		(end 100.615 108.719628)
		(width 0.19)
		(layer "B.Cu")
		(net 782)
	)
	(segment
		(start 100.615 104.27663)
		(end 97.965 101.62663)
		(width 0.19)
		(layer "B.Cu")
		(net 782)
	)
	(segment
		(start 85.935532 115.775)
		(end 86.385532 116.225)
		(width 0.19)
		(layer "B.Cu")
		(net 782)
	)
	(segment
		(start 100.395 108.499628)
		(end 100.339664 108.499628)
		(width 0.19)
		(layer "B.Cu")
		(net 782)
	)
	(segment
		(start 100.615 107.729628)
		(end 100.615 107.619628)
		(width 0.19)
		(layer "B.Cu")
		(net 782)
	)
	(segment
		(start 99.965 84.62337)
		(end 99.965 83.82663)
		(width 0.19)
		(layer "B.Cu")
		(net 782)
	)
	(segment
		(start 99.59837 83.46)
		(end 97.14837 83.46)
		(width 0.19)
		(layer "B.Cu")
		(net 782)
	)
	(segment
		(start 96.695532 81.915)
		(end 96.580532 81.8)
		(width 0.19)
		(layer "B.Cu")
		(net 782)
	)
	(segment
		(start 100.339664 107.949628)
		(end 100.395 107.949628)
		(width 0.19)
		(layer "B.Cu")
		(net 782)
	)
	(segment
		(start 100.615 104.56547)
		(end 100.615 104.27663)
		(width 0.19)
		(layer "B.Cu")
		(net 782)
	)
	(arc
		(start 100.395 107.949628)
		(mid 100.550563 107.885191)
		(end 100.615 107.729628)
		(width 0.19)
		(layer "B.Cu")
		(net 782)
	)
	(arc
		(start 100.119664 108.169628)
		(mid 100.184101 108.014065)
		(end 100.339664 107.949628)
		(width 0.19)
		(layer "B.Cu")
		(net 782)
	)
	(arc
		(start 100.615 108.719628)
		(mid 100.550563 108.564065)
		(end 100.395 108.499628)
		(width 0.19)
		(layer "B.Cu")
		(net 782)
	)
	(arc
		(start 100.339664 108.499628)
		(mid 100.184101 108.435191)
		(end 100.119664 108.279628)
		(width 0.19)
		(layer "B.Cu")
		(net 782)
	)
	(segment
		(start 148.3 70.475)
		(end 145.875 72.9)
		(width 0.1)
		(layer "F.Cu")
		(net 783)
	)
	(segment
		(start 143.575 73.225)
		(end 143.575 74.325)
		(width 0.1)
		(layer "F.Cu")
		(net 783)
	)
	(segment
		(start 143.575 74.325)
		(end 143.330532 74.569468)
		(width 0.1)
		(layer "F.Cu")
		(net 783)
	)
	(segment
		(start 148.3 70.1)
		(end 148.3 70.475)
		(width 0.1)
		(layer "F.Cu")
		(net 783)
	)
	(segment
		(start 143.9 72.9)
		(end 143.575 73.225)
		(width 0.1)
		(layer "F.Cu")
		(net 783)
	)
	(segment
		(start 145.875 72.9)
		(end 143.9 72.9)
		(width 0.1)
		(layer "F.Cu")
		(net 783)
	)
	(segment
		(start 143.330532 74.569468)
		(end 143.330532 75.15)
		(width 0.1)
		(layer "F.Cu")
		(net 783)
	)
	(via
		(at 148.3 70.1)
		(size 0.45)
		(drill 0.1)
		(layers "F.Cu" "B.Cu")
		(net 783)
	)
	(via
		(at 74.505532 99.265)
		(size 0.45)
		(drill 0.1)
		(layers "F.Cu" "B.Cu")
		(net 783)
	)
	(segment
		(start 73.2375 97.5)
		(end 74.9 97.5)
		(width 0.1)
		(layer "In5.Cu")
		(net 783)
	)
	(segment
		(start 147.45 69.93)
		(end 147.45 69.43)
		(width 0.1)
		(layer "In5.Cu")
		(net 783)
	)
	(segment
		(start 148.1 104.065686)
		(end 146.8 105.365686)
		(width 0.1)
		(layer "In5.Cu")
		(net 783)
	)
	(segment
		(start 74.800738 125.4)
		(end 73.65 124.249262)
		(width 0.1)
		(layer "In5.Cu")
		(net 783)
	)
	(segment
		(start 109.124264 132.999998)
		(end 107.124264 132.999998)
		(width 0.1)
		(layer "In5.Cu")
		(net 783)
	)
	(segment
		(start 105.824264 134.299998)
		(end 96.724264 134.299998)
		(width 0.1)
		(layer "In5.Cu")
		(net 783)
	)
	(segment
		(start 147.3 118.524264)
		(end 136.424265 129.399999)
		(width 0.1)
		(layer "In5.Cu")
		(net 783)
	)
	(segment
		(start 146.8 105.365686)
		(end 146.8 106.8)
		(width 0.1)
		(layer "In5.Cu")
		(net 783)
	)
	(segment
		(start 73.65 111.25)
		(end 74.4 110.5)
		(width 0.1)
		(layer "In5.Cu")
		(net 783)
	)
	(segment
		(start 147.68 69.2)
		(end 149.975 69.2)
		(width 0.1)
		(layer "In5.Cu")
		(net 783)
	)
	(segment
		(start 121.800002 132.299998)
		(end 109.824264 132.299998)
		(width 0.1)
		(layer "In5.Cu")
		(net 783)
	)
	(segment
		(start 147.62 70.1)
		(end 147.45 69.93)
		(width 0.1)
		(layer "In5.Cu")
		(net 783)
	)
	(segment
		(start 96.724264 134.299998)
		(end 92.324264 138.699998)
		(width 0.1)
		(layer "In5.Cu")
		(net 783)
	)
	(segment
		(start 73.65 109.45)
		(end 73.65 108.65)
		(width 0.1)
		(layer "In5.Cu")
		(net 783)
	)
	(segment
		(start 151.96 71.185)
		(end 151.96 72.06)
		(width 0.1)
		(layer "In5.Cu")
		(net 783)
	)
	(segment
		(start 73.65 108.65)
		(end 72.5 107.5)
		(width 0.1)
		(layer "In5.Cu")
		(net 783)
	)
	(segment
		(start 149.975 69.2)
		(end 151.96 71.185)
		(width 0.1)
		(layer "In5.Cu")
		(net 783)
	)
	(segment
		(start 72.5 107.5)
		(end 72.5 98.2375)
		(width 0.1)
		(layer "In5.Cu")
		(net 783)
	)
	(segment
		(start 74.95 97.55)
		(end 74.95 98.820532)
		(width 0.1)
		(layer "In5.Cu")
		(net 783)
	)
	(segment
		(start 73.65 124.249262)
		(end 73.65 111.25)
		(width 0.1)
		(layer "In5.Cu")
		(net 783)
	)
	(segment
		(start 147.3 107.3)
		(end 147.3 118.524264)
		(width 0.1)
		(layer "In5.Cu")
		(net 783)
	)
	(segment
		(start 80.500002 135.424264)
		(end 80.500002 129.274264)
		(width 0.1)
		(layer "In5.Cu")
		(net 783)
	)
	(segment
		(start 74.4 110.2)
		(end 73.65 109.45)
		(width 0.1)
		(layer "In5.Cu")
		(net 783)
	)
	(segment
		(start 151.96 72.06)
		(end 152.7 72.8)
		(width 0.1)
		(layer "In5.Cu")
		(net 783)
	)
	(segment
		(start 147.45 69.43)
		(end 147.68 69.2)
		(width 0.1)
		(layer "In5.Cu")
		(net 783)
	)
	(segment
		(start 79.775 125.4)
		(end 74.800738 125.4)
		(width 0.1)
		(layer "In5.Cu")
		(net 783)
	)
	(segment
		(start 152.7 83.9)
		(end 148.1 88.5)
		(width 0.1)
		(layer "In5.Cu")
		(net 783)
	)
	(segment
		(start 72.5 98.2375)
		(end 73.2375 97.5)
		(width 0.1)
		(layer "In5.Cu")
		(net 783)
	)
	(segment
		(start 83.775736 138.699998)
		(end 80.500002 135.424264)
		(width 0.1)
		(layer "In5.Cu")
		(net 783)
	)
	(segment
		(start 80.075002 125.700002)
		(end 79.775 125.4)
		(width 0.1)
		(layer "In5.Cu")
		(net 783)
	)
	(segment
		(start 74.9 97.5)
		(end 74.95 97.55)
		(width 0.1)
		(layer "In5.Cu")
		(net 783)
	)
	(segment
		(start 152.7 72.8)
		(end 152.7 83.9)
		(width 0.1)
		(layer "In5.Cu")
		(net 783)
	)
	(segment
		(start 109.824264 132.299998)
		(end 109.124264 132.999998)
		(width 0.1)
		(layer "In5.Cu")
		(net 783)
	)
	(segment
		(start 80.500002 129.274264)
		(end 80.075002 128.849264)
		(width 0.1)
		(layer "In5.Cu")
		(net 783)
	)
	(segment
		(start 146.8 106.8)
		(end 147.3 107.3)
		(width 0.1)
		(layer "In5.Cu")
		(net 783)
	)
	(segment
		(start 148.1 88.5)
		(end 148.1 104.065686)
		(width 0.1)
		(layer "In5.Cu")
		(net 783)
	)
	(segment
		(start 74.95 98.820532)
		(end 74.505532 99.265)
		(width 0.1)
		(layer "In5.Cu")
		(net 783)
	)
	(segment
		(start 92.324264 138.699998)
		(end 83.775736 138.699998)
		(width 0.1)
		(layer "In5.Cu")
		(net 783)
	)
	(segment
		(start 148.3 70.1)
		(end 147.62 70.1)
		(width 0.1)
		(layer "In5.Cu")
		(net 783)
	)
	(segment
		(start 124.700001 129.399999)
		(end 121.800002 132.299998)
		(width 0.1)
		(layer "In5.Cu")
		(net 783)
	)
	(segment
		(start 74.4 110.5)
		(end 74.4 110.2)
		(width 0.1)
		(layer "In5.Cu")
		(net 783)
	)
	(segment
		(start 136.424265 129.399999)
		(end 124.700001 129.399999)
		(width 0.1)
		(layer "In5.Cu")
		(net 783)
	)
	(segment
		(start 107.124264 132.999998)
		(end 105.824264 134.299998)
		(width 0.1)
		(layer "In5.Cu")
		(net 783)
	)
	(segment
		(start 80.075002 128.849264)
		(end 80.075002 125.700002)
		(width 0.1)
		(layer "In5.Cu")
		(net 783)
	)
	(segment
		(start 210.901514 89.986856)
		(end 210.602514 90.285856)
		(width 0.19)
		(layer "F.Cu")
		(net 786)
	)
	(segment
		(start 205.57 90.285856)
		(end 210.602514 90.285856)
		(width 0.19)
		(layer "F.Cu")
		(net 786)
	)
	(segment
		(start 212.101631 89.986856)
		(end 210.901514 89.986856)
		(width 0.19)
		(layer "F.Cu")
		(net 786)
	)
	(segment
		(start 205.255 89.970856)
		(end 205.57 90.285856)
		(width 0.19)
		(layer "F.Cu")
		(net 786)
	)
	(segment
		(start 212.115631 89.972856)
		(end 212.565632 89.972856)
		(width 0.19)
		(layer "F.Cu")
		(net 786)
	)
	(segment
		(start 205.23 89.970856)
		(end 205.255 89.970856)
		(width 0.19)
		(layer "F.Cu")
		(net 786)
	)
	(segment
		(start 212.101631 89.986856)
		(end 212.115631 89.972856)
		(width 0.19)
		(layer "F.Cu")
		(net 786)
	)
	(segment
		(start 133.2 71.5)
		(end 133.3 71.5)
		(width 0.19)
		(layer "F.Cu")
		(net 788)
	)
	(segment
		(start 133.430532 71.630532)
		(end 133.430532 72.15)
		(width 0.19)
		(layer "F.Cu")
		(net 788)
	)
	(segment
		(start 133.3 71.5)
		(end 133.430532 71.630532)
		(width 0.19)
		(layer "F.Cu")
		(net 788)
	)
	(segment
		(start 198.7 100.8)
		(end 199.2 101.3)
		(width 0.19)
		(layer "F.Cu")
		(net 788)
	)
	(segment
		(start 200.6 101.3)
		(end 201.2 100.7)
		(width 0.19)
		(layer "F.Cu")
		(net 788)
	)
	(segment
		(start 196.9 100)
		(end 197.7 100.8)
		(width 0.19)
		(layer "F.Cu")
		(net 788)
	)
	(segment
		(start 201.2 100.7)
		(end 201.2 100.1)
		(width 0.19)
		(layer "F.Cu")
		(net 788)
	)
	(segment
		(start 197.7 100.8)
		(end 198.7 100.8)
		(width 0.19)
		(layer "F.Cu")
		(net 788)
	)
	(segment
		(start 199.2 101.3)
		(end 200.6 101.3)
		(width 0.19)
		(layer "F.Cu")
		(net 788)
	)
	(via
		(at 196.9 100)
		(size 0.45)
		(drill 0.1)
		(layers "F.Cu" "B.Cu")
		(net 788)
	)
	(via
		(at 133.2 71.5)
		(size 0.45)
		(drill 0.1)
		(layers "F.Cu" "B.Cu")
		(net 788)
	)
	(via
		(at 201.2 100.1)
		(size 0.45)
		(drill 0.1)
		(layers "F.Cu" "B.Cu")
		(net 788)
	)
	(segment
		(start 205.3 100.1)
		(end 211.2 94.2)
		(width 0.19)
		(layer "B.Cu")
		(net 788)
	)
	(segment
		(start 211.2 94.2)
		(end 213.6 94.2)
		(width 0.19)
		(layer "B.Cu")
		(net 788)
	)
	(segment
		(start 213.9 93.9)
		(end 213.6 94.2)
		(width 0.19)
		(layer "B.Cu")
		(net 788)
	)
	(segment
		(start 214.7 93.9)
		(end 213.9 93.9)
		(width 0.19)
		(layer "B.Cu")
		(net 788)
	)
	(segment
		(start 214.9 94.1)
		(end 214.7 93.9)
		(width 0.19)
		(layer "B.Cu")
		(net 788)
	)
	(segment
		(start 214.9 94.62)
		(end 214.9 94.1)
		(width 0.19)
		(layer "B.Cu")
		(net 788)
	)
	(segment
		(start 205.3 100.1)
		(end 201.2 100.1)
		(width 0.19)
		(layer "B.Cu")
		(net 788)
	)
	(segment
		(start 156.2 79)
		(end 185.3 79)
		(width 0.1)
		(layer "In5.Cu")
		(net 788)
	)
	(segment
		(start 186.8 84.3)
		(end 191.5 89)
		(width 0.1)
		(layer "In5.Cu")
		(net 788)
	)
	(segment
		(start 187.1 80.8)
		(end 187.1 81.3)
		(width 0.1)
		(layer "In5.Cu")
		(net 788)
	)
	(segment
		(start 133.2 71.5)
		(end 133.2 73.4)
		(width 0.1)
		(layer "In5.Cu")
		(net 788)
	)
	(segment
		(start 191.5 89)
		(end 191.5 97.8)
		(width 0.1)
		(layer "In5.Cu")
		(net 788)
	)
	(segment
		(start 137.3 75.6)
		(end 137.7 75.2)
		(width 0.1)
		(layer "In5.Cu")
		(net 788)
	)
	(segment
		(start 155.5 72.8)
		(end 155.5 78.3)
		(width 0.1)
		(layer "In5.Cu")
		(net 788)
	)
	(segment
		(start 137.7 75.2)
		(end 137.7 73.1)
		(width 0.1)
		(layer "In5.Cu")
		(net 788)
	)
	(segment
		(start 153.95 71.25)
		(end 155.5 72.8)
		(width 0.1)
		(layer "In5.Cu")
		(net 788)
	)
	(segment
		(start 150.225 68.825)
		(end 152.65 71.25)
		(width 0.1)
		(layer "In5.Cu")
		(net 788)
	)
	(segment
		(start 155.5 78.3)
		(end 156.2 79)
		(width 0.1)
		(layer "In5.Cu")
		(net 788)
	)
	(segment
		(start 137.775 68.825)
		(end 150.225 68.825)
		(width 0.1)
		(layer "In5.Cu")
		(net 788)
	)
	(segment
		(start 192.5 102.5)
		(end 193.6 102.5)
		(width 0.1)
		(layer "In5.Cu")
		(net 788)
	)
	(segment
		(start 192.2 98.5)
		(end 192.2 102.2)
		(width 0.1)
		(layer "In5.Cu")
		(net 788)
	)
	(segment
		(start 152.65 71.25)
		(end 153.95 71.25)
		(width 0.1)
		(layer "In5.Cu")
		(net 788)
	)
	(segment
		(start 196.1 100)
		(end 196.9 100)
		(width 0.1)
		(layer "In5.Cu")
		(net 788)
	)
	(segment
		(start 187.1 81.3)
		(end 186.8 81.6)
		(width 0.1)
		(layer "In5.Cu")
		(net 788)
	)
	(segment
		(start 137.4 72.8)
		(end 137.4 69.2)
		(width 0.1)
		(layer "In5.Cu")
		(net 788)
	)
	(segment
		(start 137.4 69.2)
		(end 137.775 68.825)
		(width 0.1)
		(layer "In5.Cu")
		(net 788)
	)
	(segment
		(start 135.4 75.6)
		(end 137.3 75.6)
		(width 0.1)
		(layer "In5.Cu")
		(net 788)
	)
	(segment
		(start 137.7 73.1)
		(end 137.4 72.8)
		(width 0.1)
		(layer "In5.Cu")
		(net 788)
	)
	(segment
		(start 192.2 102.2)
		(end 192.5 102.5)
		(width 0.1)
		(layer "In5.Cu")
		(net 788)
	)
	(segment
		(start 191.5 97.8)
		(end 192.2 98.5)
		(width 0.1)
		(layer "In5.Cu")
		(net 788)
	)
	(segment
		(start 133.2 73.4)
		(end 135.4 75.6)
		(width 0.1)
		(layer "In5.Cu")
		(net 788)
	)
	(segment
		(start 186.8 81.6)
		(end 186.8 84.3)
		(width 0.1)
		(layer "In5.Cu")
		(net 788)
	)
	(segment
		(start 185.3 79)
		(end 187.1 80.8)
		(width 0.1)
		(layer "In5.Cu")
		(net 788)
	)
	(segment
		(start 193.6 102.5)
		(end 196.1 100)
		(width 0.1)
		(layer "In5.Cu")
		(net 788)
	)
	(segment
		(start 101 87.980532)
		(end 103.330532 85.65)
		(width 0.1)
		(layer "F.Cu")
		(net 789)
	)
	(segment
		(start 100.4 93.2)
		(end 101 92.6)
		(width 0.1)
		(layer "F.Cu")
		(net 789)
	)
	(segment
		(start 101 92.6)
		(end 101 87.980532)
		(width 0.1)
		(layer "F.Cu")
		(net 789)
	)
	(via
		(at 87.7 110.4)
		(size 0.45)
		(drill 0.1)
		(layers "F.Cu" "B.Cu")
		(net 789)
	)
	(via
		(at 100.4 93.2)
		(size 0.45)
		(drill 0.1)
		(layers "F.Cu" "B.Cu")
		(net 789)
	)
	(segment
		(start 84 107.2)
		(end 84.2 107.4)
		(width 0.1)
		(layer "B.Cu")
		(net 789)
	)
	(segment
		(start 81.450532 102.4)
		(end 83.6 102.4)
		(width 0.1)
		(layer "B.Cu")
		(net 789)
	)
	(segment
		(start 86.8 107.4)
		(end 87.7 108.3)
		(width 0.1)
		(layer "B.Cu")
		(net 789)
	)
	(segment
		(start 80.855532 101.805)
		(end 81.450532 102.4)
		(width 0.1)
		(layer "B.Cu")
		(net 789)
	)
	(segment
		(start 87.7 108.3)
		(end 87.7 110.4)
		(width 0.1)
		(layer "B.Cu")
		(net 789)
	)
	(segment
		(start 84 102.8)
		(end 84 107.2)
		(width 0.1)
		(layer "B.Cu")
		(net 789)
	)
	(segment
		(start 83.6 102.4)
		(end 84 102.8)
		(width 0.1)
		(layer "B.Cu")
		(net 789)
	)
	(segment
		(start 84.2 107.4)
		(end 86.8 107.4)
		(width 0.1)
		(layer "B.Cu")
		(net 789)
	)
	(segment
		(start 100.4 93.2)
		(end 99.3 93.2)
		(width 0.1)
		(layer "In5.Cu")
		(net 789)
	)
	(segment
		(start 95.8 102.2)
		(end 95.8 109.1)
		(width 0.1)
		(layer "In5.Cu")
		(net 789)
	)
	(segment
		(start 97.8 94.7)
		(end 97.8 100.2)
		(width 0.1)
		(layer "In5.Cu")
		(net 789)
	)
	(segment
		(start 95.4 109.5)
		(end 95.8 109.1)
		(width 0.1)
		(layer "In5.Cu")
		(net 789)
	)
	(segment
		(start 95.4 110.2)
		(end 92.7 112.9)
		(width 0.1)
		(layer "In5.Cu")
		(net 789)
	)
	(segment
		(start 95.4 109.5)
		(end 95.4 110.2)
		(width 0.1)
		(layer "In5.Cu")
		(net 789)
	)
	(segment
		(start 95.8 102.2)
		(end 97.8 100.2)
		(width 0.1)
		(layer "In5.Cu")
		(net 789)
	)
	(segment
		(start 89.4 110.4)
		(end 87.7 110.4)
		(width 0.1)
		(layer "In5.Cu")
		(net 789)
	)
	(segment
		(start 97.8 94.7)
		(end 99.3 93.2)
		(width 0.1)
		(layer "In5.Cu")
		(net 789)
	)
	(segment
		(start 92.7 112.9)
		(end 91.9 112.9)
		(width 0.1)
		(layer "In5.Cu")
		(net 789)
	)
	(segment
		(start 91.9 112.9)
		(end 89.4 110.4)
		(width 0.1)
		(layer "In5.Cu")
		(net 789)
	)
	(segment
		(start 103.97663 103.81)
		(end 105.065532 102.721098)
		(width 0.19)
		(layer "F.Cu")
		(net 790)
	)
	(segment
		(start 100.97663 121.285)
		(end 103.085 119.17663)
		(width 0.19)
		(layer "F.Cu")
		(net 790)
	)
	(segment
		(start 93.205 119.1)
		(end 93.52 118.785)
		(width 0.19)
		(layer "F.Cu")
		(net 790)
	)
	(segment
		(start 103.085 119.17663)
		(end 103.085 116.32337)
		(width 0.19)
		(layer "F.Cu")
		(net 790)
	)
	(segment
		(start 101.31 104.80163)
		(end 102.30163 103.81)
		(width 0.19)
		(layer "F.Cu")
		(net 790)
	)
	(segment
		(start 105.065532 84.415)
		(end 105.330532 84.15)
		(width 0.19)
		(layer "F.Cu")
		(net 790)
	)
	(segment
		(start 93.18 119.1)
		(end 93.205 119.1)
		(width 0.19)
		(layer "F.Cu")
		(net 790)
	)
	(segment
		(start 95.12337 118.785)
		(end 97.62337 121.285)
		(width 0.19)
		(layer "F.Cu")
		(net 790)
	)
	(segment
		(start 102.30163 103.81)
		(end 103.97663 103.81)
		(width 0.19)
		(layer "F.Cu")
		(net 790)
	)
	(segment
		(start 101.31 114.54837)
		(end 101.31 104.80163)
		(width 0.19)
		(layer "F.Cu")
		(net 790)
	)
	(segment
		(start 93.52 118.785)
		(end 95.12337 118.785)
		(width 0.19)
		(layer "F.Cu")
		(net 790)
	)
	(segment
		(start 105.065532 102.721098)
		(end 105.065532 84.415)
		(width 0.19)
		(layer "F.Cu")
		(net 790)
	)
	(segment
		(start 103.085 116.32337)
		(end 101.31 114.54837)
		(width 0.19)
		(layer "F.Cu")
		(net 790)
	)
	(segment
		(start 97.62337 121.285)
		(end 100.97663 121.285)
		(width 0.19)
		(layer "F.Cu")
		(net 790)
	)
	(segment
		(start 207.856408 89.155856)
		(end 207.57 89.155856)
		(width 0.19)
		(layer "F.Cu")
		(net 792)
	)
	(segment
		(start 207.858408 89.157856)
		(end 207.856408 89.155856)
		(width 0.19)
		(layer "F.Cu")
		(net 792)
	)
	(segment
		(start 212.115631 89.172856)
		(end 212.100631 89.157856)
		(width 0.19)
		(layer "F.Cu")
		(net 792)
	)
	(segment
		(start 207.57 89.155856)
		(end 207.255 89.470856)
		(width 0.19)
		(layer "F.Cu")
		(net 792)
	)
	(segment
		(start 207.255 89.470856)
		(end 207.23 89.470856)
		(width 0.19)
		(layer "F.Cu")
		(net 792)
	)
	(segment
		(start 212.565632 89.172856)
		(end 212.115631 89.172856)
		(width 0.19)
		(layer "F.Cu")
		(net 792)
	)
	(segment
		(start 212.100631 89.157856)
		(end 207.858408 89.157856)
		(width 0.19)
		(layer "F.Cu")
		(net 792)
	)
	(via
		(at 95.330532 70.65)
		(size 0.45)
		(drill 0.1)
		(layers "F.Cu" "B.Cu")
		(net 793)
	)
	(segment
		(start 86.3 98.44)
		(end 86.275 98.465)
		(width 0.19)
		(layer "B.Cu")
		(net 794)
	)
	(segment
		(start 91.865001 102.203371)
		(end 89.985 100.32337)
		(width 0.19)
		(layer "B.Cu")
		(net 794)
	)
	(segment
		(start 89.985 98.92337)
		(end 89.50163 98.44)
		(width 0.19)
		(layer "B.Cu")
		(net 794)
	)
	(segment
		(start 85.135532 98.465)
		(end 86.275 98.465)
		(width 0.1)
		(layer "B.Cu")
		(net 794)
	)
	(segment
		(start 89.985 100.32337)
		(end 89.985 98.92337)
		(width 0.19)
		(layer "B.Cu")
		(net 794)
	)
	(segment
		(start 84.665532 97.995)
		(end 85.135532 98.465)
		(width 0.1)
		(layer "B.Cu")
		(net 794)
	)
	(segment
		(start 86.3 98.44)
		(end 89.50163 98.44)
		(width 0.19)
		(layer "B.Cu")
		(net 794)
	)
	(segment
		(start 92.180001 103.12)
		(end 92.180001 103.095)
		(width 0.19)
		(layer "B.Cu")
		(net 794)
	)
	(segment
		(start 92.180001 103.095)
		(end 91.865001 102.78)
		(width 0.19)
		(layer "B.Cu")
		(net 794)
	)
	(segment
		(start 91.865001 102.78)
		(end 91.865001 102.203371)
		(width 0.19)
		(layer "B.Cu")
		(net 794)
	)
	(segment
		(start 94.630532 84.15)
		(end 94.75 84.15)
		(width 0.2)
		(layer "F.Cu")
		(net 795)
	)
	(segment
		(start 94.75 84.15)
		(end 95 84.4)
		(width 0.2)
		(layer "F.Cu")
		(net 795)
	)
	(via
		(at 95 84.4)
		(size 0.45)
		(drill 0.1)
		(layers "F.Cu" "B.Cu")
		(net 795)
	)
	(via
		(at 90.830532 82.65)
		(size 0.45)
		(drill 0.1)
		(layers "F.Cu" "B.Cu")
		(net 796)
	)
	(segment
		(start 90.1 81.6)
		(end 90.830532 82.330532)
		(width 0.1)
		(layer "B.Cu")
		(net 796)
	)
	(segment
		(start 90.830532 82.330532)
		(end 90.830532 82.65)
		(width 0.1)
		(layer "B.Cu")
		(net 796)
	)
	(segment
		(start 96.695532 84.415)
		(end 96.695532 84.985)
		(width 0.19)
		(layer "F.Cu")
		(net 797)
	)
	(segment
		(start 96.695532 84.985)
		(end 96.580532 85.1)
		(width 0.19)
		(layer "F.Cu")
		(net 797)
	)
	(segment
		(start 96.430532 84.15)
		(end 96.695532 84.415)
		(width 0.19)
		(layer "F.Cu")
		(net 797)
	)
	(via
		(at 96.580532 85.1)
		(size 0.45)
		(drill 0.1)
		(layers "F.Cu" "B.Cu")
		(net 797)
	)
	(segment
		(start 98.222582 104.284212)
		(end 97.215 103.27663)
		(width 0.19)
		(layer "B.Cu")
		(net 797)
	)
	(segment
		(start 95.965 101.02663)
		(end 95.965 98.82337)
		(width 0.19)
		(layer "B.Cu")
		(net 797)
	)
	(segment
		(start 96.695532 85.215)
		(end 96.580532 85.1)
		(width 0.19)
		(layer "B.Cu")
		(net 797)
	)
	(segment
		(start 85.935532 110.695)
		(end 86.385532 111.145)
		(width 0.19)
		(layer "B.Cu")
		(net 797)
	)
	(segment
		(start 95.965 98.82337)
		(end 96.695532 98.092838)
		(width 0.19)
		(layer "B.Cu")
		(net 797)
	)
	(segment
		(start 95.12337 114.615)
		(end 98.815 110.92337)
		(width 0.19)
		(layer "B.Cu")
		(net 797)
	)
	(segment
		(start 98.815 104.87663)
		(end 98.222582 104.284212)
		(width 0.19)
		(layer "B.Cu")
		(net 797)
	)
	(segment
		(start 98.595 108.335255)
		(end 98.539555 108.335255)
		(width 0.19)
		(layer "B.Cu")
		(net 797)
	)
	(segment
		(start 86.385532 111.145)
		(end 87.20663 111.145)
		(width 0.19)
		(layer "B.Cu")
		(net 797)
	)
	(segment
		(start 98.815 107.565255)
		(end 98.815 107.455255)
		(width 0.19)
		(layer "B.Cu")
		(net 797)
	)
	(segment
		(start 98.319555 108.115255)
		(end 98.319555 108.005255)
		(width 0.19)
		(layer "B.Cu")
		(net 797)
	)
	(segment
		(start 98.815 110.92337)
		(end 98.815 108.555255)
		(width 0.19)
		(layer "B.Cu")
		(net 797)
	)
	(segment
		(start 96.695532 98.092838)
		(end 96.695532 85.215)
		(width 0.19)
		(layer "B.Cu")
		(net 797)
	)
	(segment
		(start 97.215 102.27663)
		(end 95.965 101.02663)
		(width 0.19)
		(layer "B.Cu")
		(net 797)
	)
	(segment
		(start 98.815 107.455255)
		(end 98.815 104.87663)
		(width 0.19)
		(layer "B.Cu")
		(net 797)
	)
	(segment
		(start 97.215 103.27663)
		(end 97.215 102.27663)
		(width 0.19)
		(layer "B.Cu")
		(net 797)
	)
	(segment
		(start 98.539555 107.785255)
		(end 98.595 107.785255)
		(width 0.19)
		(layer "B.Cu")
		(net 797)
	)
	(segment
		(start 90.67663 114.615)
		(end 95.12337 114.615)
		(width 0.19)
		(layer "B.Cu")
		(net 797)
	)
	(segment
		(start 87.20663 111.145)
		(end 90.67663 114.615)
		(width 0.19)
		(layer "B.Cu")
		(net 797)
	)
	(arc
		(start 98.815 108.555255)
		(mid 98.750563 108.399692)
		(end 98.595 108.335255)
		(width 0.19)
		(layer "B.Cu")
		(net 797)
	)
	(arc
		(start 98.319555 108.005255)
		(mid 98.383992 107.849692)
		(end 98.539555 107.785255)
		(width 0.19)
		(layer "B.Cu")
		(net 797)
	)
	(arc
		(start 98.539555 108.335255)
		(mid 98.383992 108.270818)
		(end 98.319555 108.115255)
		(width 0.19)
		(layer "B.Cu")
		(net 797)
	)
	(arc
		(start 98.595 107.785255)
		(mid 98.750563 107.720818)
		(end 98.815 107.565255)
		(width 0.19)
		(layer "B.Cu")
		(net 797)
	)
	(segment
		(start 206.245 92.470856)
		(end 205.93 92.155856)
		(width 0.19)
		(layer "F.Cu")
		(net 799)
	)
	(segment
		(start 203.315 92.155856)
		(end 203.2 92.270856)
		(width 0.19)
		(layer "F.Cu")
		(net 799)
	)
	(segment
		(start 206.27 92.470856)
		(end 206.245 92.470856)
		(width 0.19)
		(layer "F.Cu")
		(net 799)
	)
	(segment
		(start 205.93 92.155856)
		(end 203.315 92.155856)
		(width 0.19)
		(layer "F.Cu")
		(net 799)
	)
	(via
		(at 203.2 92.270856)
		(size 0.45)
		(drill 0.1)
		(layers "F.Cu" "B.Cu")
		(net 799)
	)
	(via
		(at 133.230532 82.65)
		(size 0.45)
		(drill 0.1)
		(layers "F.Cu" "B.Cu")
		(net 799)
	)
	(segment
		(start 132.343044 83.2625)
		(end 131.4625 84.143044)
		(width 0.15)
		(layer "In7.Cu")
		(net 799)
	)
	(segment
		(start 133.543032 82.9625)
		(end 133.543032 82.962512)
		(width 0.15)
		(layer "In7.Cu")
		(net 799)
	)
	(segment
		(start 133.443044 87.9375)
		(end 136.843044 87.9375)
		(width 0.15)
		(layer "In7.Cu")
		(net 799)
	)
	(segment
		(start 133.543032 82.962512)
		(end 133.243044 83.2625)
		(width 0.15)
		(layer "In7.Cu")
		(net 799)
	)
	(segment
		(start 133.230532 82.65)
		(end 133.543032 82.9625)
		(width 0.15)
		(layer "In7.Cu")
		(net 799)
	)
	(segment
		(start 131.4625 84.143044)
		(end 131.4625 85.956956)
		(width 0.15)
		(layer "In7.Cu")
		(net 799)
	)
	(segment
		(start 133.243044 83.2625)
		(end 132.343044 83.2625)
		(width 0.15)
		(layer "In7.Cu")
		(net 799)
	)
	(segment
		(start 131.4625 85.956956)
		(end 133.443044 87.9375)
		(width 0.15)
		(layer "In7.Cu")
		(net 799)
	)
	(segment
		(start 141.0139 92.108356)
		(end 203.0375 92.108356)
		(width 0.15)
		(layer "In7.Cu")
		(net 799)
	)
	(segment
		(start 203.0375 92.108356)
		(end 203.2 92.270856)
		(width 0.15)
		(layer "In7.Cu")
		(net 799)
	)
	(segment
		(start 136.843044 87.9375)
		(end 141.0139 92.108356)
		(width 0.15)
		(layer "In7.Cu")
		(net 799)
	)
	(segment
		(start 215.645 104.526)
		(end 215.645 104.863501)
		(width 0.19)
		(layer "F.Cu")
		(net 800)
	)
	(segment
		(start 230.930532 104.566251)
		(end 230.930532 103.3475)
		(width 0.19)
		(layer "F.Cu")
		(net 800)
	)
	(segment
		(start 215.6605 104.879001)
		(end 215.6605 105.32213)
		(width 0.19)
		(layer "F.Cu")
		(net 800)
	)
	(segment
		(start 220.506499 106.395)
		(end 220.571499 106.46)
		(width 0.19)
		(layer "F.Cu")
		(net 800)
	)
	(segment
		(start 230.865532 104.631251)
		(end 230.930532 104.566251)
		(width 0.19)
		(layer "F.Cu")
		(net 800)
	)
	(segment
		(start 221.756 106.46)
		(end 220.984 106.46)
		(width 0.19)
		(layer "F.Cu")
		(net 800)
	)
	(segment
		(start 216.73337 106.395)
		(end 220.506499 106.395)
		(width 0.19)
		(layer "F.Cu")
		(net 800)
	)
	(segment
		(start 221.756 106.46)
		(end 222.168501 106.46)
		(width 0.19)
		(layer "F.Cu")
		(net 800)
	)
	(segment
		(start 222.168501 106.46)
		(end 222.233501 106.395)
		(width 0.19)
		(layer "F.Cu")
		(net 800)
	)
	(segment
		(start 223.63337 106.395)
		(end 224.17337 106.935)
		(width 0.19)
		(layer "F.Cu")
		(net 800)
	)
	(segment
		(start 215.6605 105.32213)
		(end 216.73337 106.395)
		(width 0.19)
		(layer "F.Cu")
		(net 800)
	)
	(segment
		(start 222.233501 106.395)
		(end 223.63337 106.395)
		(width 0.19)
		(layer "F.Cu")
		(net 800)
	)
	(segment
		(start 229.54663 106.935)
		(end 230.865532 105.616098)
		(width 0.19)
		(layer "F.Cu")
		(net 800)
	)
	(segment
		(start 215.645 104.863501)
		(end 215.6605 104.879001)
		(width 0.19)
		(layer "F.Cu")
		(net 800)
	)
	(segment
		(start 230.865532 105.616098)
		(end 230.865532 104.631251)
		(width 0.19)
		(layer "F.Cu")
		(net 800)
	)
	(segment
		(start 224.17337 106.935)
		(end 229.54663 106.935)
		(width 0.19)
		(layer "F.Cu")
		(net 800)
	)
	(segment
		(start 220.571499 106.46)
		(end 220.984 106.46)
		(width 0.19)
		(layer "F.Cu")
		(net 800)
	)
	(segment
		(start 214.017 100.526)
		(end 213.726 100.526)
		(width 0.1)
		(layer "F.Cu")
		(net 801)
	)
	(segment
		(start 233.430532 103.3475)
		(end 233.430532 105.460532)
		(width 0.1)
		(layer "F.Cu")
		(net 801)
	)
	(segment
		(start 221.754 102.858)
		(end 222.742 102.858)
		(width 0.1)
		(layer "F.Cu")
		(net 801)
	)
	(segment
		(start 213.5 100.3)
		(end 213.726 100.526)
		(width 0.1)
		(layer "F.Cu")
		(net 801)
	)
	(segment
		(start 233.430532 105.460532)
		(end 233.77 105.8)
		(width 0.1)
		(layer "F.Cu")
		(net 801)
	)
	(segment
		(start 220.982 102.858)
		(end 220.458 102.858)
		(width 0.1)
		(layer "F.Cu")
		(net 801)
	)
	(segment
		(start 213.5 100.3)
		(end 212.7 100.3)
		(width 0.1)
		(layer "F.Cu")
		(net 801)
	)
	(segment
		(start 233.77 105.8)
		(end 234.57 105.8)
		(width 0.1)
		(layer "F.Cu")
		(net 801)
	)
	(segment
		(start 222.742 102.858)
		(end 222.8 102.8)
		(width 0.1)
		(layer "F.Cu")
		(net 801)
	)
	(segment
		(start 220.458 102.858)
		(end 220.4 102.8)
		(width 0.1)
		(layer "F.Cu")
		(net 801)
	)
	(segment
		(start 221.754 102.858)
		(end 220.982 102.858)
		(width 0.1)
		(layer "F.Cu")
		(net 801)
	)
	(via
		(at 234.57 105.8)
		(size 0.45)
		(drill 0.1)
		(layers "F.Cu" "B.Cu")
		(net 801)
	)
	(via
		(at 222.8 102.8)
		(size 0.45)
		(drill 0.1)
		(layers "F.Cu" "B.Cu")
		(net 801)
	)
	(via
		(at 220.4 102.8)
		(size 0.45)
		(drill 0.1)
		(layers "F.Cu" "B.Cu")
		(net 801)
	)
	(via
		(at 212.7 100.3)
		(size 0.45)
		(drill 0.1)
		(layers "F.Cu" "B.Cu")
		(net 801)
	)
	(segment
		(start 220.2 102.8)
		(end 220.4 102.8)
		(width 0.1)
		(layer "In5.Cu")
		(net 801)
	)
	(segment
		(start 218.1 98.2)
		(end 219.1 99.2)
		(width 0.1)
		(layer "In5.Cu")
		(net 801)
	)
	(segment
		(start 212.7 100.3)
		(end 214.8 98.2)
		(width 0.1)
		(layer "In5.Cu")
		(net 801)
	)
	(segment
		(start 219.6 103)
		(end 220 103)
		(width 0.1)
		(layer "In5.Cu")
		(net 801)
	)
	(segment
		(start 219.1 99.2)
		(end 219.1 102.5)
		(width 0.1)
		(layer "In5.Cu")
		(net 801)
	)
	(segment
		(start 220 103)
		(end 220.2 102.8)
		(width 0.1)
		(layer "In5.Cu")
		(net 801)
	)
	(segment
		(start 219.1 102.5)
		(end 219.6 103)
		(width 0.1)
		(layer "In5.Cu")
		(net 801)
	)
	(segment
		(start 214.8 98.2)
		(end 218.1 98.2)
		(width 0.1)
		(layer "In5.Cu")
		(net 801)
	)
	(segment
		(start 222.8 102.8)
		(end 224.4 102.8)
		(width 0.1)
		(layer "In7.Cu")
		(net 801)
	)
	(segment
		(start 225.7 104.1)
		(end 225.7 105.7)
		(width 0.1)
		(layer "In7.Cu")
		(net 801)
	)
	(segment
		(start 230.8 106.5)
		(end 231.5 105.8)
		(width 0.1)
		(layer "In7.Cu")
		(net 801)
	)
	(segment
		(start 226.5 106.5)
		(end 230.8 106.5)
		(width 0.1)
		(layer "In7.Cu")
		(net 801)
	)
	(segment
		(start 225.7 105.7)
		(end 226.5 106.5)
		(width 0.1)
		(layer "In7.Cu")
		(net 801)
	)
	(segment
		(start 224.4 102.8)
		(end 225.7 104.1)
		(width 0.1)
		(layer "In7.Cu")
		(net 801)
	)
	(segment
		(start 231.5 105.8)
		(end 234.57 105.8)
		(width 0.1)
		(layer "In7.Cu")
		(net 801)
	)
	(segment
		(start 220.506499 106.025)
		(end 220.571499 105.96)
		(width 0.19)
		(layer "F.Cu")
		(net 802)
	)
	(segment
		(start 216.046 104.526)
		(end 216.046 104.863501)
		(width 0.19)
		(layer "F.Cu")
		(net 802)
	)
	(segment
		(start 230.171186 105.787182)
		(end 230.307766 105.650604)
		(width 0.19)
		(layer "F.Cu")
		(net 802)
	)
	(segment
		(start 222.168501 105.96)
		(end 222.233501 106.025)
		(width 0.19)
		(layer "F.Cu")
		(net 802)
	)
	(segment
		(start 216.046 104.863501)
		(end 216.0305 104.879001)
		(width 0.19)
		(layer "F.Cu")
		(net 802)
	)
	(segment
		(start 216.0305 105.16887)
		(end 216.88663 106.025)
		(width 0.19)
		(layer "F.Cu")
		(net 802)
	)
	(segment
		(start 230.430532 104.566251)
		(end 230.430532 103.3475)
		(width 0.19)
		(layer "F.Cu")
		(net 802)
	)
	(segment
		(start 216.88663 106.025)
		(end 220.506499 106.025)
		(width 0.19)
		(layer "F.Cu")
		(net 802)
	)
	(segment
		(start 216.0305 104.879001)
		(end 216.0305 105.16887)
		(width 0.19)
		(layer "F.Cu")
		(net 802)
	)
	(segment
		(start 221.756 105.96)
		(end 222.168501 105.96)
		(width 0.19)
		(layer "F.Cu")
		(net 802)
	)
	(segment
		(start 229.39337 106.565)
		(end 230.171186 105.787182)
		(width 0.19)
		(layer "F.Cu")
		(net 802)
	)
	(segment
		(start 226.789095 106.565)
		(end 229.39337 106.565)
		(width 0.19)
		(layer "F.Cu")
		(net 802)
	)
	(segment
		(start 226.589095 105.980284)
		(end 226.589095 106.365)
		(width 0.19)
		(layer "F.Cu")
		(net 802)
	)
	(segment
		(start 220.571499 105.96)
		(end 220.984 105.96)
		(width 0.19)
		(layer "F.Cu")
		(net 802)
	)
	(segment
		(start 224.32663 106.565)
		(end 225.889095 106.565)
		(width 0.19)
		(layer "F.Cu")
		(net 802)
	)
	(segment
		(start 226.089095 106.365)
		(end 226.089095 105.980284)
		(width 0.19)
		(layer "F.Cu")
		(net 802)
	)
	(segment
		(start 223.78663 106.025)
		(end 224.32663 106.565)
		(width 0.19)
		(layer "F.Cu")
		(net 802)
	)
	(segment
		(start 226.289095 105.780284)
		(end 226.389095 105.780284)
		(width 0.19)
		(layer "F.Cu")
		(net 802)
	)
	(segment
		(start 222.233501 106.025)
		(end 223.78663 106.025)
		(width 0.19)
		(layer "F.Cu")
		(net 802)
	)
	(segment
		(start 220.984 105.96)
		(end 221.756 105.96)
		(width 0.19)
		(layer "F.Cu")
		(net 802)
	)
	(segment
		(start 230.495532 105.462838)
		(end 230.495532 104.631251)
		(width 0.19)
		(layer "F.Cu")
		(net 802)
	)
	(segment
		(start 230.307766 105.650604)
		(end 230.495532 105.462838)
		(width 0.19)
		(layer "F.Cu")
		(net 802)
	)
	(segment
		(start 230.495532 104.631251)
		(end 230.430532 104.566251)
		(width 0.19)
		(layer "F.Cu")
		(net 802)
	)
	(arc
		(start 226.089095 105.980284)
		(mid 226.147674 105.838863)
		(end 226.289095 105.780284)
		(width 0.19)
		(layer "F.Cu")
		(net 802)
	)
	(arc
		(start 225.889095 106.565)
		(mid 226.030516 106.506421)
		(end 226.089095 106.365)
		(width 0.19)
		(layer "F.Cu")
		(net 802)
	)
	(arc
		(start 226.389095 105.780284)
		(mid 226.530516 105.838863)
		(end 226.589095 105.980284)
		(width 0.19)
		(layer "F.Cu")
		(net 802)
	)
	(arc
		(start 226.589095 106.365)
		(mid 226.647674 106.506421)
		(end 226.789095 106.565)
		(width 0.19)
		(layer "F.Cu")
		(net 802)
	)
	(segment
		(start 217.94837 102.94)
		(end 218.665 102.22337)
		(width 0.19)
		(layer "F.Cu")
		(net 804)
	)
	(segment
		(start 220.506499 99.825)
		(end 220.571499 99.76)
		(width 0.19)
		(layer "F.Cu")
		(net 804)
	)
	(segment
		(start 216.820001 102.925)
		(end 216.835001 102.94)
		(width 0.19)
		(layer "F.Cu")
		(net 804)
	)
	(segment
		(start 234.495532 99.715)
		(end 234.380532 99.6)
		(width 0.19)
		(layer "F.Cu")
		(net 804)
	)
	(segment
		(start 218.665 100.84837)
		(end 219.68837 99.825)
		(width 0.19)
		(layer "F.Cu")
		(net 804)
	)
	(segment
		(start 224.385 99.825)
		(end 224.5 99.71)
		(width 0.19)
		(layer "F.Cu")
		(net 804)
	)
	(segment
		(start 222.168501 99.76)
		(end 222.233501 99.825)
		(width 0.19)
		(layer "F.Cu")
		(net 804)
	)
	(segment
		(start 221.756 99.76)
		(end 222.168501 99.76)
		(width 0.19)
		(layer "F.Cu")
		(net 804)
	)
	(segment
		(start 222.233501 99.825)
		(end 224.385 99.825)
		(width 0.19)
		(layer "F.Cu")
		(net 804)
	)
	(segment
		(start 219.68837 99.825)
		(end 220.506499 99.825)
		(width 0.19)
		(layer "F.Cu")
		(net 804)
	)
	(segment
		(start 234.430532 101.0725)
		(end 234.430532 100.385)
		(width 0.19)
		(layer "F.Cu")
		(net 804)
	)
	(segment
		(start 216.445 102.925)
		(end 216.820001 102.925)
		(width 0.19)
		(layer "F.Cu")
		(net 804)
	)
	(segment
		(start 234.430532 100.385)
		(end 234.495532 100.32)
		(width 0.19)
		(layer "F.Cu")
		(net 804)
	)
	(segment
		(start 221.756 99.76)
		(end 220.984 99.76)
		(width 0.19)
		(layer "F.Cu")
		(net 804)
	)
	(segment
		(start 218.665 102.22337)
		(end 218.665 100.84837)
		(width 0.19)
		(layer "F.Cu")
		(net 804)
	)
	(segment
		(start 220.571499 99.76)
		(end 220.984 99.76)
		(width 0.19)
		(layer "F.Cu")
		(net 804)
	)
	(segment
		(start 216.835001 102.94)
		(end 217.94837 102.94)
		(width 0.19)
		(layer "F.Cu")
		(net 804)
	)
	(segment
		(start 234.495532 100.32)
		(end 234.495532 99.715)
		(width 0.19)
		(layer "F.Cu")
		(net 804)
	)
	(via
		(at 234.380532 99.6)
		(size 0.45)
		(drill 0.1)
		(layers "F.Cu" "B.Cu")
		(net 804)
	)
	(via
		(at 224.5 99.71)
		(size 0.45)
		(drill 0.1)
		(layers "F.Cu" "B.Cu")
		(net 804)
	)
	(segment
		(start 226.961646 96.6375)
		(end 228.247402 96.6375)
		(width 0.15)
		(layer "In7.Cu")
		(net 804)
	)
	(segment
		(start 225.585646 97.30195)
		(end 225.671646 97.30195)
		(width 0.15)
		(layer "In7.Cu")
		(net 804)
	)
	(segment
		(start 234.543032 99.4375)
		(end 234.380532 99.6)
		(width 0.15)
		(layer "In7.Cu")
		(net 804)
	)
	(segment
		(start 226.39385 96.929704)
		(end 226.531646 96.929704)
		(width 0.15)
		(layer "In7.Cu")
		(net 804)
	)
	(segment
		(start 234.543032 98.931944)
		(end 234.543032 99.4375)
		(width 0.15)
		(layer "In7.Cu")
		(net 804)
	)
	(segment
		(start 224.3375 99.8725)
		(end 223.861412 99.8725)
		(width 0.15)
		(layer "In7.Cu")
		(net 804)
	)
	(segment
		(start 225.413646 96.8095)
		(end 225.413646 97.12995)
		(width 0.15)
		(layer "In7.Cu")
		(net 804)
	)
	(segment
		(start 223.861412 99.8725)
		(end 223.3875 99.398588)
		(width 0.15)
		(layer "In7.Cu")
		(net 804)
	)
	(segment
		(start 224.5 99.71)
		(end 224.3375 99.8725)
		(width 0.15)
		(layer "In7.Cu")
		(net 804)
	)
	(segment
		(start 226.82385 96.6375)
		(end 226.961646 96.6375)
		(width 0.15)
		(layer "In7.Cu")
		(net 804)
	)
	(segment
		(start 223.3875 98.056956)
		(end 224.806956 96.6375)
		(width 0.15)
		(layer "In7.Cu")
		(net 804)
	)
	(segment
		(start 228.247402 96.6375)
		(end 232.248588 96.6375)
		(width 0.15)
		(layer "In7.Cu")
		(net 804)
	)
	(segment
		(start 232.248588 96.6375)
		(end 234.543032 98.931944)
		(width 0.15)
		(layer "In7.Cu")
		(net 804)
	)
	(segment
		(start 224.806956 96.6375)
		(end 225.241646 96.6375)
		(width 0.15)
		(layer "In7.Cu")
		(net 804)
	)
	(segment
		(start 225.843646 97.12995)
		(end 225.843646 96.8095)
		(width 0.15)
		(layer "In7.Cu")
		(net 804)
	)
	(segment
		(start 223.3875 99.398588)
		(end 223.3875 98.056956)
		(width 0.15)
		(layer "In7.Cu")
		(net 804)
	)
	(segment
		(start 226.015646 96.6375)
		(end 226.101646 96.6375)
		(width 0.15)
		(layer "In7.Cu")
		(net 804)
	)
	(arc
		(start 226.247748 96.783602)
		(mid 226.29054 96.886912)
		(end 226.39385 96.929704)
		(width 0.15)
		(layer "In7.Cu")
		(net 804)
	)
	(arc
		(start 225.843646 96.8095)
		(mid 225.894024 96.687878)
		(end 226.015646 96.6375)
		(width 0.15)
		(layer "In7.Cu")
		(net 804)
	)
	(arc
		(start 226.531646 96.929704)
		(mid 226.634956 96.886912)
		(end 226.677748 96.783602)
		(width 0.15)
		(layer "In7.Cu")
		(net 804)
	)
	(arc
		(start 226.101646 96.6375)
		(mid 226.204956 96.680292)
		(end 226.247748 96.783602)
		(width 0.15)
		(layer "In7.Cu")
		(net 804)
	)
	(arc
		(start 225.671646 97.30195)
		(mid 225.793268 97.251572)
		(end 225.843646 97.12995)
		(width 0.15)
		(layer "In7.Cu")
		(net 804)
	)
	(arc
		(start 225.413646 97.12995)
		(mid 225.464024 97.251572)
		(end 225.585646 97.30195)
		(width 0.15)
		(layer "In7.Cu")
		(net 804)
	)
	(arc
		(start 226.677748 96.783602)
		(mid 226.72054 96.680292)
		(end 226.82385 96.6375)
		(width 0.15)
		(layer "In7.Cu")
		(net 804)
	)
	(arc
		(start 225.241646 96.6375)
		(mid 225.363268 96.687878)
		(end 225.413646 96.8095)
		(width 0.15)
		(layer "In7.Cu")
		(net 804)
	)
	(segment
		(start 231.930532 99.660532)
		(end 231.47 99.2)
		(width 0.1)
		(layer "F.Cu")
		(net 806)
	)
	(segment
		(start 214.046 100.925)
		(end 213.725 100.925)
		(width 0.1)
		(layer "F.Cu")
		(net 806)
	)
	(segment
		(start 221.754 103.358)
		(end 222.558 103.358)
		(width 0.1)
		(layer "F.Cu")
		(net 806)
	)
	(segment
		(start 213.725 100.925)
		(end 213.5 100.7)
		(width 0.1)
		(layer "F.Cu")
		(net 806)
	)
	(segment
		(start 222.558 103.358)
		(end 222.6 103.4)
		(width 0.1)
		(layer "F.Cu")
		(net 806)
	)
	(segment
		(start 220.242 103.358)
		(end 220.2 103.4)
		(width 0.1)
		(layer "F.Cu")
		(net 806)
	)
	(segment
		(start 220.982 103.358)
		(end 220.242 103.358)
		(width 0.1)
		(layer "F.Cu")
		(net 806)
	)
	(segment
		(start 220.982 103.358)
		(end 221.754 103.358)
		(width 0.1)
		(layer "F.Cu")
		(net 806)
	)
	(segment
		(start 213.5 100.7)
		(end 213.2 100.7)
		(width 0.1)
		(layer "F.Cu")
		(net 806)
	)
	(segment
		(start 231.930532 101.0725)
		(end 231.930532 99.660532)
		(width 0.1)
		(layer "F.Cu")
		(net 806)
	)
	(via
		(at 231.47 99.2)
		(size 0.45)
		(drill 0.1)
		(layers "F.Cu" "B.Cu")
		(net 806)
	)
	(via
		(at 220.2 103.4)
		(size 0.45)
		(drill 0.1)
		(layers "F.Cu" "B.Cu")
		(net 806)
	)
	(via
		(at 213.2 100.7)
		(size 0.45)
		(drill 0.1)
		(layers "F.Cu" "B.Cu")
		(net 806)
	)
	(via
		(at 222.6 103.4)
		(size 0.45)
		(drill 0.1)
		(layers "F.Cu" "B.Cu")
		(net 806)
	)
	(segment
		(start 217.7 98.5)
		(end 218.8 99.6)
		(width 0.1)
		(layer "In5.Cu")
		(net 806)
	)
	(segment
		(start 219.5 103.4)
		(end 220.2 103.4)
		(width 0.1)
		(layer "In5.Cu")
		(net 806)
	)
	(segment
		(start 213.2 100.7)
		(end 215.4 98.5)
		(width 0.1)
		(layer "In5.Cu")
		(net 806)
	)
	(segment
		(start 218.8 102.7)
		(end 219.5 103.4)
		(width 0.1)
		(layer "In5.Cu")
		(net 806)
	)
	(segment
		(start 218.8 99.6)
		(end 218.8 102.7)
		(width 0.1)
		(layer "In5.Cu")
		(net 806)
	)
	(segment
		(start 215.4 98.5)
		(end 217.7 98.5)
		(width 0.1)
		(layer "In5.Cu")
		(net 806)
	)
	(segment
		(start 222.2 100.5)
		(end 222.9 100.5)
		(width 0.1)
		(layer "In7.Cu")
		(net 806)
	)
	(segment
		(start 230.27 100.4)
		(end 231.47 99.2)
		(width 0.1)
		(layer "In7.Cu")
		(net 806)
	)
	(segment
		(start 222.1 103.4)
		(end 221.8 103.1)
		(width 0.1)
		(layer "In7.Cu")
		(net 806)
	)
	(segment
		(start 223.7 101.3)
		(end 227 101.3)
		(width 0.1)
		(layer "In7.Cu")
		(net 806)
	)
	(segment
		(start 221.8 100.9)
		(end 222.2 100.5)
		(width 0.1)
		(layer "In7.Cu")
		(net 806)
	)
	(segment
		(start 222.9 100.5)
		(end 223.7 101.3)
		(width 0.1)
		(layer "In7.Cu")
		(net 806)
	)
	(segment
		(start 222.6 103.4)
		(end 222.1 103.4)
		(width 0.1)
		(layer "In7.Cu")
		(net 806)
	)
	(segment
		(start 227 101.3)
		(end 227.9 100.4)
		(width 0.1)
		(layer "In7.Cu")
		(net 806)
	)
	(segment
		(start 227.9 100.4)
		(end 230.27 100.4)
		(width 0.1)
		(layer "In7.Cu")
		(net 806)
	)
	(segment
		(start 221.8 103.1)
		(end 221.8 100.9)
		(width 0.1)
		(layer "In7.Cu")
		(net 806)
	)
	(segment
		(start 219.035 102.37663)
		(end 219.035 101.00163)
		(width 0.19)
		(layer "F.Cu")
		(net 807)
	)
	(segment
		(start 234.930532 100.385)
		(end 234.865532 100.32)
		(width 0.19)
		(layer "F.Cu")
		(net 807)
	)
	(segment
		(start 234.930532 101.0725)
		(end 234.930532 100.385)
		(width 0.19)
		(layer "F.Cu")
		(net 807)
	)
	(segment
		(start 220.506499 100.195)
		(end 220.571499 100.26)
		(width 0.19)
		(layer "F.Cu")
		(net 807)
	)
	(segment
		(start 216.445 103.325)
		(end 216.820001 103.325)
		(width 0.19)
		(layer "F.Cu")
		(net 807)
	)
	(segment
		(start 234.865532 100.32)
		(end 234.865532 99.715)
		(width 0.19)
		(layer "F.Cu")
		(net 807)
	)
	(segment
		(start 222.233501 100.195)
		(end 224.385 100.195)
		(width 0.19)
		(layer "F.Cu")
		(net 807)
	)
	(segment
		(start 218.10163 103.31)
		(end 219.035 102.37663)
		(width 0.19)
		(layer "F.Cu")
		(net 807)
	)
	(segment
		(start 219.035 101.00163)
		(end 219.84163 100.195)
		(width 0.19)
		(layer "F.Cu")
		(net 807)
	)
	(segment
		(start 222.168501 100.26)
		(end 222.233501 100.195)
		(width 0.19)
		(layer "F.Cu")
		(net 807)
	)
	(segment
		(start 220.571499 100.26)
		(end 220.984 100.26)
		(width 0.19)
		(layer "F.Cu")
		(net 807)
	)
	(segment
		(start 216.835001 103.31)
		(end 218.10163 103.31)
		(width 0.19)
		(layer "F.Cu")
		(net 807)
	)
	(segment
		(start 219.84163 100.195)
		(end 220.506499 100.195)
		(width 0.19)
		(layer "F.Cu")
		(net 807)
	)
	(segment
		(start 234.865532 99.715)
		(end 234.980532 99.6)
		(width 0.19)
		(layer "F.Cu")
		(net 807)
	)
	(segment
		(start 220.984 100.26)
		(end 221.756 100.26)
		(width 0.19)
		(layer "F.Cu")
		(net 807)
	)
	(segment
		(start 216.820001 103.325)
		(end 216.835001 103.31)
		(width 0.19)
		(layer "F.Cu")
		(net 807)
	)
	(segment
		(start 224.385 100.195)
		(end 224.5 100.31)
		(width 0.19)
		(layer "F.Cu")
		(net 807)
	)
	(segment
		(start 221.756 100.26)
		(end 222.168501 100.26)
		(width 0.19)
		(layer "F.Cu")
		(net 807)
	)
	(via
		(at 224.5 100.31)
		(size 0.45)
		(drill 0.1)
		(layers "F.Cu" "B.Cu")
		(net 807)
	)
	(via
		(at 234.980532 99.6)
		(size 0.45)
		(drill 0.1)
		(layers "F.Cu" "B.Cu")
		(net 807)
	)
	(segment
		(start 234.818032 98.818032)
		(end 232.3625 96.3625)
		(width 0.15)
		(layer "In7.Cu")
		(net 807)
	)
	(segment
		(start 232.3625 96.3625)
		(end 224.693044 96.3625)
		(width 0.15)
		(layer "In7.Cu")
		(net 807)
	)
	(segment
		(start 223.7475 100.1475)
		(end 224.3375 100.1475)
		(width 0.15)
		(layer "In7.Cu")
		(net 807)
	)
	(segment
		(start 234.980532 99.6)
		(end 234.818032 99.4375)
		(width 0.15)
		(layer "In7.Cu")
		(net 807)
	)
	(segment
		(start 234.818032 99.4375)
		(end 234.818032 98.818032)
		(width 0.15)
		(layer "In7.Cu")
		(net 807)
	)
	(segment
		(start 224.3375 100.1475)
		(end 224.5 100.31)
		(width 0.15)
		(layer "In7.Cu")
		(net 807)
	)
	(segment
		(start 223.1125 99.5125)
		(end 223.7475 100.1475)
		(width 0.15)
		(layer "In7.Cu")
		(net 807)
	)
	(segment
		(start 224.693044 96.3625)
		(end 223.1125 97.943044)
		(width 0.15)
		(layer "In7.Cu")
		(net 807)
	)
	(segment
		(start 223.1125 97.943044)
		(end 223.1125 99.5125)
		(width 0.15)
		(layer "In7.Cu")
		(net 807)
	)
	(segment
		(start 197.9 98)
		(end 198.265 97.635)
		(width 0.1)
		(layer "F.Cu")
		(net 810)
	)
	(segment
		(start 197.9 98.34)
		(end 197.9 98)
		(width 0.1)
		(layer "F.Cu")
		(net 810)
	)
	(segment
		(start 198.902 97.672)
		(end 198.939 97.635)
		(width 0.1)
		(layer "F.Cu")
		(net 810)
	)
	(segment
		(start 198.265 97.635)
		(end 198.939 97.635)
		(width 0.1)
		(layer "F.Cu")
		(net 810)
	)
	(via
		(at 198.939 97.635)
		(size 0.45)
		(drill 0.1)
		(layers "F.Cu" "B.Cu")
		(net 810)
	)
	(segment
		(start 194.8 99.5)
		(end 194.8 101.27279)
		(width 0.1)
		(layer "B.Cu")
		(net 810)
	)
	(segment
		(start 187.8 122.8)
		(end 187.8 122.18)
		(width 0.1)
		(layer "B.Cu")
		(net 810)
	)
	(segment
		(start 193.7 89.5)
		(end 193.7 88.28)
		(width 0.1)
		(layer "B.Cu")
		(net 810)
	)
	(segment
		(start 193.3 92.7)
		(end 193.3 89.9)
		(width 0.1)
		(layer "B.Cu")
		(net 810)
	)
	(segment
		(start 194.8 101.27279)
		(end 193.599999 102.472791)
		(width 0.1)
		(layer "B.Cu")
		(net 810)
	)
	(segment
		(start 194.8 99.5)
		(end 194.8 99.4)
		(width 0.1)
		(layer "B.Cu")
		(net 810)
	)
	(segment
		(start 193.599999 121.400001)
		(end 191.6 123.4)
		(width 0.1)
		(layer "B.Cu")
		(net 810)
	)
	(segment
		(start 194.8 99.5)
		(end 194.9 99.4)
		(width 0.1)
		(layer "B.Cu")
		(net 810)
	)
	(segment
		(start 188.4 123.4)
		(end 187.8 122.8)
		(width 0.1)
		(layer "B.Cu")
		(net 810)
	)
	(segment
		(start 191.6 123.4)
		(end 188.4 123.4)
		(width 0.1)
		(layer "B.Cu")
		(net 810)
	)
	(segment
		(start 194.8 99.5)
		(end 194.7 99.4)
		(width 0.1)
		(layer "B.Cu")
		(net 810)
	)
	(segment
		(start 193.3 89.9)
		(end 193.7 89.5)
		(width 0.1)
		(layer "B.Cu")
		(net 810)
	)
	(segment
		(start 194.9 99.4)
		(end 197.174 99.4)
		(width 0.1)
		(layer "B.Cu")
		(net 810)
	)
	(segment
		(start 190.9 98.3)
		(end 190.9 95.1)
		(width 0.1)
		(layer "B.Cu")
		(net 810)
	)
	(segment
		(start 194.7 99.4)
		(end 194.8 99.4)
		(width 0.1)
		(layer "B.Cu")
		(net 810)
	)
	(segment
		(start 194.8 99.4)
		(end 194.9 99.4)
		(width 0.1)
		(layer "B.Cu")
		(net 810)
	)
	(segment
		(start 194.7 99.4)
		(end 192 99.4)
		(width 0.1)
		(layer "B.Cu")
		(net 810)
	)
	(segment
		(start 197.174 99.4)
		(end 198.939 97.635)
		(width 0.1)
		(layer "B.Cu")
		(net 810)
	)
	(segment
		(start 190.9 95.1)
		(end 193.3 92.7)
		(width 0.1)
		(layer "B.Cu")
		(net 810)
	)
	(segment
		(start 193.599999 102.472791)
		(end 193.599999 121.400001)
		(width 0.1)
		(layer "B.Cu")
		(net 810)
	)
	(segment
		(start 192 99.4)
		(end 190.9 98.3)
		(width 0.1)
		(layer "B.Cu")
		(net 810)
	)
	(segment
		(start 196.6 97.6)
		(end 196.9 97.9)
		(width 0.1)
		(layer "F.Cu")
		(net 811)
	)
	(segment
		(start 196.4 97.6)
		(end 196.6 97.6)
		(width 0.1)
		(layer "F.Cu")
		(net 811)
	)
	(segment
		(start 196.9 97.9)
		(end 196.9 98.34)
		(width 0.1)
		(layer "F.Cu")
		(net 811)
	)
	(via
		(at 196.4 97.6)
		(size 0.45)
		(drill 0.1)
		(layers "F.Cu" "B.Cu")
		(net 811)
	)
	(via
		(at 193.5 101.2)
		(size 0.45)
		(drill 0.1)
		(layers "F.Cu" "B.Cu")
		(net 811)
	)
	(segment
		(start 190.3 122.8)
		(end 190 122.5)
		(width 0.1)
		(layer "B.Cu")
		(net 811)
	)
	(segment
		(start 190 122.5)
		(end 190 122.18)
		(width 0.1)
		(layer "B.Cu")
		(net 811)
	)
	(segment
		(start 190.3 122.8)
		(end 191.351474 122.8)
		(width 0.1)
		(layer "B.Cu")
		(net 811)
	)
	(segment
		(start 195.775 97.01)
		(end 194.79 97.01)
		(width 0.1)
		(layer "B.Cu")
		(net 811)
	)
	(segment
		(start 193.5 101.6)
		(end 193.5 101.2)
		(width 0.1)
		(layer "B.Cu")
		(net 811)
	)
	(segment
		(start 192.999999 121.151475)
		(end 192.999999 102.100001)
		(width 0.1)
		(layer "B.Cu")
		(net 811)
	)
	(segment
		(start 196.4 97.635)
		(end 195.775 97.01)
		(width 0.1)
		(layer "B.Cu")
		(net 811)
	)
	(segment
		(start 194.79 97.01)
		(end 194.49 96.71)
		(width 0.1)
		(layer "B.Cu")
		(net 811)
	)
	(segment
		(start 194.49 96.71)
		(end 194.49 90.01)
		(width 0.1)
		(layer "B.Cu")
		(net 811)
	)
	(segment
		(start 194.49 90.01)
		(end 195.9 88.6)
		(width 0.1)
		(layer "B.Cu")
		(net 811)
	)
	(segment
		(start 192.999999 102.100001)
		(end 193.5 101.6)
		(width 0.1)
		(layer "B.Cu")
		(net 811)
	)
	(segment
		(start 195.9 88.6)
		(end 195.9 88.28)
		(width 0.1)
		(layer "B.Cu")
		(net 811)
	)
	(segment
		(start 191.351474 122.8)
		(end 192.999999 121.151475)
		(width 0.1)
		(layer "B.Cu")
		(net 811)
	)
	(segment
		(start 196.4 97.7)
		(end 196.4 97.6)
		(width 0.1)
		(layer "In5.Cu")
		(net 811)
	)
	(segment
		(start 193.5 100.6)
		(end 196.4 97.7)
		(width 0.1)
		(layer "In5.Cu")
		(net 811)
	)
	(segment
		(start 193.5 101.2)
		(end 193.5 100.6)
		(width 0.1)
		(layer "In5.Cu")
		(net 811)
	)
	(via
		(at 192.9 101.6)
		(size 0.45)
		(drill 0.1)
		(layers "F.Cu" "B.Cu")
		(net 812)
	)
	(via
		(at 195.1 96.4)
		(size 0.45)
		(drill 0.1)
		(layers "F.Cu" "B.Cu")
		(net 812)
	)
	(segment
		(start 195.9 89.2)
		(end 196.4 89.2)
		(width 0.1)
		(layer "B.Cu")
		(net 812)
	)
	(segment
		(start 196.4 89.2)
		(end 197 88.6)
		(width 0.1)
		(layer "B.Cu")
		(net 812)
	)
	(segment
		(start 195.13 89.97)
		(end 195.9 89.2)
		(width 0.1)
		(layer "B.Cu")
		(net 812)
	)
	(segment
		(start 195.13 96.366)
		(end 195.13 89.97)
		(width 0.1)
		(layer "B.Cu")
		(net 812)
	)
	(segment
		(start 192.7 121.02721)
		(end 191.54721 122.18)
		(width 0.1)
		(layer "B.Cu")
		(net 812)
	)
	(segment
		(start 191.12 122.18)
		(end 191.54721 122.18)
		(width 0.1)
		(layer "B.Cu")
		(net 812)
	)
	(segment
		(start 192.7 101.8)
		(end 192.9 101.6)
		(width 0.1)
		(layer "B.Cu")
		(net 812)
	)
	(segment
		(start 197 88.6)
		(end 197 88.28)
		(width 0.1)
		(layer "B.Cu")
		(net 812)
	)
	(segment
		(start 192.7 121.02721)
		(end 192.7 101.8)
		(width 0.1)
		(layer "B.Cu")
		(net 812)
	)
	(segment
		(start 192.9 98.6)
		(end 195.1 96.4)
		(width 0.1)
		(layer "In5.Cu")
		(net 812)
	)
	(segment
		(start 192.9 101.6)
		(end 192.9 98.6)
		(width 0.1)
		(layer "In5.Cu")
		(net 812)
	)
	(segment
		(start 231.930532 91.360532)
		(end 232.67 92.1)
		(width 0.19)
		(layer "F.Cu")
		(net 815)
	)
	(segment
		(start 219.56486 95.597)
		(end 220.075457 95.597)
		(width 0.19)
		(layer "F.Cu")
		(net 815)
	)
	(segment
		(start 221.787132 95.662)
		(end 222.647 95.662)
		(width 0.19)
		(layer "F.Cu")
		(net 815)
	)
	(segment
		(start 215.063632 92.670856)
		(end 215.063632 93.120857)
		(width 0.19)
		(layer "F.Cu")
		(net 815)
	)
	(segment
		(start 218.12486 96.09966)
		(end 218.21486 96.09966)
		(width 0.19)
		(layer "F.Cu")
		(net 815)
	)
	(segment
		(start 227.704989 93.585)
		(end 227.614989 93.585)
		(width 0.19)
		(layer "F.Cu")
		(net 815)
	)
	(segment
		(start 227.884989 93.905)
		(end 227.884989 93.765)
		(width 0.19)
		(layer "F.Cu")
		(net 815)
	)
	(segment
		(start 215.078632 94.540262)
		(end 216.13537 95.597)
		(width 0.19)
		(layer "F.Cu")
		(net 815)
	)
	(segment
		(start 219.02486 96.099681)
		(end 219.11486 96.099681)
		(width 0.19)
		(layer "F.Cu")
		(net 815)
	)
	(segment
		(start 219.47486 95.597)
		(end 219.56486 95.597)
		(width 0.19)
		(layer "F.Cu")
		(net 815)
	)
	(segment
		(start 229.684989 93.905)
		(end 229.684989 93.765)
		(width 0.19)
		(layer "F.Cu")
		(net 815)
	)
	(segment
		(start 226.714989 93.585)
		(end 226.193011 93.585)
		(width 0.19)
		(layer "F.Cu")
		(net 815)
	)
	(segment
		(start 231.034989 93.765)
		(end 231.034989 93.905)
		(width 0.19)
		(layer "F.Cu")
		(net 815)
	)
	(segment
		(start 226.08826 93.585)
		(end 224.12926 95.544)
		(width 0.19)
		(layer "F.Cu")
		(net 815)
	)
	(segment
		(start 226.193011 93.585)
		(end 226.08826 93.585)
		(width 0.19)
		(layer "F.Cu")
		(net 815)
	)
	(segment
		(start 228.334989 93.765)
		(end 228.334989 93.905)
		(width 0.19)
		(layer "F.Cu")
		(net 815)
	)
	(segment
		(start 224.12926 95.544)
		(end 222.765 95.544)
		(width 0.19)
		(layer "F.Cu")
		(net 815)
	)
	(segment
		(start 230.854989 94.085)
		(end 230.764989 94.085)
		(width 0.19)
		(layer "F.Cu")
		(net 815)
	)
	(segment
		(start 222.647 95.662)
		(end 222.65 95.659)
		(width 0.19)
		(layer "F.Cu")
		(net 815)
	)
	(segment
		(start 231.64663 93.585)
		(end 231.214989 93.585)
		(width 0.19)
		(layer "F.Cu")
		(net 815)
	)
	(segment
		(start 215.063632 93.120857)
		(end 215.078632 93.135857)
		(width 0.19)
		(layer "F.Cu")
		(net 815)
	)
	(segment
		(start 220.075457 95.597)
		(end 220.537631 95.597)
		(width 0.19)
		(layer "F.Cu")
		(net 815)
	)
	(segment
		(start 215.078632 93.135857)
		(end 215.078632 94.540262)
		(width 0.19)
		(layer "F.Cu")
		(net 815)
	)
	(segment
		(start 218.84486 95.777)
		(end 218.84486 95.919681)
		(width 0.19)
		(layer "F.Cu")
		(net 815)
	)
	(segment
		(start 220.602631 95.662)
		(end 221.015132 95.662)
		(width 0.19)
		(layer "F.Cu")
		(net 815)
	)
	(segment
		(start 216.13537 95.597)
		(end 216.86486 95.597)
		(width 0.19)
		(layer "F.Cu")
		(net 815)
	)
	(segment
		(start 226.804989 93.585)
		(end 226.714989 93.585)
		(width 0.19)
		(layer "F.Cu")
		(net 815)
	)
	(segment
		(start 221.015132 95.662)
		(end 221.787132 95.662)
		(width 0.19)
		(layer "F.Cu")
		(net 815)
	)
	(segment
		(start 218.39486 95.91966)
		(end 218.39486 95.777)
		(width 0.19)
		(layer "F.Cu")
		(net 815)
	)
	(segment
		(start 228.154989 94.085)
		(end 228.064989 94.085)
		(width 0.19)
		(layer "F.Cu")
		(net 815)
	)
	(segment
		(start 232.67 92.56163)
		(end 231.64663 93.585)
		(width 0.19)
		(layer "F.Cu")
		(net 815)
	)
	(segment
		(start 217.04486 95.777)
		(end 217.04486 95.91966)
		(width 0.19)
		(layer "F.Cu")
		(net 815)
	)
	(segment
		(start 217.49486 95.91966)
		(end 217.49486 95.777)
		(width 0.19)
		(layer "F.Cu")
		(net 815)
	)
	(segment
		(start 226.984989 93.905)
		(end 226.984989 93.765)
		(width 0.19)
		(layer "F.Cu")
		(net 815)
	)
	(segment
		(start 217.67486 95.597)
		(end 217.76486 95.597)
		(width 0.19)
		(layer "F.Cu")
		(net 815)
	)
	(segment
		(start 230.584989 93.905)
		(end 230.584989 93.765)
		(width 0.19)
		(layer "F.Cu")
		(net 815)
	)
	(segment
		(start 227.434989 93.765)
		(end 227.434989 93.905)
		(width 0.19)
		(layer "F.Cu")
		(net 815)
	)
	(segment
		(start 228.604989 93.585)
		(end 228.514989 93.585)
		(width 0.19)
		(layer "F.Cu")
		(net 815)
	)
	(segment
		(start 230.404989 93.585)
		(end 230.314989 93.585)
		(width 0.19)
		(layer "F.Cu")
		(net 815)
	)
	(segment
		(start 217.94486 95.777)
		(end 217.94486 95.91966)
		(width 0.19)
		(layer "F.Cu")
		(net 815)
	)
	(segment
		(start 232.67 92.1)
		(end 232.67 92.56163)
		(width 0.19)
		(layer "F.Cu")
		(net 815)
	)
	(segment
		(start 231.930532 90.3475)
		(end 231.930532 91.360532)
		(width 0.19)
		(layer "F.Cu")
		(net 815)
	)
	(segment
		(start 222.765 95.544)
		(end 222.65 95.659)
		(width 0.19)
		(layer "F.Cu")
		(net 815)
	)
	(segment
		(start 230.134989 93.765)
		(end 230.134989 93.905)
		(width 0.19)
		(layer "F.Cu")
		(net 815)
	)
	(segment
		(start 227.254989 94.085)
		(end 227.164989 94.085)
		(width 0.19)
		(layer "F.Cu")
		(net 815)
	)
	(segment
		(start 229.954989 94.085)
		(end 229.864989 94.085)
		(width 0.19)
		(layer "F.Cu")
		(net 815)
	)
	(segment
		(start 220.537631 95.597)
		(end 220.602631 95.662)
		(width 0.19)
		(layer "F.Cu")
		(net 815)
	)
	(segment
		(start 219.29486 95.919681)
		(end 219.29486 95.777)
		(width 0.19)
		(layer "F.Cu")
		(net 815)
	)
	(segment
		(start 228.784989 93.905)
		(end 228.784989 93.765)
		(width 0.19)
		(layer "F.Cu")
		(net 815)
	)
	(segment
		(start 229.054989 94.085)
		(end 228.964989 94.085)
		(width 0.19)
		(layer "F.Cu")
		(net 815)
	)
	(segment
		(start 218.57486 95.597)
		(end 218.66486 95.597)
		(width 0.19)
		(layer "F.Cu")
		(net 815)
	)
	(segment
		(start 217.22486 96.09966)
		(end 217.31486 96.09966)
		(width 0.19)
		(layer "F.Cu")
		(net 815)
	)
	(segment
		(start 229.504989 93.585)
		(end 229.414989 93.585)
		(width 0.19)
		(layer "F.Cu")
		(net 815)
	)
	(segment
		(start 229.234989 93.765)
		(end 229.234989 93.905)
		(width 0.19)
		(layer "F.Cu")
		(net 815)
	)
	(via
		(at 222.65 95.659)
		(size 0.45)
		(drill 0.1)
		(layers "F.Cu" "B.Cu")
		(net 815)
	)
	(arc
		(start 217.94486 95.91966)
		(mid 217.997581 96.046939)
		(end 218.12486 96.09966)
		(width 0.19)
		(layer "F.Cu")
		(net 815)
	)
	(arc
		(start 229.684989 93.765)
		(mid 229.632268 93.637721)
		(end 229.504989 93.585)
		(width 0.19)
		(layer "F.Cu")
		(net 815)
	)
	(arc
		(start 230.134989 93.905)
		(mid 230.082268 94.032279)
		(end 229.954989 94.085)
		(width 0.19)
		(layer "F.Cu")
		(net 815)
	)
	(arc
		(start 217.04486 95.91966)
		(mid 217.097581 96.046939)
		(end 217.22486 96.09966)
		(width 0.19)
		(layer "F.Cu")
		(net 815)
	)
	(arc
		(start 226.984989 93.765)
		(mid 226.932268 93.637721)
		(end 226.804989 93.585)
		(width 0.19)
		(layer "F.Cu")
		(net 815)
	)
	(arc
		(start 227.164989 94.085)
		(mid 227.03771 94.032279)
		(end 226.984989 93.905)
		(width 0.19)
		(layer "F.Cu")
		(net 815)
	)
	(arc
		(start 228.064989 94.085)
		(mid 227.93771 94.032279)
		(end 227.884989 93.905)
		(width 0.19)
		(layer "F.Cu")
		(net 815)
	)
	(arc
		(start 231.034989 93.905)
		(mid 230.982268 94.032279)
		(end 230.854989 94.085)
		(width 0.19)
		(layer "F.Cu")
		(net 815)
	)
	(arc
		(start 230.584989 93.765)
		(mid 230.532268 93.637721)
		(end 230.404989 93.585)
		(width 0.19)
		(layer "F.Cu")
		(net 815)
	)
	(arc
		(start 218.66486 95.597)
		(mid 218.792139 95.649721)
		(end 218.84486 95.777)
		(width 0.19)
		(layer "F.Cu")
		(net 815)
	)
	(arc
		(start 218.84486 95.919681)
		(mid 218.897581 96.04696)
		(end 219.02486 96.099681)
		(width 0.19)
		(layer "F.Cu")
		(net 815)
	)
	(arc
		(start 231.214989 93.585)
		(mid 231.08771 93.637721)
		(end 231.034989 93.765)
		(width 0.19)
		(layer "F.Cu")
		(net 815)
	)
	(arc
		(start 229.234989 93.905)
		(mid 229.182268 94.032279)
		(end 229.054989 94.085)
		(width 0.19)
		(layer "F.Cu")
		(net 815)
	)
	(arc
		(start 218.21486 96.09966)
		(mid 218.342139 96.046939)
		(end 218.39486 95.91966)
		(width 0.19)
		(layer "F.Cu")
		(net 815)
	)
	(arc
		(start 217.76486 95.597)
		(mid 217.892139 95.649721)
		(end 217.94486 95.777)
		(width 0.19)
		(layer "F.Cu")
		(net 815)
	)
	(arc
		(start 229.864989 94.085)
		(mid 229.73771 94.032279)
		(end 229.684989 93.905)
		(width 0.19)
		(layer "F.Cu")
		(net 815)
	)
	(arc
		(start 217.49486 95.777)
		(mid 217.547581 95.649721)
		(end 217.67486 95.597)
		(width 0.19)
		(layer "F.Cu")
		(net 815)
	)
	(arc
		(start 229.414989 93.585)
		(mid 229.28771 93.637721)
		(end 229.234989 93.765)
		(width 0.19)
		(layer "F.Cu")
		(net 815)
	)
	(arc
		(start 227.434989 93.905)
		(mid 227.382268 94.032279)
		(end 227.254989 94.085)
		(width 0.19)
		(layer "F.Cu")
		(net 815)
	)
	(arc
		(start 218.39486 95.777)
		(mid 218.447581 95.649721)
		(end 218.57486 95.597)
		(width 0.19)
		(layer "F.Cu")
		(net 815)
	)
	(arc
		(start 228.514989 93.585)
		(mid 228.38771 93.637721)
		(end 228.334989 93.765)
		(width 0.19)
		(layer "F.Cu")
		(net 815)
	)
	(arc
		(start 228.334989 93.905)
		(mid 228.282268 94.032279)
		(end 228.154989 94.085)
		(width 0.19)
		(layer "F.Cu")
		(net 815)
	)
	(arc
		(start 217.31486 96.09966)
		(mid 217.442139 96.046939)
		(end 217.49486 95.91966)
		(width 0.19)
		(layer "F.Cu")
		(net 815)
	)
	(arc
		(start 228.784989 93.765)
		(mid 228.732268 93.637721)
		(end 228.604989 93.585)
		(width 0.19)
		(layer "F.Cu")
		(net 815)
	)
	(arc
		(start 219.29486 95.777)
		(mid 219.347581 95.649721)
		(end 219.47486 95.597)
		(width 0.19)
		(layer "F.Cu")
		(net 815)
	)
	(arc
		(start 230.764989 94.085)
		(mid 230.63771 94.032279)
		(end 230.584989 93.905)
		(width 0.19)
		(layer "F.Cu")
		(net 815)
	)
	(arc
		(start 227.614989 93.585)
		(mid 227.48771 93.637721)
		(end 227.434989 93.765)
		(width 0.19)
		(layer "F.Cu")
		(net 815)
	)
	(arc
		(start 230.314989 93.585)
		(mid 230.18771 93.637721)
		(end 230.134989 93.765)
		(width 0.19)
		(layer "F.Cu")
		(net 815)
	)
	(arc
		(start 227.884989 93.765)
		(mid 227.832268 93.637721)
		(end 227.704989 93.585)
		(width 0.19)
		(layer "F.Cu")
		(net 815)
	)
	(arc
		(start 216.86486 95.597)
		(mid 216.992139 95.649721)
		(end 217.04486 95.777)
		(width 0.19)
		(layer "F.Cu")
		(net 815)
	)
	(arc
		(start 219.11486 96.099681)
		(mid 219.242139 96.04696)
		(end 219.29486 95.919681)
		(width 0.19)
		(layer "F.Cu")
		(net 815)
	)
	(arc
		(start 228.964989 94.085)
		(mid 228.83771 94.032279)
		(end 228.784989 93.905)
		(width 0.19)
		(layer "F.Cu")
		(net 815)
	)
	(segment
		(start 223.021 95.544)
		(end 222.765 95.544)
		(width 0.19)
		(layer "B.Cu")
		(net 815)
	)
	(segment
		(start 223.37 95.868)
		(end 223.345 95.868)
		(width 0.19)
		(layer "B.Cu")
		(net 815)
	)
	(segment
		(start 223.345 95.868)
		(end 223.021 95.544)
		(width 0.19)
		(layer "B.Cu")
		(net 815)
	)
	(segment
		(start 222.765 95.544)
		(end 222.65 95.659)
		(width 0.19)
		(layer "B.Cu")
		(net 815)
	)
	(segment
		(start 233.345 92.5)
		(end 233.345 90.433032)
		(width 0.1)
		(layer "F.Cu")
		(net 816)
	)
	(segment
		(start 235.1 93.325)
		(end 234.17 93.325)
		(width 0.1)
		(layer "F.Cu")
		(net 816)
	)
	(segment
		(start 199.65 82.25)
		(end 199.8 82.4)
		(width 0.1)
		(layer "F.Cu")
		(net 816)
	)
	(segment
		(start 222.59 90.085)
		(end 222.9 89.775)
		(width 0.1)
		(layer "F.Cu")
		(net 816)
	)
	(segment
		(start 221.789132 90.085)
		(end 221.017132 90.085)
		(width 0.1)
		(layer "F.Cu")
		(net 816)
	)
	(segment
		(start 199.8 82.4)
		(end 199.8 82.8)
		(width 0.1)
		(layer "F.Cu")
		(net 816)
	)
	(segment
		(start 200 83)
		(end 199.8 82.8)
		(width 0.1)
		(layer "F.Cu")
		(net 816)
	)
	(segment
		(start 199.65 82.25)
		(end 199.65 81.88)
		(width 0.1)
		(layer "F.Cu")
		(net 816)
	)
	(segment
		(start 221.017132 90.085)
		(end 220.485 90.085)
		(width 0.1)
		(layer "F.Cu")
		(net 816)
	)
	(segment
		(start 233.345 90.433032)
		(end 233.430532 90.3475)
		(width 0.1)
		(layer "F.Cu")
		(net 816)
	)
	(segment
		(start 200 83.4)
		(end 200 83)
		(width 0.1)
		(layer "F.Cu")
		(net 816)
	)
	(segment
		(start 220.485 90.085)
		(end 220.1 89.7)
		(width 0.1)
		(layer "F.Cu")
		(net 816)
	)
	(segment
		(start 222.9 89.775)
		(end 224.175 89.775)
		(width 0.1)
		(layer "F.Cu")
		(net 816)
	)
	(segment
		(start 234.17 93.325)
		(end 233.345 92.5)
		(width 0.1)
		(layer "F.Cu")
		(net 816)
	)
	(segment
		(start 221.789132 90.085)
		(end 222.59 90.085)
		(width 0.1)
		(layer "F.Cu")
		(net 816)
	)
	(segment
		(start 199.65 81.88)
		(end 199.601 81.831)
		(width 0.1)
		(layer "F.Cu")
		(net 816)
	)
	(via
		(at 224.175 89.775)
		(size 0.45)
		(drill 0.1)
		(layers "F.Cu" "B.Cu")
		(net 816)
	)
	(via
		(at 200 83.4)
		(size 0.45)
		(drill 0.1)
		(layers "F.Cu" "B.Cu")
		(net 816)
	)
	(via
		(at 220.1 89.7)
		(size 0.45)
		(drill 0.1)
		(layers "F.Cu" "B.Cu")
		(net 816)
	)
	(via
		(at 235.1 93.325)
		(size 0.45)
		(drill 0.1)
		(layers "F.Cu" "B.Cu")
		(net 816)
	)
	(segment
		(start 200 83.4)
		(end 200 83.6)
		(width 0.1)
		(layer "In5.Cu")
		(net 816)
	)
	(segment
		(start 219.9 89.9)
		(end 220.1 89.7)
		(width 0.1)
		(layer "In5.Cu")
		(net 816)
	)
	(segment
		(start 218.2 87.8)
		(end 218.2 89.7)
		(width 0.1)
		(layer "In5.Cu")
		(net 816)
	)
	(segment
		(start 218.6 90.1)
		(end 219.5 90.1)
		(width 0.1)
		(layer "In5.Cu")
		(net 816)
	)
	(segment
		(start 224.875 91.85)
		(end 224.875 90.475)
		(width 0.1)
		(layer "In5.Cu")
		(net 816)
	)
	(segment
		(start 218.2 89.7)
		(end 218.6 90.1)
		(width 0.1)
		(layer "In5.Cu")
		(net 816)
	)
	(segment
		(start 219.5 90.1)
		(end 219.7 89.9)
		(width 0.1)
		(layer "In5.Cu")
		(net 816)
	)
	(segment
		(start 205.3 83.8)
		(end 208.3 86.8)
		(width 0.1)
		(layer "In5.Cu")
		(net 816)
	)
	(segment
		(start 217.2 86.8)
		(end 218.2 87.8)
		(width 0.1)
		(layer "In5.Cu")
		(net 816)
	)
	(segment
		(start 219.7 89.9)
		(end 219.9 89.9)
		(width 0.1)
		(layer "In5.Cu")
		(net 816)
	)
	(segment
		(start 224.875 90.475)
		(end 224.175 89.775)
		(width 0.1)
		(layer "In5.Cu")
		(net 816)
	)
	(segment
		(start 200.2 83.8)
		(end 205.3 83.8)
		(width 0.1)
		(layer "In5.Cu")
		(net 816)
	)
	(segment
		(start 235.1 93.325)
		(end 226.35 93.325)
		(width 0.1)
		(layer "In5.Cu")
		(net 816)
	)
	(segment
		(start 208.3 86.8)
		(end 217.2 86.8)
		(width 0.1)
		(layer "In5.Cu")
		(net 816)
	)
	(segment
		(start 200 83.6)
		(end 200.2 83.8)
		(width 0.1)
		(layer "In5.Cu")
		(net 816)
	)
	(segment
		(start 226.35 93.325)
		(end 224.875 91.85)
		(width 0.1)
		(layer "In5.Cu")
		(net 816)
	)
	(segment
		(start 221.017132 90.585)
		(end 221.789132 90.585)
		(width 0.1)
		(layer "F.Cu")
		(net 817)
	)
	(segment
		(start 221.017132 90.585)
		(end 220.185 90.585)
		(width 0.1)
		(layer "F.Cu")
		(net 817)
	)
	(segment
		(start 231.995 88.008032)
		(end 231.930532 88.0725)
		(width 0.1)
		(layer "F.Cu")
		(net 817)
	)
	(segment
		(start 230.935 85.325)
		(end 231.995 86.385)
		(width 0.1)
		(layer "F.Cu")
		(net 817)
	)
	(segment
		(start 221.789132 90.585)
		(end 222.565 90.585)
		(width 0.1)
		(layer "F.Cu")
		(net 817)
	)
	(segment
		(start 226.675 85.325)
		(end 230.935 85.325)
		(width 0.1)
		(layer "F.Cu")
		(net 817)
	)
	(segment
		(start 226.325 85.675)
		(end 226.675 85.325)
		(width 0.1)
		(layer "F.Cu")
		(net 817)
	)
	(segment
		(start 226.325 89.075)
		(end 226.325 85.675)
		(width 0.1)
		(layer "F.Cu")
		(net 817)
	)
	(segment
		(start 225.15 90.25)
		(end 226.325 89.075)
		(width 0.1)
		(layer "F.Cu")
		(net 817)
	)
	(segment
		(start 198.799 82.599)
		(end 198.8 82.6)
		(width 0.1)
		(layer "F.Cu")
		(net 817)
	)
	(segment
		(start 198.799 81.831)
		(end 198.799 82.599)
		(width 0.1)
		(layer "F.Cu")
		(net 817)
	)
	(segment
		(start 222.565 90.585)
		(end 222.9 90.25)
		(width 0.1)
		(layer "F.Cu")
		(net 817)
	)
	(segment
		(start 222.9 90.25)
		(end 225.15 90.25)
		(width 0.1)
		(layer "F.Cu")
		(net 817)
	)
	(segment
		(start 220.185 90.585)
		(end 219.9 90.3)
		(width 0.1)
		(layer "F.Cu")
		(net 817)
	)
	(segment
		(start 231.995 86.385)
		(end 231.995 88.008032)
		(width 0.1)
		(layer "F.Cu")
		(net 817)
	)
	(via
		(at 198.8 82.6)
		(size 0.45)
		(drill 0.1)
		(layers "F.Cu" "B.Cu")
		(net 817)
	)
	(via
		(at 219.9 90.3)
		(size 0.45)
		(drill 0.1)
		(layers "F.Cu" "B.Cu")
		(net 817)
	)
	(segment
		(start 198.8 83.3)
		(end 199.7 84.2)
		(width 0.1)
		(layer "In5.Cu")
		(net 817)
	)
	(segment
		(start 205.134314 84.2)
		(end 208.134314 87.2)
		(width 0.1)
		(layer "In5.Cu")
		(net 817)
	)
	(segment
		(start 217.8 87.965686)
		(end 217.8 89.865686)
		(width 0.1)
		(layer "In5.Cu")
		(net 817)
	)
	(segment
		(start 208.134314 87.2)
		(end 217.034314 87.2)
		(width 0.1)
		(layer "In5.Cu")
		(net 817)
	)
	(segment
		(start 198.8 82.6)
		(end 198.8 83.3)
		(width 0.1)
		(layer "In5.Cu")
		(net 817)
	)
	(segment
		(start 219.817157 90.382843)
		(end 218.317157 90.382843)
		(width 0.1)
		(layer "In5.Cu")
		(net 817)
	)
	(segment
		(start 217.8 89.865686)
		(end 218.317157 90.382843)
		(width 0.1)
		(layer "In5.Cu")
		(net 817)
	)
	(segment
		(start 217.034314 87.2)
		(end 217.8 87.965686)
		(width 0.1)
		(layer "In5.Cu")
		(net 817)
	)
	(segment
		(start 199.7 84.2)
		(end 205.134314 84.2)
		(width 0.1)
		(layer "In5.Cu")
		(net 817)
	)
	(segment
		(start 219.9 90.3)
		(end 219.817157 90.382843)
		(width 0.1)
		(layer "In5.Cu")
		(net 817)
	)
	(segment
		(start 232.456885 85.002974)
		(end 232.456885 84.75)
		(width 0.19)
		(layer "F.Cu")
		(net 818)
	)
	(segment
		(start 234.930532 86.853749)
		(end 234.930532 88.0725)
		(width 0.19)
		(layer "F.Cu")
		(net 818)
	)
	(segment
		(start 216.564632 87.570856)
		(end 216.580132 87.586356)
		(width 0.19)
		(layer "F.Cu")
		(net 818)
	)
	(segment
		(start 224.57663 83.415)
		(end 225.32663 84.165)
		(width 0.19)
		(layer "F.Cu")
		(net 818)
	)
	(segment
		(start 223.72337 83.415)
		(end 224.57663 83.415)
		(width 0.19)
		(layer "F.Cu")
		(net 818)
	)
	(segment
		(start 217.465 86.92337)
		(end 217.465 86.17337)
		(width 0.19)
		(layer "F.Cu")
		(net 818)
	)
	(segment
		(start 231.826885 83.897014)
		(end 231.826885 85.002974)
		(width 0.19)
		(layer "F.Cu")
		(net 818)
	)
	(segment
		(start 228.970749 83.436136)
		(end 229.241885 83.436136)
		(width 0.19)
		(layer "F.Cu")
		(net 818)
	)
	(segment
		(start 230.456885 83.95)
		(end 230.456885 83.897014)
		(width 0.19)
		(layer "F.Cu")
		(net 818)
	)
	(segment
		(start 233.041885 84.165)
		(end 233.54663 84.165)
		(width 0.19)
		(layer "F.Cu")
		(net 818)
	)
	(segment
		(start 223.315 83.82337)
		(end 223.72337 83.415)
		(width 0.19)
		(layer "F.Cu")
		(net 818)
	)
	(segment
		(start 232.041885 85.217974)
		(end 232.241885 85.217974)
		(width 0.19)
		(layer "F.Cu")
		(net 818)
	)
	(segment
		(start 233.54663 84.165)
		(end 234.865532 85.483902)
		(width 0.19)
		(layer "F.Cu")
		(net 818)
	)
	(segment
		(start 234.865532 85.483902)
		(end 234.865532 86.788749)
		(width 0.19)
		(layer "F.Cu")
		(net 818)
	)
	(segment
		(start 217.465 86.17337)
		(end 218.02337 85.615)
		(width 0.19)
		(layer "F.Cu")
		(net 818)
	)
	(segment
		(start 234.865532 86.788749)
		(end 234.930532 86.853749)
		(width 0.19)
		(layer "F.Cu")
		(net 818)
	)
	(segment
		(start 216.802014 87.586356)
		(end 217.465 86.92337)
		(width 0.19)
		(layer "F.Cu")
		(net 818)
	)
	(segment
		(start 229.970749 84.165)
		(end 230.241885 84.165)
		(width 0.19)
		(layer "F.Cu")
		(net 818)
	)
	(segment
		(start 216.364632 87.570856)
		(end 216.564632 87.570856)
		(width 0.19)
		(layer "F.Cu")
		(net 818)
	)
	(segment
		(start 223.315 84.87337)
		(end 223.315 83.82337)
		(width 0.19)
		(layer "F.Cu")
		(net 818)
	)
	(segment
		(start 231.041885 83.312014)
		(end 231.241885 83.312014)
		(width 0.19)
		(layer "F.Cu")
		(net 818)
	)
	(segment
		(start 225.32663 84.165)
		(end 228.241885 84.165)
		(width 0.19)
		(layer "F.Cu")
		(net 818)
	)
	(segment
		(start 218.02337 85.615)
		(end 222.57337 85.615)
		(width 0.19)
		(layer "F.Cu")
		(net 818)
	)
	(segment
		(start 222.57337 85.615)
		(end 223.315 84.87337)
		(width 0.19)
		(layer "F.Cu")
		(net 818)
	)
	(segment
		(start 216.580132 87.586356)
		(end 216.802014 87.586356)
		(width 0.19)
		(layer "F.Cu")
		(net 818)
	)
	(arc
		(start 231.241885 83.312014)
		(mid 231.655542 83.483357)
		(end 231.826885 83.897014)
		(width 0.19)
		(layer "F.Cu")
		(net 818)
	)
	(arc
		(start 228.241885 84.165)
		(mid 228.368763 84.112446)
		(end 228.421317 83.985568)
		(width 0.19)
		(layer "F.Cu")
		(net 818)
	)
	(arc
		(start 228.421317 83.985568)
		(mid 228.582242 83.597061)
		(end 228.970749 83.436136)
		(width 0.19)
		(layer "F.Cu")
		(net 818)
	)
	(arc
		(start 229.241885 83.436136)
		(mid 229.630392 83.597061)
		(end 229.791317 83.985568)
		(width 0.19)
		(layer "F.Cu")
		(net 818)
	)
	(arc
		(start 229.791317 83.985568)
		(mid 229.843871 84.112446)
		(end 229.970749 84.165)
		(width 0.19)
		(layer "F.Cu")
		(net 818)
	)
	(arc
		(start 230.456885 83.897014)
		(mid 230.628228 83.483357)
		(end 231.041885 83.312014)
		(width 0.19)
		(layer "F.Cu")
		(net 818)
	)
	(arc
		(start 232.241885 85.217974)
		(mid 232.393913 85.155002)
		(end 232.456885 85.002974)
		(width 0.19)
		(layer "F.Cu")
		(net 818)
	)
	(arc
		(start 232.456885 84.75)
		(mid 232.628228 84.336343)
		(end 233.041885 84.165)
		(width 0.19)
		(layer "F.Cu")
		(net 818)
	)
	(arc
		(start 231.826885 85.002974)
		(mid 231.889857 85.155002)
		(end 232.041885 85.217974)
		(width 0.19)
		(layer "F.Cu")
		(net 818)
	)
	(arc
		(start 230.241885 84.165)
		(mid 230.393913 84.102028)
		(end 230.456885 83.95)
		(width 0.19)
		(layer "F.Cu")
		(net 818)
	)
	(segment
		(start 222.201633 93.16)
		(end 222.266633 93.225)
		(width 0.19)
		(layer "F.Cu")
		(net 819)
	)
	(segment
		(start 216.814633 91.170856)
		(end 216.830633 91.186856)
		(width 0.19)
		(layer "F.Cu")
		(net 819)
	)
	(segment
		(start 220.604631 93.16)
		(end 221.017132 93.16)
		(width 0.19)
		(layer "F.Cu")
		(net 819)
	)
	(segment
		(start 220.539631 93.225)
		(end 220.604631 93.16)
		(width 0.19)
		(layer "F.Cu")
		(net 819)
	)
	(segment
		(start 217.785 92.52337)
		(end 218.48663 93.225)
		(width 0.19)
		(layer "F.Cu")
		(net 819)
	)
	(segment
		(start 221.789132 93.16)
		(end 221.017132 93.16)
		(width 0.19)
		(layer "F.Cu")
		(net 819)
	)
	(segment
		(start 217.785 91.92337)
		(end 217.785 92.52337)
		(width 0.19)
		(layer "F.Cu")
		(net 819)
	)
	(segment
		(start 217.048486 91.186856)
		(end 217.785 91.92337)
		(width 0.19)
		(layer "F.Cu")
		(net 819)
	)
	(segment
		(start 222.785 93.225)
		(end 222.9 93.11)
		(width 0.19)
		(layer "F.Cu")
		(net 819)
	)
	(segment
		(start 230.930532 90.3475)
		(end 230.930532 91.566251)
		(width 0.19)
		(layer "F.Cu")
		(net 819)
	)
	(segment
		(start 230.865532 91.631251)
		(end 230.865532 91.885)
		(width 0.19)
		(layer "F.Cu")
		(net 819)
	)
	(segment
		(start 222.266633 93.225)
		(end 222.785 93.225)
		(width 0.19)
		(layer "F.Cu")
		(net 819)
	)
	(segment
		(start 230.930532 91.566251)
		(end 230.865532 91.631251)
		(width 0.19)
		(layer "F.Cu")
		(net 819)
	)
	(segment
		(start 221.789132 93.16)
		(end 222.201633 93.16)
		(width 0.19)
		(layer "F.Cu")
		(net 819)
	)
	(segment
		(start 218.48663 93.225)
		(end 220.539631 93.225)
		(width 0.19)
		(layer "F.Cu")
		(net 819)
	)
	(segment
		(start 230.865532 91.885)
		(end 230.980532 92)
		(width 0.19)
		(layer "F.Cu")
		(net 819)
	)
	(segment
		(start 216.364632 91.170856)
		(end 216.814633 91.170856)
		(width 0.19)
		(layer "F.Cu")
		(net 819)
	)
	(segment
		(start 216.830633 91.186856)
		(end 217.048486 91.186856)
		(width 0.19)
		(layer "F.Cu")
		(net 819)
	)
	(via
		(at 230.980532 92)
		(size 0.45)
		(drill 0.1)
		(layers "F.Cu" "B.Cu")
		(net 819)
	)
	(via
		(at 222.9 93.11)
		(size 0.45)
		(drill 0.1)
		(layers "F.Cu" "B.Cu")
		(net 819)
	)
	(segment
		(start 225.879455 90.59)
		(end 225.879455 88.623615)
		(width 0.15)
		(layer "In7.Cu")
		(net 819)
	)
	(segment
		(start 222.9 93.11)
		(end 223.0625 93.2725)
		(width 0.15)
		(layer "In7.Cu")
		(net 819)
	)
	(segment
		(start 224.3125 92.043044)
		(end 225.643044 90.7125)
		(width 0.15)
		(layer "In7.Cu")
		(net 819)
	)
	(segment
		(start 230.818032 91.353576)
		(end 230.818032 91.8375)
		(width 0.15)
		(layer "In7.Cu")
		(net 819)
	)
	(segment
		(start 223.0625 93.2725)
		(end 223.633044 93.2725)
		(width 0.15)
		(layer "In7.Cu")
		(net 819)
	)
	(segment
		(start 227.576956 90.712499)
		(end 227.706956 90.712499)
		(width 0.15)
		(layer "In7.Cu")
		(net 819)
	)
	(segment
		(start 228.14255 91.148093)
		(end 228.356956 91.148093)
		(width 0.15)
		(layer "In7.Cu")
		(net 819)
	)
	(segment
		(start 226.926956 91.248891)
		(end 227.056956 91.248891)
		(width 0.15)
		(layer "In7.Cu")
		(net 819)
	)
	(segment
		(start 226.276956 88.226114)
		(end 226.406956 88.226114)
		(width 0.15)
		(layer "In7.Cu")
		(net 819)
	)
	(segment
		(start 230.176956 90.7125)
		(end 229.206956 90.7125)
		(width 0.15)
		(layer "In7.Cu")
		(net 819)
	)
	(segment
		(start 230.176956 90.7125)
		(end 230.818032 91.353576)
		(width 0.15)
		(layer "In7.Cu")
		(net 819)
	)
	(segment
		(start 225.643044 90.7125)
		(end 225.756956 90.712499)
		(width 0.15)
		(layer "In7.Cu")
		(net 819)
	)
	(segment
		(start 223.633044 93.2725)
		(end 224.3125 92.593044)
		(width 0.15)
		(layer "In7.Cu")
		(net 819)
	)
	(segment
		(start 224.3125 92.593044)
		(end 224.3125 92.043044)
		(width 0.15)
		(layer "In7.Cu")
		(net 819)
	)
	(segment
		(start 227.179455 91.126392)
		(end 227.179455 91.11)
		(width 0.15)
		(layer "In7.Cu")
		(net 819)
	)
	(segment
		(start 226.804457 88.623615)
		(end 226.804457 91.126392)
		(width 0.15)
		(layer "In7.Cu")
		(net 819)
	)
	(segment
		(start 228.79255 90.712499)
		(end 229.206956 90.7125)
		(width 0.15)
		(layer "In7.Cu")
		(net 819)
	)
	(segment
		(start 230.818032 91.8375)
		(end 230.980532 92)
		(width 0.15)
		(layer "In7.Cu")
		(net 819)
	)
	(arc
		(start 226.406956 88.226114)
		(mid 226.688032 88.342539)
		(end 226.804457 88.623615)
		(width 0.15)
		(layer "In7.Cu")
		(net 819)
	)
	(arc
		(start 225.756956 90.712499)
		(mid 225.843576 90.67662)
		(end 225.879455 90.59)
		(width 0.15)
		(layer "In7.Cu")
		(net 819)
	)
	(arc
		(start 227.179455 91.11)
		(mid 227.29588 90.828924)
		(end 227.576956 90.712499)
		(width 0.15)
		(layer "In7.Cu")
		(net 819)
	)
	(arc
		(start 226.804457 91.126392)
		(mid 226.840336 91.213012)
		(end 226.926956 91.248891)
		(width 0.15)
		(layer "In7.Cu")
		(net 819)
	)
	(arc
		(start 228.437252 91.067797)
		(mid 228.541316 90.816563)
		(end 228.79255 90.712499)
		(width 0.15)
		(layer "In7.Cu")
		(net 819)
	)
	(arc
		(start 225.879455 88.623615)
		(mid 225.99588 88.342539)
		(end 226.276956 88.226114)
		(width 0.15)
		(layer "In7.Cu")
		(net 819)
	)
	(arc
		(start 228.356956 91.148093)
		(mid 228.413734 91.124575)
		(end 228.437252 91.067797)
		(width 0.15)
		(layer "In7.Cu")
		(net 819)
	)
	(arc
		(start 227.706956 90.712499)
		(mid 227.95819 90.816563)
		(end 228.062254 91.067797)
		(width 0.15)
		(layer "In7.Cu")
		(net 819)
	)
	(arc
		(start 228.062254 91.067797)
		(mid 228.085772 91.124575)
		(end 228.14255 91.148093)
		(width 0.15)
		(layer "In7.Cu")
		(net 819)
	)
	(arc
		(start 227.056956 91.248891)
		(mid 227.143576 91.213012)
		(end 227.179455 91.126392)
		(width 0.15)
		(layer "In7.Cu")
		(net 819)
	)
	(segment
		(start 217.835 87.07663)
		(end 217.835 86.32663)
		(width 0.19)
		(layer "F.Cu")
		(net 820)
	)
	(segment
		(start 223.685 85.02663)
		(end 223.685 83.97663)
		(width 0.19)
		(layer "F.Cu")
		(net 820)
	)
	(segment
		(start 231.456885 83.897014)
		(end 231.456885 85.002974)
		(width 0.19)
		(layer "F.Cu")
		(net 820)
	)
	(segment
		(start 216.580132 87.956356)
		(end 216.955274 87.956356)
		(width 0.19)
		(layer "F.Cu")
		(net 820)
	)
	(segment
		(start 223.685 83.97663)
		(end 223.87663 83.785)
		(width 0.19)
		(layer "F.Cu")
		(net 820)
	)
	(segment
		(start 223.87663 83.785)
		(end 224.42337 83.785)
		(width 0.19)
		(layer "F.Cu")
		(net 820)
	)
	(segment
		(start 216.564632 87.971856)
		(end 216.580132 87.956356)
		(width 0.19)
		(layer "F.Cu")
		(net 820)
	)
	(segment
		(start 234.495532 85.637162)
		(end 234.495532 86.788749)
		(width 0.19)
		(layer "F.Cu")
		(net 820)
	)
	(segment
		(start 230.826885 83.95)
		(end 230.826885 83.897014)
		(width 0.19)
		(layer "F.Cu")
		(net 820)
	)
	(segment
		(start 234.317731 85.45936)
		(end 234.495532 85.637162)
		(width 0.19)
		(layer "F.Cu")
		(net 820)
	)
	(segment
		(start 217.835 86.32663)
		(end 218.17663 85.985)
		(width 0.19)
		(layer "F.Cu")
		(net 820)
	)
	(segment
		(start 218.17663 85.985)
		(end 222.72663 85.985)
		(width 0.19)
		(layer "F.Cu")
		(net 820)
	)
	(segment
		(start 229.970749 84.535)
		(end 230.241885 84.535)
		(width 0.19)
		(layer "F.Cu")
		(net 820)
	)
	(segment
		(start 233.041885 84.535)
		(end 233.39337 84.535)
		(width 0.19)
		(layer "F.Cu")
		(net 820)
	)
	(segment
		(start 222.72663 85.985)
		(end 223.685 85.02663)
		(width 0.19)
		(layer "F.Cu")
		(net 820)
	)
	(segment
		(start 228.970749 83.806136)
		(end 229.241885 83.806136)
		(width 0.19)
		(layer "F.Cu")
		(net 820)
	)
	(segment
		(start 233.39337 84.535)
		(end 233.617697 84.759327)
		(width 0.19)
		(layer "F.Cu")
		(net 820)
	)
	(segment
		(start 225.17337 84.535)
		(end 228.241885 84.535)
		(width 0.19)
		(layer "F.Cu")
		(net 820)
	)
	(segment
		(start 234.430532 86.853749)
		(end 234.430532 88.0725)
		(width 0.19)
		(layer "F.Cu")
		(net 820)
	)
	(segment
		(start 232.041885 85.587974)
		(end 232.241885 85.587974)
		(width 0.19)
		(layer "F.Cu")
		(net 820)
	)
	(segment
		(start 233.578562 85.420714)
		(end 233.656343 85.498495)
		(width 0.19)
		(layer "F.Cu")
		(net 820)
	)
	(segment
		(start 231.041885 83.682014)
		(end 231.241885 83.682014)
		(width 0.19)
		(layer "F.Cu")
		(net 820)
	)
	(segment
		(start 234.495532 86.788749)
		(end 234.430532 86.853749)
		(width 0.19)
		(layer "F.Cu")
		(net 820)
	)
	(segment
		(start 233.617697 85.070453)
		(end 233.578562 85.109587)
		(width 0.19)
		(layer "F.Cu")
		(net 820)
	)
	(segment
		(start 216.955274 87.956356)
		(end 217.835 87.07663)
		(width 0.19)
		(layer "F.Cu")
		(net 820)
	)
	(segment
		(start 233.96747 85.498495)
		(end 234.006604 85.45936)
		(width 0.19)
		(layer "F.Cu")
		(net 820)
	)
	(segment
		(start 224.42337 83.785)
		(end 225.17337 84.535)
		(width 0.19)
		(layer "F.Cu")
		(net 820)
	)
	(segment
		(start 232.826885 85.002974)
		(end 232.826885 84.75)
		(width 0.19)
		(layer "F.Cu")
		(net 820)
	)
	(segment
		(start 216.364632 87.971856)
		(end 216.564632 87.971856)
		(width 0.19)
		(layer "F.Cu")
		(net 820)
	)
	(arc
		(start 229.241885 83.806136)
		(mid 229.368763 83.85869)
		(end 229.421317 83.985568)
		(width 0.19)
		(layer "F.Cu")
		(net 820)
	)
	(arc
		(start 230.826885 83.897014)
		(mid 230.889857 83.744986)
		(end 231.041885 83.682014)
		(width 0.19)
		(layer "F.Cu")
		(net 820)
	)
	(arc
		(start 233.656343 85.498495)
		(mid 233.811907 85.562931)
		(end 233.96747 85.498495)
		(width 0.19)
		(layer "F.Cu")
		(net 820)
	)
	(arc
		(start 228.241885 84.535)
		(mid 228.630392 84.374075)
		(end 228.791317 83.985568)
		(width 0.19)
		(layer "F.Cu")
		(net 820)
	)
	(arc
		(start 231.456885 85.002974)
		(mid 231.628228 85.416631)
		(end 232.041885 85.587974)
		(width 0.19)
		(layer "F.Cu")
		(net 820)
	)
	(arc
		(start 231.241885 83.682014)
		(mid 231.393913 83.744986)
		(end 231.456885 83.897014)
		(width 0.19)
		(layer "F.Cu")
		(net 820)
	)
	(arc
		(start 233.617697 84.759327)
		(mid 233.682133 84.91489)
		(end 233.617697 85.070453)
		(width 0.19)
		(layer "F.Cu")
		(net 820)
	)
	(arc
		(start 229.421317 83.985568)
		(mid 229.582242 84.374075)
		(end 229.970749 84.535)
		(width 0.19)
		(layer "F.Cu")
		(net 820)
	)
	(arc
		(start 233.578562 85.109587)
		(mid 233.514126 85.26515)
		(end 233.578562 85.420714)
		(width 0.19)
		(layer "F.Cu")
		(net 820)
	)
	(arc
		(start 228.791317 83.985568)
		(mid 228.843871 83.85869)
		(end 228.970749 83.806136)
		(width 0.19)
		(layer "F.Cu")
		(net 820)
	)
	(arc
		(start 232.241885 85.587974)
		(mid 232.655542 85.416631)
		(end 232.826885 85.002974)
		(width 0.19)
		(layer "F.Cu")
		(net 820)
	)
	(arc
		(start 230.241885 84.535)
		(mid 230.655542 84.363657)
		(end 230.826885 83.95)
		(width 0.19)
		(layer "F.Cu")
		(net 820)
	)
	(arc
		(start 232.826885 84.75)
		(mid 232.889857 84.597972)
		(end 233.041885 84.535)
		(width 0.19)
		(layer "F.Cu")
		(net 820)
	)
	(arc
		(start 234.006604 85.45936)
		(mid 234.162167 85.394924)
		(end 234.317731 85.45936)
		(width 0.19)
		(layer "F.Cu")
		(net 820)
	)
	(segment
		(start 233.43 86.54)
		(end 233.43 88.071968)
		(width 0.19)
		(layer "F.Cu")
		(net 821)
	)
	(segment
		(start 220.602631 95.162)
		(end 220.537631 95.227)
		(width 0.19)
		(layer "F.Cu")
		(net 821)
	)
	(segment
		(start 215.463632 93.120857)
		(end 215.463632 92.670856)
		(width 0.19)
		(layer "F.Cu")
		(net 821)
	)
	(segment
		(start 221.015132 95.162)
		(end 221.787132 95.162)
		(width 0.19)
		(layer "F.Cu")
		(net 821)
	)
	(segment
		(start 222.547 95.162)
		(end 222.65 95.059)
		(width 0.19)
		(layer "F.Cu")
		(net 821)
	)
	(segment
		(start 232.12 92.2)
		(end 232.12 92.58837)
		(width 0.19)
		(layer "F.Cu")
		(net 821)
	)
	(segment
		(start 232.12 92.58837)
		(end 231.49337 93.215)
		(width 0.19)
		(layer "F.Cu")
		(net 821)
	)
	(segment
		(start 221.787132 95.162)
		(end 222.547 95.162)
		(width 0.19)
		(layer "F.Cu")
		(net 821)
	)
	(segment
		(start 223.976 95.174)
		(end 222.765 95.174)
		(width 0.19)
		(layer "F.Cu")
		(net 821)
	)
	(segment
		(start 220.537631 95.227)
		(end 216.28863 95.227)
		(width 0.19)
		(layer "F.Cu")
		(net 821)
	)
	(segment
		(start 215.448632 94.387002)
		(end 215.448632 93.135857)
		(width 0.19)
		(layer "F.Cu")
		(net 821)
	)
	(segment
		(start 231.49337 93.215)
		(end 225.935 93.215)
		(width 0.19)
		(layer "F.Cu")
		(net 821)
	)
	(segment
		(start 225.935 93.215)
		(end 223.976 95.174)
		(width 0.19)
		(layer "F.Cu")
		(net 821)
	)
	(segment
		(start 221.015132 95.162)
		(end 220.602631 95.162)
		(width 0.19)
		(layer "F.Cu")
		(net 821)
	)
	(segment
		(start 222.765 95.174)
		(end 222.65 95.059)
		(width 0.19)
		(layer "F.Cu")
		(net 821)
	)
	(segment
		(start 215.448632 93.135857)
		(end 215.463632 93.120857)
		(width 0.19)
		(layer "F.Cu")
		(net 821)
	)
	(segment
		(start 216.28863 95.227)
		(end 215.448632 94.387002)
		(width 0.19)
		(layer "F.Cu")
		(net 821)
	)
	(segment
		(start 233.43 88.071968)
		(end 233.430532 88.0725)
		(width 0.19)
		(layer "F.Cu")
		(net 821)
	)
	(via
		(at 222.65 95.059)
		(size 0.45)
		(drill 0.1)
		(layers "F.Cu" "B.Cu")
		(net 821)
	)
	(via
		(at 233.43 86.54)
		(size 0.45)
		(drill 0.1)
		(layers "F.Cu" "B.Cu")
		(net 821)
	)
	(via
		(at 232.12 92.2)
		(size 0.45)
		(drill 0.1)
		(layers "F.Cu" "B.Cu")
		(net 821)
	)
	(segment
		(start 223.021 95.174)
		(end 222.765 95.174)
		(width 0.19)
		(layer "B.Cu")
		(net 821)
	)
	(segment
		(start 222.765 95.174)
		(end 222.65 95.059)
		(width 0.19)
		(layer "B.Cu")
		(net 821)
	)
	(segment
		(start 223.37 94.85)
		(end 223.345 94.85)
		(width 0.19)
		(layer "B.Cu")
		(net 821)
	)
	(segment
		(start 223.345 94.85)
		(end 223.021 95.174)
		(width 0.19)
		(layer "B.Cu")
		(net 821)
	)
	(segment
		(start 233.37 91.8)
		(end 233.07 92.1)
		(width 0.15)
		(layer "In2.Cu")
		(net 821)
	)
	(segment
		(start 233.43 87.34)
		(end 233.37 87.4)
		(width 0.15)
		(layer "In2.Cu")
		(net 821)
	)
	(segment
		(start 232.22 92.1)
		(end 232.12 92.2)
		(width 0.15)
		(layer "In2.Cu")
		(net 821)
	)
	(segment
		(start 233.37 87.4)
		(end 233.37 91.8)
		(width 0.15)
		(layer "In2.Cu")
		(net 821)
	)
	(segment
		(start 233.07 92.1)
		(end 232.22 92.1)
		(width 0.15)
		(layer "In2.Cu")
		(net 821)
	)
	(segment
		(start 233.43 86.54)
		(end 233.43 87.34)
		(width 0.15)
		(layer "In2.Cu")
		(net 821)
	)
	(segment
		(start 216.895226 91.556856)
		(end 217.415 92.07663)
		(width 0.19)
		(layer "F.Cu")
		(net 822)
	)
	(segment
		(start 217.415 92.07663)
		(end 217.415 92.67663)
		(width 0.19)
		(layer "F.Cu")
		(net 822)
	)
	(segment
		(start 222.201633 93.66)
		(end 222.266633 93.595)
		(width 0.19)
		(layer "F.Cu")
		(net 822)
	)
	(segment
		(start 221.789132 93.66)
		(end 221.017132 93.66)
		(width 0.19)
		(layer "F.Cu")
		(net 822)
	)
	(segment
		(start 220.539631 93.595)
		(end 220.604631 93.66)
		(width 0.19)
		(layer "F.Cu")
		(net 822)
	)
	(segment
		(start 216.814633 91.572856)
		(end 216.830633 91.556856)
		(width 0.19)
		(layer "F.Cu")
		(net 822)
	)
	(segment
		(start 218.33337 93.595)
		(end 220.539631 93.595)
		(width 0.19)
		(layer "F.Cu")
		(net 822)
	)
	(segment
		(start 216.830633 91.556856)
		(end 216.895226 91.556856)
		(width 0.19)
		(layer "F.Cu")
		(net 822)
	)
	(segment
		(start 221.789132 93.66)
		(end 222.201633 93.66)
		(width 0.19)
		(layer "F.Cu")
		(net 822)
	)
	(segment
		(start 230.495532 91.885)
		(end 230.380532 92)
		(width 0.19)
		(layer "F.Cu")
		(net 822)
	)
	(segment
		(start 216.364632 91.572856)
		(end 216.814633 91.572856)
		(width 0.19)
		(layer "F.Cu")
		(net 822)
	)
	(segment
		(start 220.604631 93.66)
		(end 221.017132 93.66)
		(width 0.19)
		(layer "F.Cu")
		(net 822)
	)
	(segment
		(start 222.785 93.595)
		(end 222.9 93.71)
		(width 0.19)
		(layer "F.Cu")
		(net 822)
	)
	(segment
		(start 217.415 92.67663)
		(end 218.33337 93.595)
		(width 0.19)
		(layer "F.Cu")
		(net 822)
	)
	(segment
		(start 230.430532 90.3475)
		(end 230.430532 91.566251)
		(width 0.19)
		(layer "F.Cu")
		(net 822)
	)
	(segment
		(start 230.495532 91.631251)
		(end 230.495532 91.885)
		(width 0.19)
		(layer "F.Cu")
		(net 822)
	)
	(segment
		(start 230.430532 91.566251)
		(end 230.495532 91.631251)
		(width 0.19)
		(layer "F.Cu")
		(net 822)
	)
	(segment
		(start 222.266633 93.595)
		(end 222.785 93.595)
		(width 0.19)
		(layer "F.Cu")
		(net 822)
	)
	(via
		(at 230.380532 92)
		(size 0.45)
		(drill 0.1)
		(layers "F.Cu" "B.Cu")
		(net 822)
	)
	(via
		(at 222.9 93.71)
		(size 0.45)
		(drill 0.1)
		(layers "F.Cu" "B.Cu")
		(net 822)
	)
	(segment
		(start 228.79255 90.987501)
		(end 229.006956 90.987501)
		(width 0.15)
		(layer "In7.Cu")
		(net 822)
	)
	(segment
		(start 222.9 93.71)
		(end 223.0625 93.5475)
		(width 0.15)
		(layer "In7.Cu")
		(net 822)
	)
	(segment
		(start 226.529455 88.623615)
		(end 226.529455 91.126392)
		(width 0.15)
		(layer "In7.Cu")
		(net 822)
	)
	(segment
		(start 226.154457 90.59)
		(end 226.154457 88.623615)
		(width 0.15)
		(layer "In7.Cu")
		(net 822)
	)
	(segment
		(start 223.0625 93.5475)
		(end 223.746956 93.5475)
		(width 0.15)
		(layer "In7.Cu")
		(net 822)
	)
	(segment
		(start 225.190372 91.848198)
		(end 225.142308 91.800134)
		(width 0.15)
		(layer "In7.Cu")
		(net 822)
	)
	(segment
		(start 230.543032 91.8375)
		(end 230.543032 91.467488)
		(width 0.15)
		(layer "In7.Cu")
		(net 822)
	)
	(segment
		(start 224.5875 92.156956)
		(end 224.696833 92.047623)
		(width 0.15)
		(layer "In7.Cu")
		(net 822)
	)
	(segment
		(start 226.926956 91.523893)
		(end 227.056956 91.523893)
		(width 0.15)
		(layer "In7.Cu")
		(net 822)
	)
	(segment
		(start 225.142308 91.602144)
		(end 225.191807 91.552648)
		(width 0.15)
		(layer "In7.Cu")
		(net 822)
	)
	(segment
		(start 225.756956 90.9875)
		(end 225.756956 90.987501)
		(width 0.15)
		(layer "In7.Cu")
		(net 822)
	)
	(segment
		(start 225.191807 91.552648)
		(end 225.756956 90.9875)
		(width 0.15)
		(layer "In7.Cu")
		(net 822)
	)
	(segment
		(start 230.063044 90.9875)
		(end 229.093044 90.9875)
		(width 0.15)
		(layer "In7.Cu")
		(net 822)
	)
	(segment
		(start 230.543032 91.467488)
		(end 230.063044 90.9875)
		(width 0.15)
		(layer "In7.Cu")
		(net 822)
	)
	(segment
		(start 227.454457 91.126392)
		(end 227.454457 91.11)
		(width 0.15)
		(layer "In7.Cu")
		(net 822)
	)
	(segment
		(start 223.746956 93.5475)
		(end 224.5875 92.706956)
		(width 0.15)
		(layer "In7.Cu")
		(net 822)
	)
	(segment
		(start 226.276956 88.501116)
		(end 226.406956 88.501116)
		(width 0.15)
		(layer "In7.Cu")
		(net 822)
	)
	(segment
		(start 230.380532 92)
		(end 230.543032 91.8375)
		(width 0.15)
		(layer "In7.Cu")
		(net 822)
	)
	(segment
		(start 227.576956 90.987501)
		(end 227.706956 90.987501)
		(width 0.15)
		(layer "In7.Cu")
		(net 822)
	)
	(segment
		(start 228.14255 91.423095)
		(end 228.356956 91.423095)
		(width 0.15)
		(layer "In7.Cu")
		(net 822)
	)
	(segment
		(start 225.140875 92.095686)
		(end 225.190372 92.046188)
		(width 0.15)
		(layer "In7.Cu")
		(net 822)
	)
	(segment
		(start 224.894822 92.047623)
		(end 224.942885 92.095686)
		(width 0.15)
		(layer "In7.Cu")
		(net 822)
	)
	(segment
		(start 229.006956 90.987501)
		(end 229.093044 90.9875)
		(width 0.15)
		(layer "In7.Cu")
		(net 822)
	)
	(segment
		(start 224.5875 92.706956)
		(end 224.5875 92.156956)
		(width 0.15)
		(layer "In7.Cu")
		(net 822)
	)
	(arc
		(start 227.056956 91.523893)
		(mid 227.338032 91.407468)
		(end 227.454457 91.126392)
		(width 0.15)
		(layer "In7.Cu")
		(net 822)
	)
	(arc
		(start 227.787252 91.067797)
		(mid 227.891316 91.319031)
		(end 228.14255 91.423095)
		(width 0.15)
		(layer "In7.Cu")
		(net 822)
	)
	(arc
		(start 228.712254 91.067797)
		(mid 228.735772 91.011019)
		(end 228.79255 90.987501)
		(width 0.15)
		(layer "In7.Cu")
		(net 822)
	)
	(arc
		(start 226.154457 88.623615)
		(mid 226.190336 88.536995)
		(end 226.276956 88.501116)
		(width 0.15)
		(layer "In7.Cu")
		(net 822)
	)
	(arc
		(start 227.706956 90.987501)
		(mid 227.763734 91.011019)
		(end 227.787252 91.067797)
		(width 0.15)
		(layer "In7.Cu")
		(net 822)
	)
	(arc
		(start 226.406956 88.501116)
		(mid 226.493576 88.536995)
		(end 226.529455 88.623615)
		(width 0.15)
		(layer "In7.Cu")
		(net 822)
	)
	(arc
		(start 225.142308 91.800134)
		(mid 225.101303 91.701139)
		(end 225.142308 91.602144)
		(width 0.15)
		(layer "In7.Cu")
		(net 822)
	)
	(arc
		(start 224.942885 92.095686)
		(mid 225.04188 92.136691)
		(end 225.140875 92.095686)
		(width 0.15)
		(layer "In7.Cu")
		(net 822)
	)
	(arc
		(start 227.454457 91.11)
		(mid 227.490336 91.02338)
		(end 227.576956 90.987501)
		(width 0.15)
		(layer "In7.Cu")
		(net 822)
	)
	(arc
		(start 224.696833 92.047623)
		(mid 224.795827 92.006618)
		(end 224.894822 92.047623)
		(width 0.15)
		(layer "In7.Cu")
		(net 822)
	)
	(arc
		(start 225.756956 90.987501)
		(mid 226.038032 90.871076)
		(end 226.154457 90.59)
		(width 0.15)
		(layer "In7.Cu")
		(net 822)
	)
	(arc
		(start 226.529455 91.126392)
		(mid 226.64588 91.407468)
		(end 226.926956 91.523893)
		(width 0.15)
		(layer "In7.Cu")
		(net 822)
	)
	(arc
		(start 228.356956 91.423095)
		(mid 228.60819 91.319031)
		(end 228.712254 91.067797)
		(width 0.15)
		(layer "In7.Cu")
		(net 822)
	)
	(arc
		(start 225.190372 92.046188)
		(mid 225.231377 91.947193)
		(end 225.190372 91.848198)
		(width 0.15)
		(layer "In7.Cu")
		(net 822)
	)
	(segment
		(start 207.376 145.1)
		(end 207.476 145)
		(width 0.1)
		(layer "F.Cu")
		(net 823)
	)
	(segment
		(start 205.926 145.1)
		(end 207.376 145.1)
		(width 0.1)
		(layer "F.Cu")
		(net 823)
	)
	(via
		(at 207.476 145)
		(size 0.45)
		(drill 0.1)
		(layers "F.Cu" "B.Cu")
		(net 823)
	)
	(segment
		(start 206.966 145.51)
		(end 207.476 145)
		(width 0.1)
		(layer "B.Cu")
		(net 823)
	)
	(segment
		(start 208.246 145.01)
		(end 207.486 145.01)
		(width 0.1)
		(layer "B.Cu")
		(net 823)
	)
	(segment
		(start 205.409 145.51)
		(end 206.181001 145.51)
		(width 0.1)
		(layer "B.Cu")
		(net 823)
	)
	(segment
		(start 206.181001 145.51)
		(end 206.966 145.51)
		(width 0.1)
		(layer "B.Cu")
		(net 823)
	)
	(segment
		(start 207.486 145.01)
		(end 207.476 145)
		(width 0.1)
		(layer "B.Cu")
		(net 823)
	)
	(segment
		(start 205.926 145.9)
		(end 207.376 145.9)
		(width 0.1)
		(layer "F.Cu")
		(net 824)
	)
	(segment
		(start 207.376 145.9)
		(end 207.476 146)
		(width 0.1)
		(layer "F.Cu")
		(net 824)
	)
	(via
		(at 207.476 146)
		(size 0.45)
		(drill 0.1)
		(layers "F.Cu" "B.Cu")
		(net 824)
	)
	(segment
		(start 207.476 146)
		(end 208.246 146)
		(width 0.1)
		(layer "B.Cu")
		(net 824)
	)
	(segment
		(start 206.181 146.01)
		(end 207.466 146.01)
		(width 0.1)
		(layer "B.Cu")
		(net 824)
	)
	(segment
		(start 207.466 146.01)
		(end 207.476 146)
		(width 0.1)
		(layer "B.Cu")
		(net 824)
	)
	(segment
		(start 205.409 146.01)
		(end 206.181 146.01)
		(width 0.1)
		(layer "B.Cu")
		(net 824)
	)
	(segment
		(start 124.12 107.8)
		(end 123.2 107.8)
		(width 0.1)
		(layer "B.Cu")
		(net 825)
	)
	(segment
		(start 124.12 107.8)
		(end 124.12 108.8)
		(width 0.1)
		(layer "B.Cu")
		(net 825)
	)
	(segment
		(start 121.233 108)
		(end 123 108)
		(width 0.1)
		(layer "B.Cu")
		(net 825)
	)
	(segment
		(start 123.2 107.8)
		(end 123 108)
		(width 0.1)
		(layer "B.Cu")
		(net 825)
	)
	(segment
		(start 122.3 108.5)
		(end 122.6 108.8)
		(width 0.1)
		(layer "B.Cu")
		(net 826)
	)
	(segment
		(start 122.6 109.4)
		(end 123 109.8)
		(width 0.1)
		(layer "B.Cu")
		(net 826)
	)
	(segment
		(start 122.6 108.8)
		(end 122.6 109.4)
		(width 0.1)
		(layer "B.Cu")
		(net 826)
	)
	(segment
		(start 121.233 108.5)
		(end 122.3 108.5)
		(width 0.1)
		(layer "B.Cu")
		(net 826)
	)
	(segment
		(start 123 109.8)
		(end 124.12 109.8)
		(width 0.1)
		(layer "B.Cu")
		(net 826)
	)
	(segment
		(start 121.233 107.5)
		(end 122.7 107.5)
		(width 0.1)
		(layer "B.Cu")
		(net 827)
	)
	(segment
		(start 124.12 105.8)
		(end 124.12 106.8)
		(width 0.1)
		(layer "B.Cu")
		(net 827)
	)
	(segment
		(start 122.7 107.5)
		(end 123.4 106.8)
		(width 0.1)
		(layer "B.Cu")
		(net 827)
	)
	(segment
		(start 123.4 106.8)
		(end 124.12 106.8)
		(width 0.1)
		(layer "B.Cu")
		(net 827)
	)
	(segment
		(start 124.01 133.01)
		(end 124.12 132.9)
		(width 0.1)
		(layer "B.Cu")
		(net 831)
	)
	(segment
		(start 124.12 132.9)
		(end 124.12 131.85)
		(width 0.1)
		(layer "B.Cu")
		(net 831)
	)
	(segment
		(start 121.209 133.01)
		(end 124.01 133.01)
		(width 0.1)
		(layer "B.Cu")
		(net 831)
	)
	(segment
		(start 123.6 130.8)
		(end 123.2 131.2)
		(width 0.1)
		(layer "B.Cu")
		(net 832)
	)
	(segment
		(start 124.12 130.8)
		(end 123.6 130.8)
		(width 0.1)
		(layer "B.Cu")
		(net 832)
	)
	(segment
		(start 123.2 131.2)
		(end 123.2 132)
		(width 0.1)
		(layer "B.Cu")
		(net 832)
	)
	(segment
		(start 122.69 132.51)
		(end 121.209 132.51)
		(width 0.1)
		(layer "B.Cu")
		(net 832)
	)
	(segment
		(start 123.2 132)
		(end 122.69 132.51)
		(width 0.1)
		(layer "B.Cu")
		(net 832)
	)
	(segment
		(start 111.27 134.33)
		(end 110.31 134.33)
		(width 0.1)
		(layer "B.Cu")
		(net 833)
	)
	(segment
		(start 113.711 133.76)
		(end 111.84 133.76)
		(width 0.1)
		(layer "B.Cu")
		(net 833)
	)
	(segment
		(start 111.84 133.76)
		(end 111.27 134.33)
		(width 0.1)
		(layer "B.Cu")
		(net 833)
	)
	(segment
		(start 110.3 133.3)
		(end 110.3 132.3)
		(width 0.1)
		(layer "B.Cu")
		(net 834)
	)
	(segment
		(start 110.3 133.3)
		(end 113.671 133.3)
		(width 0.1)
		(layer "B.Cu")
		(net 834)
	)
	(segment
		(start 113.671 133.3)
		(end 113.711 133.26)
		(width 0.1)
		(layer "B.Cu")
		(net 834)
	)
	(segment
		(start 134.6 61.6)
		(end 134.6 59.48)
		(width 0.1)
		(layer "B.Cu")
		(net 838)
	)
	(segment
		(start 138.374 63.374)
		(end 138.85 63.85)
		(width 0.2)
		(layer "B.Cu")
		(net 838)
	)
	(segment
		(start 134.653 60.779)
		(end 134.653 61.653)
		(width 0.3)
		(layer "B.Cu")
		(net 838)
	)
	(segment
		(start 134.653 61.653)
		(end 135.4 62.4)
		(width 0.3)
		(layer "B.Cu")
		(net 838)
	)
	(segment
		(start 138.702 62.098)
		(end 138.702 61.277)
		(width 0.3)
		(layer "B.Cu")
		(net 838)
	)
	(segment
		(start 138.374 62.426)
		(end 138.374 63.374)
		(width 0.2)
		(layer "B.Cu")
		(net 838)
	)
	(segment
		(start 135.4 62.4)
		(end 138.4 62.4)
		(width 0.3)
		(layer "B.Cu")
		(net 838)
	)
	(segment
		(start 134.653 61.653)
		(end 134.6 61.6)
		(width 0.1)
		(layer "B.Cu")
		(net 838)
	)
	(segment
		(start 138.702 61.277)
		(end 138.702 60.505)
		(width 0.3)
		(layer "B.Cu")
		(net 838)
	)
	(segment
		(start 138.4 62.4)
		(end 138.702 62.098)
		(width 0.3)
		(layer "B.Cu")
		(net 838)
	)
	(segment
		(start 138.702 59.052)
		(end 138.63 58.98)
		(width 0.3)
		(layer "B.Cu")
		(net 838)
	)
	(segment
		(start 138.4 62.4)
		(end 138.374 62.426)
		(width 0.2)
		(layer "B.Cu")
		(net 838)
	)
	(segment
		(start 138.702 60.505)
		(end 138.702 59.052)
		(width 0.3)
		(layer "B.Cu")
		(net 838)
	)
	(segment
		(start 146.2 62.55)
		(end 146.75 63.1)
		(width 0.2)
		(layer "B.Cu")
		(net 839)
	)
	(segment
		(start 146.632 61.297)
		(end 146.632 61.968)
		(width 0.3)
		(layer "B.Cu")
		(net 839)
	)
	(segment
		(start 146.2 62.4)
		(end 146.2 62.55)
		(width 0.2)
		(layer "B.Cu")
		(net 839)
	)
	(segment
		(start 142.653 61.6)
		(end 142.653 60.779)
		(width 0.3)
		(layer "B.Cu")
		(net 839)
	)
	(segment
		(start 143 62.4)
		(end 142.653 62.053)
		(width 0.3)
		(layer "B.Cu")
		(net 839)
	)
	(segment
		(start 146.632 61.968)
		(end 146.2 62.4)
		(width 0.3)
		(layer "B.Cu")
		(net 839)
	)
	(segment
		(start 142.653 62.053)
		(end 142.653 61.6)
		(width 0.3)
		(layer "B.Cu")
		(net 839)
	)
	(segment
		(start 146.2 62.4)
		(end 143 62.4)
		(width 0.3)
		(layer "B.Cu")
		(net 839)
	)
	(segment
		(start 146.632 60.525)
		(end 146.632 61.297)
		(width 0.3)
		(layer "B.Cu")
		(net 839)
	)
	(segment
		(start 142.633 61.58)
		(end 142.653 61.6)
		(width 0.1)
		(layer "B.Cu")
		(net 839)
	)
	(segment
		(start 146.63 60.523)
		(end 146.632 60.525)
		(width 0.3)
		(layer "B.Cu")
		(net 839)
	)
	(segment
		(start 146.63 58.98)
		(end 146.63 60.523)
		(width 0.3)
		(layer "B.Cu")
		(net 839)
	)
	(segment
		(start 141.3 61.58)
		(end 142.633 61.58)
		(width 0.1)
		(layer "B.Cu")
		(net 839)
	)
	(segment
		(start 93.3 77.1)
		(end 93.05 76.85)
		(width 0.1)
		(layer "F.Cu")
		(net 842)
	)
	(segment
		(start 95.8 76.3)
		(end 95.8 76.8)
		(width 0.1)
		(layer "F.Cu")
		(net 842)
	)
	(segment
		(start 89.7 74.1)
		(end 86.95 74.1)
		(width 0.1)
		(layer "F.Cu")
		(net 842)
	)
	(segment
		(start 95.5 77.1)
		(end 93.3 77.1)
		(width 0.1)
		(layer "F.Cu")
		(net 842)
	)
	(segment
		(start 110.430532 79.65)
		(end 109.480532 78.7)
		(width 0.1)
		(layer "F.Cu")
		(net 842)
	)
	(segment
		(start 93.05 76.5)
		(end 92.75 76.2)
		(width 0.1)
		(layer "F.Cu")
		(net 842)
	)
	(segment
		(start 98.2 77.1)
		(end 98 76.9)
		(width 0.1)
		(layer "F.Cu")
		(net 842)
	)
	(segment
		(start 109.480532 78.7)
		(end 108.3 78.7)
		(width 0.1)
		(layer "F.Cu")
		(net 842)
	)
	(segment
		(start 98 76.9)
		(end 98 76.3)
		(width 0.1)
		(layer "F.Cu")
		(net 842)
	)
	(segment
		(start 108 78.4)
		(end 108 78)
		(width 0.1)
		(layer "F.Cu")
		(net 842)
	)
	(segment
		(start 93.05 76.85)
		(end 93.05 76.5)
		(width 0.1)
		(layer "F.Cu")
		(net 842)
	)
	(segment
		(start 106.3 77.4)
		(end 106 77.1)
		(width 0.1)
		(layer "F.Cu")
		(net 842)
	)
	(segment
		(start 106 77.1)
		(end 106 76.4)
		(width 0.1)
		(layer "F.Cu")
		(net 842)
	)
	(segment
		(start 91.7 75.7)
		(end 90.930532 75.7)
		(width 0.1)
		(layer "F.Cu")
		(net 842)
	)
	(segment
		(start 92.75 76.2)
		(end 92.2 76.2)
		(width 0.1)
		(layer "F.Cu")
		(net 842)
	)
	(segment
		(start 98 76.3)
		(end 97.9 76.2)
		(width 0.1)
		(layer "F.Cu")
		(net 842)
	)
	(segment
		(start 90.530532 75.3)
		(end 90.530532 74.930532)
		(width 0.1)
		(layer "F.Cu")
		(net 842)
	)
	(segment
		(start 95.8 76.8)
		(end 95.5 77.1)
		(width 0.1)
		(layer "F.Cu")
		(net 842)
	)
	(segment
		(start 86.75 73.1)
		(end 86.45 72.8)
		(width 0.1)
		(layer "F.Cu")
		(net 842)
	)
	(segment
		(start 90.930532 75.7)
		(end 90.530532 75.3)
		(width 0.1)
		(layer "F.Cu")
		(net 842)
	)
	(segment
		(start 92.2 76.2)
		(end 91.7 75.7)
		(width 0.1)
		(layer "F.Cu")
		(net 842)
	)
	(segment
		(start 101.3 76.2)
		(end 100.4 77.1)
		(width 0.1)
		(layer "F.Cu")
		(net 842)
	)
	(segment
		(start 108.3 78.7)
		(end 108 78.4)
		(width 0.1)
		(layer "F.Cu")
		(net 842)
	)
	(segment
		(start 86.75 73.9)
		(end 86.75 73.1)
		(width 0.1)
		(layer "F.Cu")
		(net 842)
	)
	(segment
		(start 90.530532 74.930532)
		(end 89.7 74.1)
		(width 0.1)
		(layer "F.Cu")
		(net 842)
	)
	(segment
		(start 95.9 76.2)
		(end 95.8 76.3)
		(width 0.1)
		(layer "F.Cu")
		(net 842)
	)
	(segment
		(start 107.4 77.4)
		(end 106.3 77.4)
		(width 0.1)
		(layer "F.Cu")
		(net 842)
	)
	(segment
		(start 108 78)
		(end 107.4 77.4)
		(width 0.1)
		(layer "F.Cu")
		(net 842)
	)
	(segment
		(start 105.8 76.2)
		(end 101.3 76.2)
		(width 0.1)
		(layer "F.Cu")
		(net 842)
	)
	(segment
		(start 106 76.4)
		(end 105.8 76.2)
		(width 0.1)
		(layer "F.Cu")
		(net 842)
	)
	(segment
		(start 97.9 76.2)
		(end 95.9 76.2)
		(width 0.1)
		(layer "F.Cu")
		(net 842)
	)
	(segment
		(start 86.95 74.1)
		(end 86.75 73.9)
		(width 0.1)
		(layer "F.Cu")
		(net 842)
	)
	(segment
		(start 100.4 77.1)
		(end 98.2 77.1)
		(width 0.1)
		(layer "F.Cu")
		(net 842)
	)
	(via
		(at 86.45 72.8)
		(size 0.45)
		(drill 0.1)
		(layers "F.Cu" "B.Cu")
		(net 842)
	)
	(via
		(at 79.585532 106.885)
		(size 0.45)
		(drill 0.1)
		(layers "F.Cu" "B.Cu")
		(net 842)
	)
	(segment
		(start 80.700001 83.499999)
		(end 79.2 85)
		(width 0.1)
		(layer "In7.Cu")
		(net 842)
	)
	(segment
		(start 91.3 73.2)
		(end 91.3 74)
		(width 0.1)
		(layer "In7.Cu")
		(net 842)
	)
	(segment
		(start 86.45 72.8)
		(end 90.9 72.8)
		(width 0.1)
		(layer "In7.Cu")
		(net 842)
	)
	(segment
		(start 86.500002 74.499998)
		(end 81.599998 79.400002)
		(width 0.1)
		(layer "In7.Cu")
		(net 842)
	)
	(segment
		(start 90.9 72.8)
		(end 91.3 73.2)
		(width 0.1)
		(layer "In7.Cu")
		(net 842)
	)
	(segment
		(start 81.599998 79.400002)
		(end 81.599998 83.024264)
		(width 0.1)
		(layer "In7.Cu")
		(net 842)
	)
	(segment
		(start 90.800002 74.499998)
		(end 86.500002 74.499998)
		(width 0.1)
		(layer "In7.Cu")
		(net 842)
	)
	(segment
		(start 81.599998 83.024264)
		(end 81.124263 83.499999)
		(width 0.1)
		(layer "In7.Cu")
		(net 842)
	)
	(segment
		(start 79.2 106.1)
		(end 79.585532 106.485532)
		(width 0.1)
		(layer "In7.Cu")
		(net 842)
	)
	(segment
		(start 79.2 85)
		(end 79.2 106.1)
		(width 0.1)
		(layer "In7.Cu")
		(net 842)
	)
	(segment
		(start 91.3 74)
		(end 90.800002 74.499998)
		(width 0.1)
		(layer "In7.Cu")
		(net 842)
	)
	(segment
		(start 79.585532 106.485532)
		(end 79.585532 106.885)
		(width 0.1)
		(layer "In7.Cu")
		(net 842)
	)
	(segment
		(start 81.124263 83.499999)
		(end 80.700001 83.499999)
		(width 0.1)
		(layer "In7.Cu")
		(net 842)
	)
	(segment
		(start 85.115532 119.135)
		(end 84.665532 119.585)
		(width 0.19)
		(layer "F.Cu")
		(net 843)
	)
	(segment
		(start 86.715 129.22337)
		(end 86.715 119.67663)
		(width 0.19)
		(layer "F.Cu")
		(net 843)
	)
	(segment
		(start 86.17337 119.135)
		(end 85.115532 119.135)
		(width 0.19)
		(layer "F.Cu")
		(net 843)
	)
	(segment
		(start 86.015 131.07)
		(end 86.015 129.92337)
		(width 0.19)
		(layer "F.Cu")
		(net 843)
	)
	(segment
		(start 86.715 119.67663)
		(end 86.17337 119.135)
		(width 0.19)
		(layer "F.Cu")
		(net 843)
	)
	(segment
		(start 85.885 131.2)
		(end 86.015 131.07)
		(width 0.19)
		(layer "F.Cu")
		(net 843)
	)
	(segment
		(start 86.015 129.92337)
		(end 86.715 129.22337)
		(width 0.19)
		(layer "F.Cu")
		(net 843)
	)
	(via
		(at 84.665532 119.585)
		(size 0.45)
		(drill 0.1)
		(layers "F.Cu" "B.Cu")
		(net 843)
	)
	(via
		(at 85.885 131.2)
		(size 0.45)
		(drill 0.1)
		(layers "F.Cu" "B.Cu")
		(net 843)
	)
	(segment
		(start 86.015 131.33)
		(end 85.885 131.2)
		(width 0.19)
		(layer "B.Cu")
		(net 843)
	)
	(segment
		(start 91.574999 148.874999)
		(end 90.113369 148.874999)
		(width 0.19)
		(layer "B.Cu")
		(net 843)
	)
	(segment
		(start 86.015 144.77663)
		(end 86.015 131.33)
		(width 0.19)
		(layer "B.Cu")
		(net 843)
	)
	(segment
		(start 92.39 149.209999)
		(end 91.909999 149.209999)
		(width 0.19)
		(layer "B.Cu")
		(net 843)
	)
	(segment
		(start 91.909999 149.209999)
		(end 91.574999 148.874999)
		(width 0.19)
		(layer "B.Cu")
		(net 843)
	)
	(segment
		(start 90.113369 148.874999)
		(end 86.015 144.77663)
		(width 0.19)
		(layer "B.Cu")
		(net 843)
	)
	(segment
		(start 74.505532 109.425)
		(end 70.975 109.425)
		(width 0.1)
		(layer "F.Cu")
		(net 849)
	)
	(segment
		(start 70.975 109.425)
		(end 69.75 110.65)
		(width 0.1)
		(layer "F.Cu")
		(net 849)
	)
	(segment
		(start 69.75 110.65)
		(end 67.7 110.65)
		(width 0.1)
		(layer "F.Cu")
		(net 849)
	)
	(segment
		(start 102.430532 73.769468)
		(end 102 74.2)
		(width 0.1)
		(layer "F.Cu")
		(net 849)
	)
	(segment
		(start 102.430532 73.65)
		(end 102.430532 73.769468)
		(width 0.1)
		(layer "F.Cu")
		(net 849)
	)
	(via
		(at 102 74.2)
		(size 0.45)
		(drill 0.1)
		(layers "F.Cu" "B.Cu")
		(net 849)
	)
	(via
		(at 67.7 110.65)
		(size 0.45)
		(drill 0.1)
		(layers "F.Cu" "B.Cu")
		(net 849)
	)
	(via
		(at 74.505532 109.425)
		(size 0.45)
		(drill 0.1)
		(layers "F.Cu" "B.Cu")
		(net 849)
	)
	(segment
		(start 100.3 70)
		(end 100.85 70.55)
		(width 0.1)
		(layer "In5.Cu")
		(net 849)
	)
	(segment
		(start 102.4 73.2)
		(end 102.4 73.8)
		(width 0.1)
		(layer "In5.Cu")
		(net 849)
	)
	(segment
		(start 79.625 76.375)
		(end 79.625 72.525)
		(width 0.1)
		(layer "In5.Cu")
		(net 849)
	)
	(segment
		(start 68.7 77.5)
		(end 78.5 77.5)
		(width 0.1)
		(layer "In5.Cu")
		(net 849)
	)
	(segment
		(start 78.5 77.5)
		(end 79.625 76.375)
		(width 0.1)
		(layer "In5.Cu")
		(net 849)
	)
	(segment
		(start 68 82.3)
		(end 68 78.2)
		(width 0.1)
		(layer "In5.Cu")
		(net 849)
	)
	(segment
		(start 67.35 82.95)
		(end 68 82.3)
		(width 0.1)
		(layer "In5.Cu")
		(net 849)
	)
	(segment
		(start 67.35 84.3)
		(end 67.35 82.95)
		(width 0.1)
		(layer "In5.Cu")
		(net 849)
	)
	(segment
		(start 67.817157 84.767157)
		(end 67.35 84.3)
		(width 0.1)
		(layer "In5.Cu")
		(net 849)
	)
	(segment
		(start 67.7 110.65)
		(end 68.2 110.15)
		(width 0.1)
		(layer "In5.Cu")
		(net 849)
	)
	(segment
		(start 79.625 72.525)
		(end 80.9 71.25)
		(width 0.1)
		(layer "In5.Cu")
		(net 849)
	)
	(segment
		(start 68.2 110.15)
		(end 68.2 92.4)
		(width 0.1)
		(layer "In5.Cu")
		(net 849)
	)
	(segment
		(start 102.4 73.8)
		(end 102 74.2)
		(width 0.1)
		(layer "In5.Cu")
		(net 849)
	)
	(segment
		(start 94.05 71.25)
		(end 95.3 70)
		(width 0.1)
		(layer "In5.Cu")
		(net 849)
	)
	(segment
		(start 68.2 92.4)
		(end 67.6 91.8)
		(width 0.1)
		(layer "In5.Cu")
		(net 849)
	)
	(segment
		(start 67.6 85.634314)
		(end 67.817157 85.417157)
		(width 0.1)
		(layer "In5.Cu")
		(net 849)
	)
	(segment
		(start 80.9 71.25)
		(end 94.05 71.25)
		(width 0.1)
		(layer "In5.Cu")
		(net 849)
	)
	(segment
		(start 100.85 70.55)
		(end 100.85 71.65)
		(width 0.1)
		(layer "In5.Cu")
		(net 849)
	)
	(segment
		(start 100.85 71.65)
		(end 102.4 73.2)
		(width 0.1)
		(layer "In5.Cu")
		(net 849)
	)
	(segment
		(start 68 78.2)
		(end 68.7 77.5)
		(width 0.1)
		(layer "In5.Cu")
		(net 849)
	)
	(segment
		(start 67.817157 85.417157)
		(end 67.817157 84.767157)
		(width 0.1)
		(layer "In5.Cu")
		(net 849)
	)
	(segment
		(start 95.3 70)
		(end 100.3 70)
		(width 0.1)
		(layer "In5.Cu")
		(net 849)
	)
	(segment
		(start 67.6 91.8)
		(end 67.6 85.634314)
		(width 0.1)
		(layer "In5.Cu")
		(net 849)
	)
	(segment
		(start 74.565686 67.6)
		(end 77.634314 67.6)
		(width 0.1)
		(layer "F.Cu")
		(net 850)
	)
	(segment
		(start 139.931999 105.868001)
		(end 140.2 105.6)
		(width 0.1)
		(layer "F.Cu")
		(net 850)
	)
	(segment
		(start 157.4 84.8)
		(end 157.2 84.6)
		(width 0.1)
		(layer "F.Cu")
		(net 850)
	)
	(segment
		(start 102.45 56.53)
		(end 102.125 56.205)
		(width 0.1)
		(layer "F.Cu")
		(net 850)
	)
	(segment
		(start 78.710532 102.2)
		(end 74.3 102.2)
		(width 0.1)
		(layer "F.Cu")
		(net 850)
	)
	(segment
		(start 157.2 84.6)
		(end 157.2 84.2)
		(width 0.1)
		(layer "F.Cu")
		(net 850)
	)
	(segment
		(start 161.490182 136.409818)
		(end 161.7 136.2)
		(width 0.1)
		(layer "F.Cu")
		(net 850)
	)
	(segment
		(start 102.45 56.79)
		(end 102.45 56.53)
		(width 0.1)
		(layer "F.Cu")
		(net 850)
	)
	(segment
		(start 169.979468 137.479468)
		(end 169.579468 137.479468)
		(width 0.1)
		(layer "F.Cu")
		(net 850)
	)
	(segment
		(start 102.385 56.855)
		(end 102.45 56.79)
		(width 0.1)
		(layer "F.Cu")
		(net 850)
	)
	(segment
		(start 102.125 56.205)
		(end 101.44 56.205)
		(width 0.1)
		(layer "F.Cu")
		(net 850)
	)
	(segment
		(start 157.4 84.8)
		(end 160.4 84.8)
		(width 0.1)
		(layer "F.Cu")
		(net 850)
	)
	(segment
		(start 161.079468 104.320532)
		(end 161 104.4)
		(width 0.1)
		(layer "F.Cu")
		(net 850)
	)
	(segment
		(start 161.079468 103.375)
		(end 161.079468 104.320532)
		(width 0.1)
		(layer "F.Cu")
		(net 850)
	)
	(segment
		(start 153.729 111.75)
		(end 154.75 111.75)
		(width 0.1)
		(layer "F.Cu")
		(net 850)
	)
	(segment
		(start 121.6 147.15)
		(end 122 146.75)
		(width 0.1)
		(layer "F.Cu")
		(net 850)
	)
	(segment
		(start 121 143)
		(end 109.3 143)
		(width 0.1)
		(layer "F.Cu")
		(net 850)
	)
	(segment
		(start 160.997234 83.252234)
		(end 160.997234 84.202766)
		(width 0.1)
		(layer "F.Cu")
		(net 850)
	)
	(segment
		(start 208.942 94.642)
		(end 208.9 94.6)
		(width 0.1)
		(layer "F.Cu")
		(net 850)
	)
	(segment
		(start 197.9 99.652001)
		(end 198.4 100.152001)
		(width 0.1)
		(layer "F.Cu")
		(net 850)
	)
	(segment
		(start 102.45 59.16)
		(end 102.45 56.92)
		(width 0.1)
		(layer "F.Cu")
		(net 850)
	)
	(segment
		(start 154.75 111.75)
		(end 154.8 111.8)
		(width 0.1)
		(layer "F.Cu")
		(net 850)
	)
	(segment
		(start 160.4 84.8)
		(end 160.997234 84.202766)
		(width 0.1)
		(layer "F.Cu")
		(net 850)
	)
	(segment
		(start 98.72 66.95)
		(end 103.12 62.55)
		(width 0.1)
		(layer "F.Cu")
		(net 850)
	)
	(segment
		(start 155.7 112.2)
		(end 156.24 112.2)
		(width 0.1)
		(layer "F.Cu")
		(net 850)
	)
	(segment
		(start 198.902001 100.152001)
		(end 198.4 100.152001)
		(width 0.1)
		(layer "F.Cu")
		(net 850)
	)
	(segment
		(start 198.4 100.152001)
		(end 197.583746 100.152001)
		(width 0.1)
		(layer "F.Cu")
		(net 850)
	)
	(segment
		(start 102.33 56.855)
		(end 102.385 56.855)
		(width 0.1)
		(layer "F.Cu")
		(net 850)
	)
	(segment
		(start 166.7 136)
		(end 166.7 134.5)
		(width 0.1)
		(layer "F.Cu")
		(net 850)
	)
	(segment
		(start 78.834314 68.8)
		(end 92.4 68.8)
		(width 0.1)
		(layer "F.Cu")
		(net 850)
	)
	(segment
		(start 169.1 137)
		(end 169.579468 137.479468)
		(width 0.1)
		(layer "F.Cu")
		(net 850)
	)
	(segment
		(start 74.05 101.95)
		(end 74.05 94.05)
		(width 0.1)
		(layer "F.Cu")
		(net 850)
	)
	(segment
		(start 196.9 99.468255)
		(end 196.9 99.3)
		(width 0.1)
		(layer "F.Cu")
		(net 850)
	)
	(segment
		(start 197.9 99.3)
		(end 197.9 99.652001)
		(width 0.1)
		(layer "F.Cu")
		(net 850)
	)
	(segment
		(start 171.2 124)
		(end 171.2 123.036)
		(width 0.1)
		(layer "F.Cu")
		(net 850)
	)
	(segment
		(start 101.44 56.855)
		(end 102.33 56.855)
		(width 0.1)
		(layer "F.Cu")
		(net 850)
	)
	(segment
		(start 169.579468 138.52)
		(end 169.579468 137.479468)
		(width 0.1)
		(layer "F.Cu")
		(net 850)
	)
	(segment
		(start 209.634132 94.642)
		(end 208.942 94.642)
		(width 0.1)
		(layer "F.Cu")
		(net 850)
	)
	(segment
		(start 92.4 68.8)
		(end 94.25 66.95)
		(width 0.1)
		(layer "F.Cu")
		(net 850)
	)
	(segment
		(start 71.5 91.5)
		(end 71.5 70.665686)
		(width 0.1)
		(layer "F.Cu")
		(net 850)
	)
	(segment
		(start 170.229468 137.729468)
		(end 169.979468 137.479468)
		(width 0.1)
		(layer "F.Cu")
		(net 850)
	)
	(segment
		(start 171.2 123.036)
		(end 171.165 123.001)
		(width 0.1)
		(layer "F.Cu")
		(net 850)
	)
	(segment
		(start 103.12 62.55)
		(end 103.12 59.83)
		(width 0.1)
		(layer "F.Cu")
		(net 850)
	)
	(segment
		(start 167.7 137)
		(end 166.7 136)
		(width 0.1)
		(layer "F.Cu")
		(net 850)
	)
	(segment
		(start 94.25 66.95)
		(end 98.72 66.95)
		(width 0.1)
		(layer "F.Cu")
		(net 850)
	)
	(segment
		(start 109.3 143)
		(end 106.4 140.1)
		(width 0.1)
		(layer "F.Cu")
		(net 850)
	)
	(segment
		(start 74.3 102.2)
		(end 74.05 101.95)
		(width 0.1)
		(layer "F.Cu")
		(net 850)
	)
	(segment
		(start 167.7 137)
		(end 169.1 137)
		(width 0.1)
		(layer "F.Cu")
		(net 850)
	)
	(segment
		(start 194.62 130.3)
		(end 194 130.3)
		(width 0.1)
		(layer "F.Cu")
		(net 850)
	)
	(segment
		(start 171.165 123.001)
		(end 171.165 122.165)
		(width 0.1)
		(layer "F.Cu")
		(net 850)
	)
	(segment
		(start 77.634314 67.6)
		(end 78.834314 68.8)
		(width 0.1)
		(layer "F.Cu")
		(net 850)
	)
	(segment
		(start 154.8 111.8)
		(end 155.3 111.8)
		(width 0.1)
		(layer "F.Cu")
		(net 850)
	)
	(segment
		(start 194 130.3)
		(end 193.9 130.4)
		(width 0.1)
		(layer "F.Cu")
		(net 850)
	)
	(segment
		(start 140.2 105.6)
		(end 147.2 105.6)
		(width 0.1)
		(layer "F.Cu")
		(net 850)
	)
	(segment
		(start 103.12 59.83)
		(end 102.45 59.16)
		(width 0.1)
		(layer "F.Cu")
		(net 850)
	)
	(segment
		(start 74.05 94.05)
		(end 71.5 91.5)
		(width 0.1)
		(layer "F.Cu")
		(net 850)
	)
	(segment
		(start 71.5 70.665686)
		(end 74.565686 67.6)
		(width 0.1)
		(layer "F.Cu")
		(net 850)
	)
	(segment
		(start 171.165 122.165)
		(end 171 122)
		(width 0.1)
		(layer "F.Cu")
		(net 850)
	)
	(segment
		(start 122 146.75)
		(end 122 144)
		(width 0.1)
		(layer "F.Cu")
		(net 850)
	)
	(segment
		(start 102.385 56.855)
		(end 102.45 56.92)
		(width 0.1)
		(layer "F.Cu")
		(net 850)
	)
	(segment
		(start 197.583746 100.152001)
		(end 196.9 99.468255)
		(width 0.1)
		(layer "F.Cu")
		(net 850)
	)
	(segment
		(start 139.931999 106.5)
		(end 139.931999 105.868001)
		(width 0.1)
		(layer "F.Cu")
		(net 850)
	)
	(segment
		(start 155.3 111.8)
		(end 155.7 112.2)
		(width 0.1)
		(layer "F.Cu")
		(net 850)
	)
	(segment
		(start 199.5 100.75)
		(end 198.902001 100.152001)
		(width 0.1)
		(layer "F.Cu")
		(net 850)
	)
	(segment
		(start 122 144)
		(end 121 143)
		(width 0.1)
		(layer "F.Cu")
		(net 850)
	)
	(segment
		(start 171 122)
		(end 170.6 122)
		(width 0.1)
		(layer "F.Cu")
		(net 850)
	)
	(segment
		(start 170.229468 138.52)
		(end 170.229468 137.729468)
		(width 0.1)
		(layer "F.Cu")
		(net 850)
	)
	(segment
		(start 157.825001 136.409818)
		(end 161.490182 136.409818)
		(width 0.1)
		(layer "F.Cu")
		(net 850)
	)
	(segment
		(start 79.585532 103.075)
		(end 78.710532 102.2)
		(width 0.1)
		(layer "F.Cu")
		(net 850)
	)
	(segment
		(start 102.45 56.92)
		(end 102.45 56.79)
		(width 0.1)
		(layer "F.Cu")
		(net 850)
	)
	(segment
		(start 121.6 148.6)
		(end 121.6 147.15)
		(width 0.1)
		(layer "F.Cu")
		(net 850)
	)
	(via
		(at 154.8 111.8)
		(size 0.45)
		(drill 0.1)
		(layers "F.Cu" "B.Cu")
		(net 850)
	)
	(via
		(at 208.9 94.6)
		(size 0.45)
		(drill 0.1)
		(layers "F.Cu" "B.Cu")
		(net 850)
	)
	(via
		(at 121.6 148.6)
		(size 0.45)
		(drill 0.1)
		(layers "F.Cu" "B.Cu")
		(net 850)
	)
	(via
		(at 147.2 105.6)
		(size 0.45)
		(drill 0.1)
		(layers "F.Cu" "B.Cu")
		(net 850)
	)
	(via
		(at 157.2 84.2)
		(size 0.45)
		(drill 0.1)
		(layers "F.Cu" "B.Cu")
		(net 850)
	)
	(via
		(at 171.2 124)
		(size 0.45)
		(drill 0.1)
		(layers "F.Cu" "B.Cu")
		(net 850)
	)
	(via
		(at 157.825001 136.409818)
		(size 0.45)
		(drill 0.1)
		(layers "F.Cu" "B.Cu")
		(net 850)
	)
	(via
		(at 161 104.4)
		(size 0.45)
		(drill 0.1)
		(layers "F.Cu" "B.Cu")
		(net 850)
	)
	(via
		(at 202.2 105.8)
		(size 0.45)
		(drill 0.1)
		(layers "F.Cu" "B.Cu")
		(net 850)
	)
	(via
		(at 166.7 134.5)
		(size 0.45)
		(drill 0.1)
		(layers "F.Cu" "B.Cu")
		(net 850)
	)
	(via
		(at 170.6 122)
		(size 0.45)
		(drill 0.1)
		(layers "F.Cu" "B.Cu")
		(net 850)
	)
	(via
		(at 199.5 100.75)
		(size 0.45)
		(drill 0.1)
		(layers "F.Cu" "B.Cu")
		(net 850)
	)
	(via
		(at 161.7 136.2)
		(size 0.45)
		(drill 0.1)
		(layers "F.Cu" "B.Cu")
		(net 850)
	)
	(via
		(at 79.585532 103.075)
		(size 0.45)
		(drill 0.1)
		(layers "F.Cu" "B.Cu")
		(net 850)
	)
	(via
		(at 196.6 69.2)
		(size 0.45)
		(drill 0.1)
		(layers "F.Cu" "B.Cu")
		(net 850)
	)
	(via
		(at 106.4 140.1)
		(size 0.45)
		(drill 0.1)
		(layers "F.Cu" "B.Cu")
		(net 850)
	)
	(via
		(at 193.9 130.4)
		(size 0.45)
		(drill 0.1)
		(layers "F.Cu" "B.Cu")
		(net 850)
	)
	(segment
		(start 170.6 122.6)
		(end 170.6 122)
		(width 0.1)
		(layer "B.Cu")
		(net 850)
	)
	(segment
		(start 121.635 149.71)
		(end 121.635 150.935)
		(width 0.1)
		(layer "B.Cu")
		(net 850)
	)
	(segment
		(start 121.635 148.635)
		(end 121.6 148.6)
		(width 0.1)
		(layer "B.Cu")
		(net 850)
	)
	(segment
		(start 124.5 146.6)
		(end 124.801 146.299)
		(width 0.1)
		(layer "B.Cu")
		(net 850)
	)
	(segment
		(start 202.92 105.800001)
		(end 202.200001 105.800001)
		(width 0.1)
		(layer "B.Cu")
		(net 850)
	)
	(segment
		(start 121.635 149.71)
		(end 121.635 148.635)
		(width 0.1)
		(layer "B.Cu")
		(net 850)
	)
	(segment
		(start 155.5 113)
		(end 155.5 111.8)
		(width 0.1)
		(layer "B.Cu")
		(net 850)
	)
	(segment
		(start 157 111.8)
		(end 168 122.8)
		(width 0.1)
		(layer "B.Cu")
		(net 850)
	)
	(segment
		(start 121.635 150.935)
		(end 122 151.3)
		(width 0.1)
		(layer "B.Cu")
		(net 850)
	)
	(segment
		(start 168 122.8)
		(end 170.4 122.8)
		(width 0.1)
		(layer "B.Cu")
		(net 850)
	)
	(segment
		(start 154.8 111.8)
		(end 155.5 111.8)
		(width 0.1)
		(layer "B.Cu")
		(net 850)
	)
	(segment
		(start 123.6 151.3)
		(end 124.5 150.4)
		(width 0.1)
		(layer "B.Cu")
		(net 850)
	)
	(segment
		(start 196.6 70.12)
		(end 196.6 69.2)
		(width 0.1)
		(layer "B.Cu")
		(net 850)
	)
	(segment
		(start 124.5 150.4)
		(end 124.5 146.6)
		(width 0.1)
		(layer "B.Cu")
		(net 850)
	)
	(segment
		(start 124.801 146.299)
		(end 125.6085 146.299)
		(width 0.1)
		(layer "B.Cu")
		(net 850)
	)
	(segment
		(start 170.4 122.8)
		(end 170.6 122.6)
		(width 0.1)
		(layer "B.Cu")
		(net 850)
	)
	(segment
		(start 122 151.3)
		(end 123.6 151.3)
		(width 0.1)
		(layer "B.Cu")
		(net 850)
	)
	(segment
		(start 202.200001 105.800001)
		(end 202.2 105.8)
		(width 0.1)
		(layer "B.Cu")
		(net 850)
	)
	(segment
		(start 155.5 111.8)
		(end 157 111.8)
		(width 0.1)
		(layer "B.Cu")
		(net 850)
	)
	(segment
		(start 199.5 100.75)
		(end 199.5 101.3)
		(width 0.1)
		(layer "In5.Cu")
		(net 850)
	)
	(segment
		(start 154 111.6)
		(end 154.2 111.8)
		(width 0.1)
		(layer "In5.Cu")
		(net 850)
	)
	(segment
		(start 185.282841 124.882843)
		(end 182.917157 122.517159)
		(width 0.1)
		(layer "In5.Cu")
		(net 850)
	)
	(segment
		(start 166.7 134.5)
		(end 167.1 134.1)
		(width 0.1)
		(layer "In5.Cu")
		(net 850)
	)
	(segment
		(start 161 103.4)
		(end 159.2 101.6)
		(width 0.1)
		(layer "In5.Cu")
		(net 850)
	)
	(segment
		(start 196.6 70.442894)
		(end 193.97 73.072894)
		(width 0.1)
		(layer "In5.Cu")
		(net 850)
	)
	(segment
		(start 195.3 114.6)
		(end 195.3 120.8)
		(width 0.1)
		(layer "In5.Cu")
		(net 850)
	)
	(segment
		(start 201.4 103.2)
		(end 201.4 105)
		(width 0.1)
		(layer "In5.Cu")
		(net 850)
	)
	(segment
		(start 147 106.6)
		(end 147.8 107.4)
		(width 0.1)
		(layer "In5.Cu")
		(net 850)
	)
	(segment
		(start 193.9 130.4)
		(end 190.4 130.4)
		(width 0.1)
		(layer "In5.Cu")
		(net 850)
	)
	(segment
		(start 159.2 98.034314)
		(end 158.4 97.234314)
		(width 0.1)
		(layer "In5.Cu")
		(net 850)
	)
	(segment
		(start 173.2 122.517159)
		(end 172.682841 122)
		(width 0.1)
		(layer "In5.Cu")
		(net 850)
	)
	(segment
		(start 157.8 86.2)
		(end 157.8 84.8)
		(width 0.1)
		(layer "In5.Cu")
		(net 850)
	)
	(segment
		(start 199.5 100.3)
		(end 202 97.8)
		(width 0.1)
		(layer "In5.Cu")
		(net 850)
	)
	(segment
		(start 159.2 101.6)
		(end 159.2 98.034314)
		(width 0.1)
		(layer "In5.Cu")
		(net 850)
	)
	(segment
		(start 195.3 120.8)
		(end 194.95 121.15)
		(width 0.1)
		(layer "In5.Cu")
		(net 850)
	)
	(segment
		(start 154.2 111.8)
		(end 154.8 111.8)
		(width 0.1)
		(layer "In5.Cu")
		(net 850)
	)
	(segment
		(start 158.4 86.8)
		(end 157.8 86.2)
		(width 0.1)
		(layer "In5.Cu")
		(net 850)
	)
	(segment
		(start 168.4 134.1)
		(end 171.5 131)
		(width 0.1)
		(layer "In5.Cu")
		(net 850)
	)
	(segment
		(start 151.2 112.1)
		(end 151.7 111.6)
		(width 0.1)
		(layer "In5.Cu")
		(net 850)
	)
	(segment
		(start 194.17 86.92)
		(end 201.85 94.6)
		(width 0.1)
		(layer "In5.Cu")
		(net 850)
	)
	(segment
		(start 185.282841 127.682843)
		(end 185.282841 124.882843)
		(width 0.1)
		(layer "In5.Cu")
		(net 850)
	)
	(segment
		(start 202.2 105.8)
		(end 202.2 107.7)
		(width 0.1)
		(layer "In5.Cu")
		(net 850)
	)
	(segment
		(start 171.2 127.5)
		(end 171.2 124)
		(width 0.1)
		(layer "In5.Cu")
		(net 850)
	)
	(segment
		(start 190.4 130.4)
		(end 188.717158 128.717158)
		(width 0.1)
		(layer "In5.Cu")
		(net 850)
	)
	(segment
		(start 161 104.4)
		(end 161 108.2)
		(width 0.1)
		(layer "In5.Cu")
		(net 850)
	)
	(segment
		(start 202 97.8)
		(end 207 97.8)
		(width 0.1)
		(layer "In5.Cu")
		(net 850)
	)
	(segment
		(start 151.7 111.6)
		(end 154 111.6)
		(width 0.1)
		(layer "In5.Cu")
		(net 850)
	)
	(segment
		(start 199.5 101.3)
		(end 201.4 103.2)
		(width 0.1)
		(layer "In5.Cu")
		(net 850)
	)
	(segment
		(start 161 108.2)
		(end 157.4 111.8)
		(width 0.1)
		(layer "In5.Cu")
		(net 850)
	)
	(segment
		(start 194.17 79.03)
		(end 194.17 86.92)
		(width 0.1)
		(layer "In5.Cu")
		(net 850)
	)
	(segment
		(start 207 97.8)
		(end 209.4 95.4)
		(width 0.1)
		(layer "In5.Cu")
		(net 850)
	)
	(segment
		(start 157.8 84.8)
		(end 157.2 84.2)
		(width 0.1)
		(layer "In5.Cu")
		(net 850)
	)
	(segment
		(start 194.1 130.4)
		(end 193.9 130.4)
		(width 0.1)
		(layer "In5.Cu")
		(net 850)
	)
	(segment
		(start 196.6 69.2)
		(end 196.6 70.442894)
		(width 0.1)
		(layer "In5.Cu")
		(net 850)
	)
	(segment
		(start 201.4 105)
		(end 202.2 105.8)
		(width 0.1)
		(layer "In5.Cu")
		(net 850)
	)
	(segment
		(start 149.7 112.1)
		(end 151.2 112.1)
		(width 0.1)
		(layer "In5.Cu")
		(net 850)
	)
	(segment
		(start 147.8 110.2)
		(end 149.7 112.1)
		(width 0.1)
		(layer "In5.Cu")
		(net 850)
	)
	(segment
		(start 167.1 134.1)
		(end 168.4 134.1)
		(width 0.1)
		(layer "In5.Cu")
		(net 850)
	)
	(segment
		(start 209.4 95.4)
		(end 209.4 95)
		(width 0.1)
		(layer "In5.Cu")
		(net 850)
	)
	(segment
		(start 199.5 100.75)
		(end 199.5 100.3)
		(width 0.1)
		(layer "In5.Cu")
		(net 850)
	)
	(segment
		(start 147.2 105.6)
		(end 147 105.8)
		(width 0.1)
		(layer "In5.Cu")
		(net 850)
	)
	(segment
		(start 201.85 94.6)
		(end 208.9 94.6)
		(width 0.1)
		(layer "In5.Cu")
		(net 850)
	)
	(segment
		(start 171.5 127.8)
		(end 171.2 127.5)
		(width 0.1)
		(layer "In5.Cu")
		(net 850)
	)
	(segment
		(start 172.682841 122)
		(end 170.6 122)
		(width 0.1)
		(layer "In5.Cu")
		(net 850)
	)
	(segment
		(start 157.4 111.8)
		(end 154.8 111.8)
		(width 0.1)
		(layer "In5.Cu")
		(net 850)
	)
	(segment
		(start 209.4 95)
		(end 209 94.6)
		(width 0.1)
		(layer "In5.Cu")
		(net 850)
	)
	(segment
		(start 158.4 97.234314)
		(end 158.4 86.8)
		(width 0.1)
		(layer "In5.Cu")
		(net 850)
	)
	(segment
		(start 186.317156 128.717158)
		(end 185.282841 127.682843)
		(width 0.1)
		(layer "In5.Cu")
		(net 850)
	)
	(segment
		(start 147 105.8)
		(end 147 106.6)
		(width 0.1)
		(layer "In5.Cu")
		(net 850)
	)
	(segment
		(start 188.717158 128.717158)
		(end 186.317156 128.717158)
		(width 0.1)
		(layer "In5.Cu")
		(net 850)
	)
	(segment
		(start 194.95 121.15)
		(end 194.95 129.55)
		(width 0.1)
		(layer "In5.Cu")
		(net 850)
	)
	(segment
		(start 202.2 107.7)
		(end 195.3 114.6)
		(width 0.1)
		(layer "In5.Cu")
		(net 850)
	)
	(segment
		(start 209 94.6)
		(end 208.9 94.6)
		(width 0.1)
		(layer "In5.Cu")
		(net 850)
	)
	(segment
		(start 193.97 73.072894)
		(end 193.97 78.83)
		(width 0.1)
		(layer "In5.Cu")
		(net 850)
	)
	(segment
		(start 193.97 78.83)
		(end 194.17 79.03)
		(width 0.1)
		(layer "In5.Cu")
		(net 850)
	)
	(segment
		(start 161 104.4)
		(end 161 103.4)
		(width 0.1)
		(layer "In5.Cu")
		(net 850)
	)
	(segment
		(start 182.917157 122.517159)
		(end 173.2 122.517159)
		(width 0.1)
		(layer "In5.Cu")
		(net 850)
	)
	(segment
		(start 171.5 131)
		(end 171.5 127.8)
		(width 0.1)
		(layer "In5.Cu")
		(net 850)
	)
	(segment
		(start 194.95 129.55)
		(end 194.1 130.4)
		(width 0.1)
		(layer "In5.Cu")
		(net 850)
	)
	(segment
		(start 147.8 107.4)
		(end 147.8 110.2)
		(width 0.1)
		(layer "In5.Cu")
		(net 850)
	)
	(segment
		(start 161.7 136.2)
		(end 166 136.2)
		(width 0.1)
		(layer "In7.Cu")
		(net 850)
	)
	(segment
		(start 124.4 145.8)
		(end 144.824264 145.8)
		(width 0.1)
		(layer "In7.Cu")
		(net 850)
	)
	(segment
		(start 102.265686 140.1)
		(end 106.4 140.1)
		(width 0.1)
		(layer "In7.Cu")
		(net 850)
	)
	(segment
		(start 166.7 135.5)
		(end 166.7 134.5)
		(width 0.1)
		(layer "In7.Cu")
		(net 850)
	)
	(segment
		(start 124.4 145.8)
		(end 121.6 148.6)
		(width 0.1)
		(layer "In7.Cu")
		(net 850)
	)
	(segment
		(start 157.815183 136.4)
		(end 154.224264 136.4)
		(width 0.1)
		(layer "In7.Cu")
		(net 850)
	)
	(segment
		(start 154.224264 136.4)
		(end 144.824264 145.8)
		(width 0.1)
		(layer "In7.Cu")
		(net 850)
	)
	(segment
		(start 79.585532 103.075)
		(end 80.4 103.889468)
		(width 0.1)
		(layer "In7.Cu")
		(net 850)
	)
	(segment
		(start 80.4 103.889468)
		(end 80.4 128.8)
		(width 0.1)
		(layer "In7.Cu")
		(net 850)
	)
	(segment
		(start 80.4 128.8)
		(end 81.328703 129.728703)
		(width 0.1)
		(layer "In7.Cu")
		(net 850)
	)
	(segment
		(start 157.825001 136.409818)
		(end 157.815183 136.4)
		(width 0.1)
		(layer "In7.Cu")
		(net 850)
	)
	(segment
		(start 91.894389 129.728703)
		(end 102.265686 140.1)
		(width 0.1)
		(layer "In7.Cu")
		(net 850)
	)
	(segment
		(start 166 136.2)
		(end 166.7 135.5)
		(width 0.1)
		(layer "In7.Cu")
		(net 850)
	)
	(segment
		(start 81.328703 129.728703)
		(end 91.894389 129.728703)
		(width 0.1)
		(layer "In7.Cu")
		(net 850)
	)
	(segment
		(start 86.32663 118.765)
		(end 85.115532 118.765)
		(width 0.19)
		(layer "F.Cu")
		(net 851)
	)
	(segment
		(start 87.085 129.37663)
		(end 87.085 119.52337)
		(width 0.19)
		(layer "F.Cu")
		(net 851)
	)
	(segment
		(start 86.515 131.2)
		(end 86.385 131.07)
		(width 0.19)
		(layer "F.Cu")
		(net 851)
	)
	(segment
		(start 86.385 131.07)
		(end 86.385 130.07663)
		(width 0.19)
		(layer "F.Cu")
		(net 851)
	)
	(segment
		(start 86.385 130.07663)
		(end 87.085 129.37663)
		(width 0.19)
		(layer "F.Cu")
		(net 851)
	)
	(segment
		(start 87.085 119.52337)
		(end 86.32663 118.765)
		(width 0.19)
		(layer "F.Cu")
		(net 851)
	)
	(segment
		(start 85.115532 118.765)
		(end 84.665532 118.315)
		(width 0.19)
		(layer "F.Cu")
		(net 851)
	)
	(via
		(at 86.515 131.2)
		(size 0.45)
		(drill 0.1)
		(layers "F.Cu" "B.Cu")
		(net 851)
	)
	(via
		(at 84.665532 118.315)
		(size 0.45)
		(drill 0.1)
		(layers "F.Cu" "B.Cu")
		(net 851)
	)
	(segment
		(start 92.39 148.17)
		(end 91.909999 148.17)
		(width 0.19)
		(layer "B.Cu")
		(net 851)
	)
	(segment
		(start 91.909999 148.17)
		(end 91.574999 148.505)
		(width 0.19)
		(layer "B.Cu")
		(net 851)
	)
	(segment
		(start 86.385 131.33)
		(end 86.515 131.2)
		(width 0.19)
		(layer "B.Cu")
		(net 851)
	)
	(segment
		(start 86.385 144.62337)
		(end 86.385 131.33)
		(width 0.19)
		(layer "B.Cu")
		(net 851)
	)
	(segment
		(start 90.26663 148.505)
		(end 86.385 144.62337)
		(width 0.19)
		(layer "B.Cu")
		(net 851)
	)
	(segment
		(start 91.574999 148.505)
		(end 90.26663 148.505)
		(width 0.19)
		(layer "B.Cu")
		(net 851)
	)
	(segment
		(start 142 106.4)
		(end 147.4 106.4)
		(width 0.1)
		(layer "F.Cu")
		(net 853)
	)
	(segment
		(start 160.429468 104.370532)
		(end 160.4 104.4)
		(width 0.1)
		(layer "F.Cu")
		(net 853)
	)
	(segment
		(start 100.58 57.78)
		(end 100.58 56.08)
		(width 0.1)
		(layer "F.Cu")
		(net 853)
	)
	(segment
		(start 79 103.759468)
		(end 79 103.1)
		(width 0.1)
		(layer "F.Cu")
		(net 853)
	)
	(segment
		(start 208.927 93.627)
		(end 208.9 93.6)
		(width 0.1)
		(layer "F.Cu")
		(net 853)
	)
	(segment
		(start 170.5 123.016)
		(end 170.515 123.001)
		(width 0.1)
		(layer "F.Cu")
		(net 853)
	)
	(segment
		(start 79.1 68.5)
		(end 92.25 68.5)
		(width 0.1)
		(layer "F.Cu")
		(net 853)
	)
	(segment
		(start 198.9 99.3)
		(end 198.9 99.5)
		(width 0.1)
		(layer "F.Cu")
		(net 853)
	)
	(segment
		(start 168.7 137.4)
		(end 167 137.4)
		(width 0.1)
		(layer "F.Cu")
		(net 853)
	)
	(segment
		(start 166 136.4)
		(end 166 134.6)
		(width 0.1)
		(layer "F.Cu")
		(net 853)
	)
	(segment
		(start 120 145.5)
		(end 120 146.75)
		(width 0.1)
		(layer "F.Cu")
		(net 853)
	)
	(segment
		(start 77.8 67.2)
		(end 79.1 68.5)
		(width 0.1)
		(layer "F.Cu")
		(net 853)
	)
	(segment
		(start 74.4 67.2)
		(end 77.8 67.2)
		(width 0.1)
		(layer "F.Cu")
		(net 853)
	)
	(segment
		(start 71.1 91.5)
		(end 71.1 70.5)
		(width 0.1)
		(layer "F.Cu")
		(net 853)
	)
	(segment
		(start 161.6 82.4)
		(end 160.4 82.4)
		(width 0.1)
		(layer "F.Cu")
		(net 853)
	)
	(segment
		(start 141.25 107.15)
		(end 142 106.4)
		(width 0.1)
		(layer "F.Cu")
		(net 853)
	)
	(segment
		(start 118 143.5)
		(end 120 145.5)
		(width 0.1)
		(layer "F.Cu")
		(net 853)
	)
	(segment
		(start 121 148.6)
		(end 121 147.75)
		(width 0.1)
		(layer "F.Cu")
		(net 853)
	)
	(segment
		(start 78.5 102.6)
		(end 74.1 102.6)
		(width 0.1)
		(layer "F.Cu")
		(net 853)
	)
	(segment
		(start 168.929468 138.52)
		(end 168.929468 137.629468)
		(width 0.1)
		(layer "F.Cu")
		(net 853)
	)
	(segment
		(start 79 103.1)
		(end 78.5 102.6)
		(width 0.1)
		(layer "F.Cu")
		(net 853)
	)
	(segment
		(start 168.7 137.4)
		(end 168.929468 137.629468)
		(width 0.1)
		(layer "F.Cu")
		(net 853)
	)
	(segment
		(start 108.9 143.5)
		(end 118 143.5)
		(width 0.1)
		(layer "F.Cu")
		(net 853)
	)
	(segment
		(start 102.74 62.5)
		(end 102.74 59.94)
		(width 0.1)
		(layer "F.Cu")
		(net 853)
	)
	(segment
		(start 160.429468 103.375)
		(end 160.429468 104.370532)
		(width 0.1)
		(layer "F.Cu")
		(net 853)
	)
	(segment
		(start 102.74 59.94)
		(end 100.58 57.78)
		(width 0.1)
		(layer "F.Cu")
		(net 853)
	)
	(segment
		(start 74.1 102.6)
		(end 73.7 102.2)
		(width 0.1)
		(layer "F.Cu")
		(net 853)
	)
	(segment
		(start 121 147.75)
		(end 120 146.75)
		(width 0.1)
		(layer "F.Cu")
		(net 853)
	)
	(segment
		(start 73.7 94.1)
		(end 71.1 91.5)
		(width 0.1)
		(layer "F.Cu")
		(net 853)
	)
	(segment
		(start 71.1 70.5)
		(end 74.4 67.2)
		(width 0.1)
		(layer "F.Cu")
		(net 853)
	)
	(segment
		(start 153.729 111.25)
		(end 154.35 111.25)
		(width 0.1)
		(layer "F.Cu")
		(net 853)
	)
	(segment
		(start 101.105 55.555)
		(end 101.44 55.555)
		(width 0.1)
		(layer "F.Cu")
		(net 853)
	)
	(segment
		(start 105.9 140.5)
		(end 108.9 143.5)
		(width 0.1)
		(layer "F.Cu")
		(net 853)
	)
	(segment
		(start 100.58 56.08)
		(end 101.105 55.555)
		(width 0.1)
		(layer "F.Cu")
		(net 853)
	)
	(segment
		(start 160.4 82.4)
		(end 160.347234 82.452766)
		(width 0.1)
		(layer "F.Cu")
		(net 853)
	)
	(segment
		(start 170.5 123.9)
		(end 170.5 123.016)
		(width 0.1)
		(layer "F.Cu")
		(net 853)
	)
	(segment
		(start 157.4 135.3)
		(end 157.9 134.8)
		(width 0.1)
		(layer "F.Cu")
		(net 853)
	)
	(segment
		(start 154.4 111.2)
		(end 156.24 111.2)
		(width 0.1)
		(layer "F.Cu")
		(net 853)
	)
	(segment
		(start 209.634132 93.627)
		(end 208.927 93.627)
		(width 0.1)
		(layer "F.Cu")
		(net 853)
	)
	(segment
		(start 167 137.4)
		(end 166 136.4)
		(width 0.1)
		(layer "F.Cu")
		(net 853)
	)
	(segment
		(start 157.9 134.8)
		(end 161.5 134.8)
		(width 0.1)
		(layer "F.Cu")
		(net 853)
	)
	(segment
		(start 98.54 66.7)
		(end 102.74 62.5)
		(width 0.1)
		(layer "F.Cu")
		(net 853)
	)
	(segment
		(start 94.05 66.7)
		(end 98.54 66.7)
		(width 0.1)
		(layer "F.Cu")
		(net 853)
	)
	(segment
		(start 161.647234 83.252234)
		(end 161.647234 82.447234)
		(width 0.1)
		(layer "F.Cu")
		(net 853)
	)
	(segment
		(start 194.62 131.3)
		(end 193.9 131.3)
		(width 0.1)
		(layer "F.Cu")
		(net 853)
	)
	(segment
		(start 79.585532 104.345)
		(end 79 103.759468)
		(width 0.1)
		(layer "F.Cu")
		(net 853)
	)
	(segment
		(start 154.35 111.25)
		(end 154.4 111.2)
		(width 0.1)
		(layer "F.Cu")
		(net 853)
	)
	(segment
		(start 161.647234 82.447234)
		(end 161.6 82.4)
		(width 0.1)
		(layer "F.Cu")
		(net 853)
	)
	(segment
		(start 122.4 149.1)
		(end 121.5 149.1)
		(width 0.1)
		(layer "F.Cu")
		(net 853)
	)
	(segment
		(start 73.7 102.2)
		(end 73.7 94.1)
		(width 0.1)
		(layer "F.Cu")
		(net 853)
	)
	(segment
		(start 121.5 149.1)
		(end 121 148.6)
		(width 0.1)
		(layer "F.Cu")
		(net 853)
	)
	(segment
		(start 160.347234 83.252234)
		(end 160.347234 84.052766)
		(width 0.1)
		(layer "F.Cu")
		(net 853)
	)
	(segment
		(start 198.9 99.5)
		(end 200.2 100.8)
		(width 0.1)
		(layer "F.Cu")
		(net 853)
	)
	(segment
		(start 122.9 148.6)
		(end 122.4 149.1)
		(width 0.1)
		(layer "F.Cu")
		(net 853)
	)
	(segment
		(start 157.4 135.6)
		(end 157.4 135.3)
		(width 0.1)
		(layer "F.Cu")
		(net 853)
	)
	(segment
		(start 160.347234 84.052766)
		(end 160.2 84.2)
		(width 0.1)
		(layer "F.Cu")
		(net 853)
	)
	(segment
		(start 160.2 84.2)
		(end 158 84.2)
		(width 0.1)
		(layer "F.Cu")
		(net 853)
	)
	(segment
		(start 140.581999 107.15)
		(end 141.25 107.15)
		(width 0.1)
		(layer "F.Cu")
		(net 853)
	)
	(segment
		(start 92.25 68.5)
		(end 94.05 66.7)
		(width 0.1)
		(layer "F.Cu")
		(net 853)
	)
	(segment
		(start 160.347234 83.252234)
		(end 160.347234 82.452766)
		(width 0.1)
		(layer "F.Cu")
		(net 853)
	)
	(via
		(at 157.4 135.6)
		(size 0.45)
		(drill 0.1)
		(layers "F.Cu" "B.Cu")
		(net 853)
	)
	(via
		(at 154.4 111.2)
		(size 0.45)
		(drill 0.1)
		(layers "F.Cu" "B.Cu")
		(net 853)
	)
	(via
		(at 208.9 93.6)
		(size 0.45)
		(drill 0.1)
		(layers "F.Cu" "B.Cu")
		(net 853)
	)
	(via
		(at 147.4 106.4)
		(size 0.45)
		(drill 0.1)
		(layers "F.Cu" "B.Cu")
		(net 853)
	)
	(via
		(at 202.2 104.8)
		(size 0.45)
		(drill 0.1)
		(layers "F.Cu" "B.Cu")
		(net 853)
	)
	(via
		(at 166 134.6)
		(size 0.45)
		(drill 0.1)
		(layers "F.Cu" "B.Cu")
		(net 853)
	)
	(via
		(at 122.9 148.6)
		(size 0.45)
		(drill 0.1)
		(layers "F.Cu" "B.Cu")
		(net 853)
	)
	(via
		(at 199.6 69.2)
		(size 0.45)
		(drill 0.1)
		(layers "F.Cu" "B.Cu")
		(net 853)
	)
	(via
		(at 158 84.2)
		(size 0.45)
		(drill 0.1)
		(layers "F.Cu" "B.Cu")
		(net 853)
	)
	(via
		(at 200.2 100.8)
		(size 0.45)
		(drill 0.1)
		(layers "F.Cu" "B.Cu")
		(net 853)
	)
	(via
		(at 161.5 134.8)
		(size 0.45)
		(drill 0.1)
		(layers "F.Cu" "B.Cu")
		(net 853)
	)
	(via
		(at 79.585532 104.345)
		(size 0.45)
		(drill 0.1)
		(layers "F.Cu" "B.Cu")
		(net 853)
	)
	(via
		(at 170.5 123.9)
		(size 0.45)
		(drill 0.1)
		(layers "F.Cu" "B.Cu")
		(net 853)
	)
	(via
		(at 160.4 104.4)
		(size 0.45)
		(drill 0.1)
		(layers "F.Cu" "B.Cu")
		(net 853)
	)
	(via
		(at 193.9 131.3)
		(size 0.45)
		(drill 0.1)
		(layers "F.Cu" "B.Cu")
		(net 853)
	)
	(via
		(at 105.9 140.5)
		(size 0.45)
		(drill 0.1)
		(layers "F.Cu" "B.Cu")
		(net 853)
	)
	(segment
		(start 199.6 70.12)
		(end 199.6 69.2)
		(width 0.1)
		(layer "B.Cu")
		(net 853)
	)
	(segment
		(start 124 148.1)
		(end 124 146.4)
		(width 0.1)
		(layer "B.Cu")
		(net 853)
	)
	(segment
		(start 154.4 111.2)
		(end 155.5 111.2)
		(width 0.1)
		(layer "B.Cu")
		(net 853)
	)
	(segment
		(start 123.5 148.6)
		(end 124 148.1)
		(width 0.1)
		(layer "B.Cu")
		(net 853)
	)
	(segment
		(start 171 121.6)
		(end 171.2 121.8)
		(width 0.1)
		(layer "B.Cu")
		(net 853)
	)
	(segment
		(start 155.5 111.2)
		(end 157 111.2)
		(width 0.1)
		(layer "B.Cu")
		(net 853)
	)
	(segment
		(start 171.2 121.8)
		(end 171.2 123.2)
		(width 0.1)
		(layer "B.Cu")
		(net 853)
	)
	(segment
		(start 202.92 104.8)
		(end 202.2 104.8)
		(width 0.1)
		(layer "B.Cu")
		(net 853)
	)
	(segment
		(start 155.5 110)
		(end 155.5 111.2)
		(width 0.1)
		(layer "B.Cu")
		(net 853)
	)
	(segment
		(start 169.424264 122.375736)
		(end 170.2 121.6)
		(width 0.1)
		(layer "B.Cu")
		(net 853)
	)
	(segment
		(start 124.601 145.799)
		(end 125.6085 145.799)
		(width 0.1)
		(layer "B.Cu")
		(net 853)
	)
	(segment
		(start 170.2 121.6)
		(end 171 121.6)
		(width 0.1)
		(layer "B.Cu")
		(net 853)
	)
	(segment
		(start 122.905 149.71)
		(end 122.905 148.605)
		(width 0.1)
		(layer "B.Cu")
		(net 853)
	)
	(segment
		(start 122.905 148.605)
		(end 122.9 148.6)
		(width 0.1)
		(layer "B.Cu")
		(net 853)
	)
	(segment
		(start 124 146.4)
		(end 124.601 145.799)
		(width 0.1)
		(layer "B.Cu")
		(net 853)
	)
	(segment
		(start 157 111.2)
		(end 168.175736 122.375736)
		(width 0.1)
		(layer "B.Cu")
		(net 853)
	)
	(segment
		(start 168.175736 122.375736)
		(end 169.424264 122.375736)
		(width 0.1)
		(layer "B.Cu")
		(net 853)
	)
	(segment
		(start 171.2 123.2)
		(end 170.5 123.9)
		(width 0.1)
		(layer "B.Cu")
		(net 853)
	)
	(segment
		(start 122.9 148.6)
		(end 123.5 148.6)
		(width 0.1)
		(layer "B.Cu")
		(net 853)
	)
	(segment
		(start 148.25 107.25)
		(end 148.25 109.95)
		(width 0.1)
		(layer "In5.Cu")
		(net 853)
	)
	(segment
		(start 193.9 131.3)
		(end 190.9 131.3)
		(width 0.1)
		(layer "In5.Cu")
		(net 853)
	)
	(segment
		(start 149.4 111.1)
		(end 151.6 111.1)
		(width 0.1)
		(layer "In5.Cu")
		(net 853)
	)
	(segment
		(start 194.7 131.3)
		(end 195.365685 130.634315)
		(width 0.1)
		(layer "In5.Cu")
		(net 853)
	)
	(segment
		(start 200.2 100.8)
		(end 200.2 100.365686)
		(width 0.1)
		(layer "In5.Cu")
		(net 853)
	)
	(segment
		(start 157.6 83.6)
		(end 156.8 83.6)
		(width 0.1)
		(layer "In5.Cu")
		(net 853)
	)
	(segment
		(start 196.75 71)
		(end 197.8 71)
		(width 0.1)
		(layer "In5.Cu")
		(net 853)
	)
	(segment
		(start 194.31 77.32)
		(end 194.31 73.44)
		(width 0.1)
		(layer "In5.Cu")
		(net 853)
	)
	(segment
		(start 208.9 93.6)
		(end 206.4 93.6)
		(width 0.1)
		(layer "In5.Cu")
		(net 853)
	)
	(segment
		(start 209.2 93.6)
		(end 208.9 93.6)
		(width 0.1)
		(layer "In5.Cu")
		(net 853)
	)
	(segment
		(start 171.2 122.8)
		(end 170.5 123.5)
		(width 0.1)
		(layer "In5.Cu")
		(net 853)
	)
	(segment
		(start 170.1 132.1)
		(end 170.1 126.1)
		(width 0.1)
		(layer "In5.Cu")
		(net 853)
	)
	(segment
		(start 206 94)
		(end 202.5 94)
		(width 0.1)
		(layer "In5.Cu")
		(net 853)
	)
	(segment
		(start 151.6 111.1)
		(end 151.7 111.2)
		(width 0.1)
		(layer "In5.Cu")
		(net 853)
	)
	(segment
		(start 154.4 111.2)
		(end 156.8 111.2)
		(width 0.1)
		(layer "In5.Cu")
		(net 853)
	)
	(segment
		(start 160.4 107.6)
		(end 160.4 104.4)
		(width 0.1)
		(layer "In5.Cu")
		(net 853)
	)
	(segment
		(start 147.4 106.4)
		(end 148.25 107.25)
		(width 0.1)
		(layer "In5.Cu")
		(net 853)
	)
	(segment
		(start 186.2 129)
		(end 185 127.8)
		(width 0.1)
		(layer "In5.Cu")
		(net 853)
	)
	(segment
		(start 209.8 94.2)
		(end 209.2 93.6)
		(width 0.1)
		(layer "In5.Cu")
		(net 853)
	)
	(segment
		(start 200.2 100.365686)
		(end 202.365686 98.2)
		(width 0.1)
		(layer "In5.Cu")
		(net 853)
	)
	(segment
		(start 156.6 84.4)
		(end 157.4 85.2)
		(width 0.1)
		(layer "In5.Cu")
		(net 853)
	)
	(segment
		(start 170.6 124)
		(end 170.5 123.9)
		(width 0.1)
		(layer "In5.Cu")
		(net 853)
	)
	(segment
		(start 166 134.6)
		(end 166.3 134.3)
		(width 0.1)
		(layer "In5.Cu")
		(net 853)
	)
	(segment
		(start 151.7 111.2)
		(end 154.4 111.2)
		(width 0.1)
		(layer "In5.Cu")
		(net 853)
	)
	(segment
		(start 185 127.8)
		(end 185 125)
		(width 0.1)
		(layer "In5.Cu")
		(net 853)
	)
	(segment
		(start 200.2 100.8)
		(end 202.2 102.8)
		(width 0.1)
		(layer "In5.Cu")
		(net 853)
	)
	(segment
		(start 194.31 73.44)
		(end 196.75 71)
		(width 0.1)
		(layer "In5.Cu")
		(net 853)
	)
	(segment
		(start 182.8 122.8)
		(end 171.2 122.8)
		(width 0.1)
		(layer "In5.Cu")
		(net 853)
	)
	(segment
		(start 156.8 111.2)
		(end 160.4 107.6)
		(width 0.1)
		(layer "In5.Cu")
		(net 853)
	)
	(segment
		(start 156.8 83.6)
		(end 156.6 83.8)
		(width 0.1)
		(layer "In5.Cu")
		(net 853)
	)
	(segment
		(start 209.8 95.565686)
		(end 209.8 94.2)
		(width 0.1)
		(layer "In5.Cu")
		(net 853)
	)
	(segment
		(start 190.9 131.3)
		(end 188.6 129)
		(width 0.1)
		(layer "In5.Cu")
		(net 853)
	)
	(segment
		(start 160.4 103.6)
		(end 158.8 102)
		(width 0.1)
		(layer "In5.Cu")
		(net 853)
	)
	(segment
		(start 202.2 102.8)
		(end 202.2 104.8)
		(width 0.1)
		(layer "In5.Cu")
		(net 853)
	)
	(segment
		(start 207.165686 98.2)
		(end 209.8 95.565686)
		(width 0.1)
		(layer "In5.Cu")
		(net 853)
	)
	(segment
		(start 202.5 94)
		(end 196 87.5)
		(width 0.1)
		(layer "In5.Cu")
		(net 853)
	)
	(segment
		(start 158 86.965686)
		(end 157.4 86.365686)
		(width 0.1)
		(layer "In5.Cu")
		(net 853)
	)
	(segment
		(start 156.6 83.8)
		(end 156.6 84.4)
		(width 0.1)
		(layer "In5.Cu")
		(net 853)
	)
	(segment
		(start 168.6 133.6)
		(end 170.1 132.1)
		(width 0.1)
		(layer "In5.Cu")
		(net 853)
	)
	(segment
		(start 202.8 107.9)
		(end 202.8 105.4)
		(width 0.1)
		(layer "In5.Cu")
		(net 853)
	)
	(segment
		(start 195.365685 121.534315)
		(end 195.865685 121.034315)
		(width 0.1)
		(layer "In5.Cu")
		(net 853)
	)
	(segment
		(start 158 84.2)
		(end 158 84)
		(width 0.1)
		(layer "In5.Cu")
		(net 853)
	)
	(segment
		(start 196 87.5)
		(end 196 79.01)
		(width 0.1)
		(layer "In5.Cu")
		(net 853)
	)
	(segment
		(start 166.3 134)
		(end 166.7 133.6)
		(width 0.1)
		(layer "In5.Cu")
		(net 853)
	)
	(segment
		(start 202.365686 98.2)
		(end 207.165686 98.2)
		(width 0.1)
		(layer "In5.Cu")
		(net 853)
	)
	(segment
		(start 158 84)
		(end 157.6 83.6)
		(width 0.1)
		(layer "In5.Cu")
		(net 853)
	)
	(segment
		(start 197.8 71)
		(end 199.6 69.2)
		(width 0.1)
		(layer "In5.Cu")
		(net 853)
	)
	(segment
		(start 157.4 85.2)
		(end 157.4 86.365686)
		(width 0.1)
		(layer "In5.Cu")
		(net 853)
	)
	(segment
		(start 170.5 123.5)
		(end 170.5 123.9)
		(width 0.1)
		(layer "In5.Cu")
		(net 853)
	)
	(segment
		(start 170.6 125.6)
		(end 170.6 124)
		(width 0.1)
		(layer "In5.Cu")
		(net 853)
	)
	(segment
		(start 188.6 129)
		(end 186.2 129)
		(width 0.1)
		(layer "In5.Cu")
		(net 853)
	)
	(segment
		(start 206.4 93.6)
		(end 206 94)
		(width 0.1)
		(layer "In5.Cu")
		(net 853)
	)
	(segment
		(start 170.1 126.1)
		(end 170.6 125.6)
		(width 0.1)
		(layer "In5.Cu")
		(net 853)
	)
	(segment
		(start 193.9 131.3)
		(end 194.7 131.3)
		(width 0.1)
		(layer "In5.Cu")
		(net 853)
	)
	(segment
		(start 202.8 105.4)
		(end 202.2 104.8)
		(width 0.1)
		(layer "In5.Cu")
		(net 853)
	)
	(segment
		(start 185 125)
		(end 182.8 122.8)
		(width 0.1)
		(layer "In5.Cu")
		(net 853)
	)
	(segment
		(start 158 97.4)
		(end 158 86.965686)
		(width 0.1)
		(layer "In5.Cu")
		(net 853)
	)
	(segment
		(start 195.865685 114.834315)
		(end 202.8 107.9)
		(width 0.1)
		(layer "In5.Cu")
		(net 853)
	)
	(segment
		(start 166.7 133.6)
		(end 168.6 133.6)
		(width 0.1)
		(layer "In5.Cu")
		(net 853)
	)
	(segment
		(start 158.8 102)
		(end 158.8 98.2)
		(width 0.1)
		(layer "In5.Cu")
		(net 853)
	)
	(segment
		(start 160.4 104.4)
		(end 160.4 103.6)
		(width 0.1)
		(layer "In5.Cu")
		(net 853)
	)
	(segment
		(start 166.3 134.3)
		(end 166.3 134)
		(width 0.1)
		(layer "In5.Cu")
		(net 853)
	)
	(segment
		(start 195.365685 130.634315)
		(end 195.365685 121.534315)
		(width 0.1)
		(layer "In5.Cu")
		(net 853)
	)
	(segment
		(start 148.25 109.95)
		(end 149.4 111.1)
		(width 0.1)
		(layer "In5.Cu")
		(net 853)
	)
	(segment
		(start 196 79.01)
		(end 194.31 77.32)
		(width 0.1)
		(layer "In5.Cu")
		(net 853)
	)
	(segment
		(start 158.8 98.2)
		(end 158 97.4)
		(width 0.1)
		(layer "In5.Cu")
		(net 853)
	)
	(segment
		(start 195.865685 121.034315)
		(end 195.865685 114.834315)
		(width 0.1)
		(layer "In5.Cu")
		(net 853)
	)
	(segment
		(start 121.05 147.3)
		(end 121.05 148.75)
		(width 0.1)
		(layer "In7.Cu")
		(net 853)
	)
	(segment
		(start 144.7 145.5)
		(end 122.85 145.5)
		(width 0.1)
		(layer "In7.Cu")
		(net 853)
	)
	(segment
		(start 121.05 148.75)
		(end 121.5 149.2)
		(width 0.1)
		(layer "In7.Cu")
		(net 853)
	)
	(segment
		(start 161.5 134.8)
		(end 162.2 135.5)
		(width 0.1)
		(layer "In7.Cu")
		(net 853)
	)
	(segment
		(start 79.585532 104.345)
		(end 79.945 104.345)
		(width 0.1)
		(layer "In7.Cu")
		(net 853)
	)
	(segment
		(start 91.728703 130.128703)
		(end 102.1 140.5)
		(width 0.1)
		(layer "In7.Cu")
		(net 853)
	)
	(segment
		(start 154.6 135.6)
		(end 157.4 135.6)
		(width 0.1)
		(layer "In7.Cu")
		(net 853)
	)
	(segment
		(start 81.163017 130.128703)
		(end 91.728703 130.128703)
		(width 0.1)
		(layer "In7.Cu")
		(net 853)
	)
	(segment
		(start 79.945 104.345)
		(end 80 104.4)
		(width 0.1)
		(layer "In7.Cu")
		(net 853)
	)
	(segment
		(start 80 104.4)
		(end 80 128.965686)
		(width 0.1)
		(layer "In7.Cu")
		(net 853)
	)
	(segment
		(start 80 128.965686)
		(end 81.163017 130.128703)
		(width 0.1)
		(layer "In7.Cu")
		(net 853)
	)
	(segment
		(start 102.1 140.5)
		(end 105.9 140.5)
		(width 0.1)
		(layer "In7.Cu")
		(net 853)
	)
	(segment
		(start 122.3 149.2)
		(end 122.9 148.6)
		(width 0.1)
		(layer "In7.Cu")
		(net 853)
	)
	(segment
		(start 121.5 149.2)
		(end 122.3 149.2)
		(width 0.1)
		(layer "In7.Cu")
		(net 853)
	)
	(segment
		(start 144.7 145.5)
		(end 154.6 135.6)
		(width 0.1)
		(layer "In7.Cu")
		(net 853)
	)
	(segment
		(start 122.85 145.5)
		(end 121.05 147.3)
		(width 0.1)
		(layer "In7.Cu")
		(net 853)
	)
	(segment
		(start 165.1 135.5)
		(end 166 134.6)
		(width 0.1)
		(layer "In7.Cu")
		(net 853)
	)
	(segment
		(start 162.2 135.5)
		(end 165.1 135.5)
		(width 0.1)
		(layer "In7.Cu")
		(net 853)
	)
	(via
		(at 134.330532 78.15)
		(size 0.45)
		(drill 0.1)
		(layers "F.Cu" "B.Cu")
		(net 856)
	)
	(via
		(at 75.9 112.6)
		(size 0.45)
		(drill 0.1)
		(layers "F.Cu" "B.Cu")
		(net 856)
	)
	(segment
		(start 78.950532 112.6)
		(end 79.585532 111.965)
		(width 0.1)
		(layer "B.Cu")
		(net 856)
	)
	(segment
		(start 75.9 112.6)
		(end 78.950532 112.6)
		(width 0.1)
		(layer "B.Cu")
		(net 856)
	)
	(segment
		(start 134.6 83.1)
		(end 133.9 83.8)
		(width 0.1)
		(layer "In5.Cu")
		(net 856)
	)
	(segment
		(start 78.8 121.4)
		(end 76.8 121.4)
		(width 0.1)
		(layer "In5.Cu")
		(net 856)
	)
	(segment
		(start 133.7 84.55)
		(end 133.7 86.4)
		(width 0.1)
		(layer "In5.Cu")
		(net 856)
	)
	(segment
		(start 134.6 82.1)
		(end 134.6 83.1)
		(width 0.1)
		(layer "In5.Cu")
		(net 856)
	)
	(segment
		(start 79.1 122.5)
		(end 79.1 121.7)
		(width 0.1)
		(layer "In5.Cu")
		(net 856)
	)
	(segment
		(start 104.7 116.7)
		(end 100.799998 120.600002)
		(width 0.1)
		(layer "In5.Cu")
		(net 856)
	)
	(segment
		(start 88.499998 120.600002)
		(end 86.4 122.7)
		(width 0.1)
		(layer "In5.Cu")
		(net 856)
	)
	(segment
		(start 129.2 91.6)
		(end 129.2 116.4)
		(width 0.1)
		(layer "In5.Cu")
		(net 856)
	)
	(segment
		(start 86.4 122.7)
		(end 79.3 122.7)
		(width 0.1)
		(layer "In5.Cu")
		(net 856)
	)
	(segment
		(start 133.95 78.530532)
		(end 133.95 81.45)
		(width 0.1)
		(layer "In5.Cu")
		(net 856)
	)
	(segment
		(start 133.95 81.45)
		(end 134.6 82.1)
		(width 0.1)
		(layer "In5.Cu")
		(net 856)
	)
	(segment
		(start 133.9 84.35)
		(end 133.7 84.55)
		(width 0.1)
		(layer "In5.Cu")
		(net 856)
	)
	(segment
		(start 133.9 83.8)
		(end 133.9 84.35)
		(width 0.1)
		(layer "In5.Cu")
		(net 856)
	)
	(segment
		(start 79.3 122.7)
		(end 79.1 122.5)
		(width 0.1)
		(layer "In5.Cu")
		(net 856)
	)
	(segment
		(start 76.8 121.4)
		(end 76.6 121.2)
		(width 0.1)
		(layer "In5.Cu")
		(net 856)
	)
	(segment
		(start 133.7 86.4)
		(end 132.25 87.85)
		(width 0.1)
		(layer "In5.Cu")
		(net 856)
	)
	(segment
		(start 76.6 112.8)
		(end 76.4 112.6)
		(width 0.1)
		(layer "In5.Cu")
		(net 856)
	)
	(segment
		(start 76.6 121.2)
		(end 76.6 112.8)
		(width 0.1)
		(layer "In5.Cu")
		(net 856)
	)
	(segment
		(start 132.25 88.55)
		(end 129.2 91.6)
		(width 0.1)
		(layer "In5.Cu")
		(net 856)
	)
	(segment
		(start 129.2 116.4)
		(end 128.9 116.7)
		(width 0.1)
		(layer "In5.Cu")
		(net 856)
	)
	(segment
		(start 132.25 87.85)
		(end 132.25 88.55)
		(width 0.1)
		(layer "In5.Cu")
		(net 856)
	)
	(segment
		(start 134.330532 78.15)
		(end 133.95 78.530532)
		(width 0.1)
		(layer "In5.Cu")
		(net 856)
	)
	(segment
		(start 100.799998 120.600002)
		(end 88.499998 120.600002)
		(width 0.1)
		(layer "In5.Cu")
		(net 856)
	)
	(segment
		(start 79.1 121.7)
		(end 78.8 121.4)
		(width 0.1)
		(layer "In5.Cu")
		(net 856)
	)
	(segment
		(start 128.9 116.7)
		(end 104.7 116.7)
		(width 0.1)
		(layer "In5.Cu")
		(net 856)
	)
	(segment
		(start 76.4 112.6)
		(end 75.9 112.6)
		(width 0.1)
		(layer "In5.Cu")
		(net 856)
	)
	(via
		(at 135.230532 78.15)
		(size 0.45)
		(drill 0.1)
		(layers "F.Cu" "B.Cu")
		(net 857)
	)
	(via
		(at 75.925 113.875)
		(size 0.45)
		(drill 0.1)
		(layers "F.Cu" "B.Cu")
		(net 857)
	)
	(segment
		(start 75.925 113.875)
		(end 80.025 113.875)
		(width 0.1)
		(layer "B.Cu")
		(net 857)
	)
	(segment
		(start 80.2 113.7)
		(end 80.2 111.309468)
		(width 0.1)
		(layer "B.Cu")
		(net 857)
	)
	(segment
		(start 80.2 111.309468)
		(end 79.585532 110.695)
		(width 0.1)
		(layer "B.Cu")
		(net 857)
	)
	(segment
		(start 80.025 113.875)
		(end 80.2 113.7)
		(width 0.1)
		(layer "B.Cu")
		(net 857)
	)
	(segment
		(start 76.35 114)
		(end 76.35 121.374262)
		(width 0.1)
		(layer "In5.Cu")
		(net 857)
	)
	(segment
		(start 75.925 113.875)
		(end 75.95 113.9)
		(width 0.1)
		(layer "In5.Cu")
		(net 857)
	)
	(segment
		(start 79.175736 122.999998)
		(end 86.524264 122.999998)
		(width 0.1)
		(layer "In5.Cu")
		(net 857)
	)
	(segment
		(start 78.800002 122.624264)
		(end 79.175736 122.999998)
		(width 0.1)
		(layer "In5.Cu")
		(net 857)
	)
	(segment
		(start 134.6 85)
		(end 134.8 84.8)
		(width 0.1)
		(layer "In5.Cu")
		(net 857)
	)
	(segment
		(start 86.524264 122.999998)
		(end 88.624262 120.9)
		(width 0.1)
		(layer "In5.Cu")
		(net 857)
	)
	(segment
		(start 75.95 113.9)
		(end 76.25 113.9)
		(width 0.1)
		(layer "In5.Cu")
		(net 857)
	)
	(segment
		(start 134.6 80.2)
		(end 134.6 78.780532)
		(width 0.1)
		(layer "In5.Cu")
		(net 857)
	)
	(segment
		(start 134.8 81.6)
		(end 134.8 80.4)
		(width 0.1)
		(layer "In5.Cu")
		(net 857)
	)
	(segment
		(start 104.9 117.1)
		(end 129 117.1)
		(width 0.1)
		(layer "In5.Cu")
		(net 857)
	)
	(segment
		(start 134.8 84.8)
		(end 134.8 83.706139)
		(width 0.1)
		(layer "In5.Cu")
		(net 857)
	)
	(segment
		(start 135.5 83.006139)
		(end 135.5 82.3)
		(width 0.1)
		(layer "In5.Cu")
		(net 857)
	)
	(segment
		(start 134.6 86.8)
		(end 134.6 85)
		(width 0.1)
		(layer "In5.Cu")
		(net 857)
	)
	(segment
		(start 134.8 80.4)
		(end 134.6 80.2)
		(width 0.1)
		(layer "In5.Cu")
		(net 857)
	)
	(segment
		(start 76.35 121.374262)
		(end 76.675736 121.699998)
		(width 0.1)
		(layer "In5.Cu")
		(net 857)
	)
	(segment
		(start 101.1 120.9)
		(end 104.9 117.1)
		(width 0.1)
		(layer "In5.Cu")
		(net 857)
	)
	(segment
		(start 129 117.1)
		(end 129.5 116.6)
		(width 0.1)
		(layer "In5.Cu")
		(net 857)
	)
	(segment
		(start 75.925 113.875)
		(end 75.9 113.9)
		(width 0.1)
		(layer "In5.Cu")
		(net 857)
	)
	(segment
		(start 76.675736 121.699998)
		(end 78.675736 121.699998)
		(width 0.1)
		(layer "In5.Cu")
		(net 857)
	)
	(segment
		(start 78.800002 121.824264)
		(end 78.800002 122.624264)
		(width 0.1)
		(layer "In5.Cu")
		(net 857)
	)
	(segment
		(start 134.8 83.706139)
		(end 135.5 83.006139)
		(width 0.1)
		(layer "In5.Cu")
		(net 857)
	)
	(segment
		(start 129.5 116.6)
		(end 129.5 91.9)
		(width 0.1)
		(layer "In5.Cu")
		(net 857)
	)
	(segment
		(start 135.5 82.3)
		(end 134.8 81.6)
		(width 0.1)
		(layer "In5.Cu")
		(net 857)
	)
	(segment
		(start 88.624262 120.9)
		(end 101.1 120.9)
		(width 0.1)
		(layer "In5.Cu")
		(net 857)
	)
	(segment
		(start 78.675736 121.699998)
		(end 78.800002 121.824264)
		(width 0.1)
		(layer "In5.Cu")
		(net 857)
	)
	(segment
		(start 76.25 113.9)
		(end 76.35 114)
		(width 0.1)
		(layer "In5.Cu")
		(net 857)
	)
	(segment
		(start 134.6 78.780532)
		(end 135.230532 78.15)
		(width 0.1)
		(layer "In5.Cu")
		(net 857)
	)
	(segment
		(start 129.5 91.9)
		(end 134.6 86.8)
		(width 0.1)
		(layer "In5.Cu")
		(net 857)
	)
	(segment
		(start 74.3 111.1)
		(end 80 111.1)
		(width 0.1)
		(layer "F.Cu")
		(net 861)
	)
	(segment
		(start 71.7 111.3)
		(end 74.1 111.3)
		(width 0.1)
		(layer "F.Cu")
		(net 861)
	)
	(segment
		(start 74.1 111.3)
		(end 74.3 111.1)
		(width 0.1)
		(layer "F.Cu")
		(net 861)
	)
	(segment
		(start 80 111.1)
		(end 80.85 111.95)
		(width 0.1)
		(layer "F.Cu")
		(net 861)
	)
	(segment
		(start 89.930532 73.65)
		(end 89.925 73.65)
		(width 0.1)
		(layer "F.Cu")
		(net 861)
	)
	(via
		(at 71.7 111.3)
		(size 0.45)
		(drill 0.1)
		(layers "F.Cu" "B.Cu")
		(net 861)
	)
	(via
		(at 89.925 73.65)
		(size 0.45)
		(drill 0.1)
		(layers "F.Cu" "B.Cu")
		(net 861)
	)
	(via
		(at 80.85 111.95)
		(size 0.45)
		(drill 0.1)
		(layers "F.Cu" "B.Cu")
		(net 861)
	)
	(segment
		(start 80.855532 111.965)
		(end 80.855532 111.955532)
		(width 0.1)
		(layer "B.Cu")
		(net 861)
	)
	(segment
		(start 80.855532 111.955532)
		(end 80.85 111.95)
		(width 0.1)
		(layer "B.Cu")
		(net 861)
	)
	(segment
		(start 69.165685 78.165685)
		(end 79.384315 78.165685)
		(width 0.1)
		(layer "In5.Cu")
		(net 861)
	)
	(segment
		(start 86.400003 72)
		(end 87.250003 72.85)
		(width 0.1)
		(layer "In5.Cu")
		(net 861)
	)
	(segment
		(start 89.125 72.85)
		(end 89.925 73.65)
		(width 0.1)
		(layer "In5.Cu")
		(net 861)
	)
	(segment
		(start 80.5 72.75)
		(end 81.25 72)
		(width 0.1)
		(layer "In5.Cu")
		(net 861)
	)
	(segment
		(start 68.8 85.565686)
		(end 68.8 78.53137)
		(width 0.1)
		(layer "In5.Cu")
		(net 861)
	)
	(segment
		(start 68.4 91.2)
		(end 68.4 85.965686)
		(width 0.1)
		(layer "In5.Cu")
		(net 861)
	)
	(segment
		(start 68.999999 110.499999)
		(end 69 91.8)
		(width 0.1)
		(layer "In5.Cu")
		(net 861)
	)
	(segment
		(start 81.25 72)
		(end 86.400003 72)
		(width 0.1)
		(layer "In5.Cu")
		(net 861)
	)
	(segment
		(start 68.999999 110.499999)
		(end 69.8 111.3)
		(width 0.1)
		(layer "In5.Cu")
		(net 861)
	)
	(segment
		(start 68.8 78.53137)
		(end 69.165685 78.165685)
		(width 0.1)
		(layer "In5.Cu")
		(net 861)
	)
	(segment
		(start 87.250003 72.85)
		(end 89.125 72.85)
		(width 0.1)
		(layer "In5.Cu")
		(net 861)
	)
	(segment
		(start 80.5 77.05)
		(end 80.5 72.75)
		(width 0.1)
		(layer "In5.Cu")
		(net 861)
	)
	(segment
		(start 69.8 111.3)
		(end 71.7 111.3)
		(width 0.1)
		(layer "In5.Cu")
		(net 861)
	)
	(segment
		(start 69 91.8)
		(end 68.4 91.2)
		(width 0.1)
		(layer "In5.Cu")
		(net 861)
	)
	(segment
		(start 79.384315 78.165685)
		(end 80.5 77.05)
		(width 0.1)
		(layer "In5.Cu")
		(net 861)
	)
	(segment
		(start 68.4 85.965686)
		(end 68.8 85.565686)
		(width 0.1)
		(layer "In5.Cu")
		(net 861)
	)
	(segment
		(start 101.2 75.6)
		(end 100.9 75.3)
		(width 0.1)
		(layer "F.Cu")
		(net 866)
	)
	(segment
		(start 100.7 74.80231)
		(end 100.9 75.00231)
		(width 0.1)
		(layer "F.Cu")
		(net 866)
	)
	(segment
		(start 94.6 74.2)
		(end 100.1 74.2)
		(width 0.1)
		(layer "F.Cu")
		(net 866)
	)
	(segment
		(start 109.8 78.4)
		(end 109.8 77.8)
		(width 0.1)
		(layer "F.Cu")
		(net 866)
	)
	(segment
		(start 109.2 77.2)
		(end 108 77.2)
		(width 0.1)
		(layer "F.Cu")
		(net 866)
	)
	(segment
		(start 90.4 74.1)
		(end 90.4 73.25)
		(width 0.1)
		(layer "F.Cu")
		(net 866)
	)
	(segment
		(start 100.7 74.8)
		(end 100.1 74.2)
		(width 0.1)
		(layer "F.Cu")
		(net 866)
	)
	(segment
		(start 107.8 75.9)
		(end 107.5 75.6)
		(width 0.1)
		(layer "F.Cu")
		(net 866)
	)
	(segment
		(start 94.2 74.6)
		(end 94.2 75.3)
		(width 0.1)
		(layer "F.Cu")
		(net 866)
	)
	(segment
		(start 100.7 74.80231)
		(end 100.7 74.8)
		(width 0.1)
		(layer "F.Cu")
		(net 866)
	)
	(segment
		(start 107.5 75.6)
		(end 101.2 75.6)
		(width 0.1)
		(layer "F.Cu")
		(net 866)
	)
	(segment
		(start 107.8 77)
		(end 107.8 75.9)
		(width 0.1)
		(layer "F.Cu")
		(net 866)
	)
	(segment
		(start 110.380532 78.7)
		(end 110.1 78.7)
		(width 0.1)
		(layer "F.Cu")
		(net 866)
	)
	(segment
		(start 94.2 74.6)
		(end 94.6 74.2)
		(width 0.1)
		(layer "F.Cu")
		(net 866)
	)
	(segment
		(start 109.8 77.8)
		(end 109.2 77.2)
		(width 0.1)
		(layer "F.Cu")
		(net 866)
	)
	(segment
		(start 108 77.2)
		(end 107.8 77)
		(width 0.1)
		(layer "F.Cu")
		(net 866)
	)
	(segment
		(start 90.9 74.6)
		(end 90.4 74.1)
		(width 0.1)
		(layer "F.Cu")
		(net 866)
	)
	(segment
		(start 94.2 75.3)
		(end 93.9 75.6)
		(width 0.1)
		(layer "F.Cu")
		(net 866)
	)
	(segment
		(start 93.9 75.6)
		(end 92.5 75.6)
		(width 0.1)
		(layer "F.Cu")
		(net 866)
	)
	(segment
		(start 92.4 75.5)
		(end 92.4 74.9)
		(width 0.1)
		(layer "F.Cu")
		(net 866)
	)
	(segment
		(start 110.1 78.7)
		(end 109.8 78.4)
		(width 0.1)
		(layer "F.Cu")
		(net 866)
	)
	(segment
		(start 92.4 74.9)
		(end 92.1 74.6)
		(width 0.1)
		(layer "F.Cu")
		(net 866)
	)
	(segment
		(start 92.1 74.6)
		(end 90.9 74.6)
		(width 0.1)
		(layer "F.Cu")
		(net 866)
	)
	(segment
		(start 92.5 75.6)
		(end 92.4 75.5)
		(width 0.1)
		(layer "F.Cu")
		(net 866)
	)
	(segment
		(start 100.9 75.3)
		(end 100.9 75.00231)
		(width 0.1)
		(layer "F.Cu")
		(net 866)
	)
	(segment
		(start 111.330532 79.65)
		(end 110.380532 78.7)
		(width 0.1)
		(layer "F.Cu")
		(net 866)
	)
	(via
		(at 90.4 73.25)
		(size 0.45)
		(drill 0.1)
		(layers "F.Cu" "B.Cu")
		(net 866)
	)
	(via
		(at 79.585532 108.155)
		(size 0.45)
		(drill 0.1)
		(layers "F.Cu" "B.Cu")
		(net 866)
	)
	(segment
		(start 81.3 79.275738)
		(end 86.375738 74.2)
		(width 0.1)
		(layer "In7.Cu")
		(net 866)
	)
	(segment
		(start 86.375738 74.2)
		(end 90.1 74.2)
		(width 0.1)
		(layer "In7.Cu")
		(net 866)
	)
	(segment
		(start 80.575736 83.2)
		(end 81 83.2)
		(width 0.1)
		(layer "In7.Cu")
		(net 866)
	)
	(segment
		(start 81 83.2)
		(end 81.3 82.9)
		(width 0.1)
		(layer "In7.Cu")
		(net 866)
	)
	(segment
		(start 78.9 84.875736)
		(end 80.575736 83.2)
		(width 0.1)
		(layer "In7.Cu")
		(net 866)
	)
	(segment
		(start 90.4 73.9)
		(end 90.4 73.25)
		(width 0.1)
		(layer "In7.Cu")
		(net 866)
	)
	(segment
		(start 79.585532 108.155)
		(end 79.585532 107.785532)
		(width 0.1)
		(layer "In7.Cu")
		(net 866)
	)
	(segment
		(start 90.1 74.2)
		(end 90.4 73.9)
		(width 0.1)
		(layer "In7.Cu")
		(net 866)
	)
	(segment
		(start 78.9 107.1)
		(end 78.9 84.875736)
		(width 0.1)
		(layer "In7.Cu")
		(net 866)
	)
	(segment
		(start 81.3 82.9)
		(end 81.3 79.275738)
		(width 0.1)
		(layer "In7.Cu")
		(net 866)
	)
	(segment
		(start 79.585532 107.785532)
		(end 78.9 107.1)
		(width 0.1)
		(layer "In7.Cu")
		(net 866)
	)
	(segment
		(start 162.875 66.74)
		(end 164.365 65.25)
		(width 0.1)
		(layer "B.Cu")
		(net 868)
	)
	(segment
		(start 161.58 66.74)
		(end 162.875 66.74)
		(width 0.1)
		(layer "B.Cu")
		(net 868)
	)
	(segment
		(start 164.15 64.6)
		(end 165.014 64.6)
		(width 0.1)
		(layer "B.Cu")
		(net 869)
	)
	(segment
		(start 161.58 66.24)
		(end 162.51 66.24)
		(width 0.1)
		(layer "B.Cu")
		(net 869)
	)
	(segment
		(start 165.014 64.6)
		(end 165.634 63.98)
		(width 0.1)
		(layer "B.Cu")
		(net 869)
	)
	(segment
		(start 162.51 66.24)
		(end 164.15 64.6)
		(width 0.1)
		(layer "B.Cu")
		(net 869)
	)
	(segment
		(start 161.99 63.201468)
		(end 161.99 63.28)
		(width 0.1)
		(layer "F.Cu")
		(net 870)
	)
	(segment
		(start 161.891468 63.3)
		(end 161.99 63.201468)
		(width 0.1)
		(layer "F.Cu")
		(net 870)
	)
	(segment
		(start 163.35 62.35)
		(end 163.35 61.55)
		(width 0.1)
		(layer "F.Cu")
		(net 870)
	)
	(segment
		(start 162.42 63.28)
		(end 163.35 62.35)
		(width 0.1)
		(layer "F.Cu")
		(net 870)
	)
	(segment
		(start 161.99 63.28)
		(end 162.42 63.28)
		(width 0.1)
		(layer "F.Cu")
		(net 870)
	)
	(segment
		(start 160.95 63.3)
		(end 161.891468 63.3)
		(width 0.1)
		(layer "F.Cu")
		(net 870)
	)
	(via
		(at 163.35 61.55)
		(size 0.45)
		(drill 0.1)
		(layers "F.Cu" "B.Cu")
		(net 870)
	)
	(segment
		(start 163.35 62.45)
		(end 163.35 61.55)
		(width 0.1)
		(layer "B.Cu")
		(net 870)
	)
	(segment
		(start 164.365 62.71)
		(end 163.61 62.71)
		(width 0.1)
		(layer "B.Cu")
		(net 870)
	)
	(segment
		(start 163.61 62.71)
		(end 163.35 62.45)
		(width 0.1)
		(layer "B.Cu")
		(net 870)
	)
	(segment
		(start 164.913 67.24)
		(end 165.634 66.519)
		(width 0.1)
		(layer "B.Cu")
		(net 871)
	)
	(segment
		(start 161.58 67.24)
		(end 164.913 67.24)
		(width 0.1)
		(layer "B.Cu")
		(net 871)
	)
	(segment
		(start 164.31 67.734)
		(end 164.365 67.789)
		(width 0.1)
		(layer "B.Cu")
		(net 872)
	)
	(segment
		(start 161.58 67.734)
		(end 164.31 67.734)
		(width 0.1)
		(layer "B.Cu")
		(net 872)
	)
	(segment
		(start 119.4 72.9)
		(end 120.580532 72.9)
		(width 0.1)
		(layer "F.Cu")
		(net 875)
	)
	(segment
		(start 121.330532 72.15)
		(end 120.580532 72.9)
		(width 0.1)
		(layer "F.Cu")
		(net 875)
	)
	(segment
		(start 119.4 72.9)
		(end 118.9 72.4)
		(width 0.1)
		(layer "F.Cu")
		(net 875)
	)
	(via
		(at 118.9 72.4)
		(size 0.45)
		(drill 0.1)
		(layers "F.Cu" "B.Cu")
		(net 875)
	)
	(segment
		(start 119.82 72.8)
		(end 120.51 72.11)
		(width 0.1)
		(layer "B.Cu")
		(net 875)
	)
	(segment
		(start 118.9 72.4)
		(end 119.3 72.8)
		(width 0.1)
		(layer "B.Cu")
		(net 875)
	)
	(segment
		(start 119.3 72.8)
		(end 119.82 72.8)
		(width 0.1)
		(layer "B.Cu")
		(net 875)
	)
	(segment
		(start 149.1 92)
		(end 145 92)
		(width 0.1)
		(layer "F.Cu")
		(net 878)
	)
	(segment
		(start 141.1 87.9)
		(end 140.430532 87.230532)
		(width 0.1)
		(layer "F.Cu")
		(net 878)
	)
	(segment
		(start 144.7 91.7)
		(end 144.7 90.4)
		(width 0.1)
		(layer "F.Cu")
		(net 878)
	)
	(segment
		(start 146 90)
		(end 146.5 89.5)
		(width 0.1)
		(layer "F.Cu")
		(net 878)
	)
	(segment
		(start 149.7 92.8)
		(end 149.7 92.6)
		(width 0.1)
		(layer "F.Cu")
		(net 878)
	)
	(segment
		(start 146.5 89)
		(end 145.4 87.9)
		(width 0.1)
		(layer "F.Cu")
		(net 878)
	)
	(segment
		(start 151.8 98.4)
		(end 151 98.4)
		(width 0.1)
		(layer "F.Cu")
		(net 878)
	)
	(segment
		(start 145.4 87.9)
		(end 141.1 87.9)
		(width 0.1)
		(layer "F.Cu")
		(net 878)
	)
	(segment
		(start 140.430532 87.230532)
		(end 140.430532 85.65)
		(width 0.1)
		(layer "F.Cu")
		(net 878)
	)
	(segment
		(start 145 92)
		(end 144.7 91.7)
		(width 0.1)
		(layer "F.Cu")
		(net 878)
	)
	(segment
		(start 149.7 92.6)
		(end 149.1 92)
		(width 0.1)
		(layer "F.Cu")
		(net 878)
	)
	(segment
		(start 145.1 90)
		(end 146 90)
		(width 0.1)
		(layer "F.Cu")
		(net 878)
	)
	(segment
		(start 146.5 89.5)
		(end 146.5 89)
		(width 0.1)
		(layer "F.Cu")
		(net 878)
	)
	(segment
		(start 144.7 90.4)
		(end 145.1 90)
		(width 0.1)
		(layer "F.Cu")
		(net 878)
	)
	(via
		(at 151 98.4)
		(size 0.45)
		(drill 0.1)
		(layers "F.Cu" "B.Cu")
		(net 878)
	)
	(via
		(at 149.7 92.8)
		(size 0.45)
		(drill 0.1)
		(layers "F.Cu" "B.Cu")
		(net 878)
	)
	(segment
		(start 149.7 92.8)
		(end 149.7 97.4)
		(width 0.1)
		(layer "In7.Cu")
		(net 878)
	)
	(segment
		(start 150.7 98.4)
		(end 151 98.4)
		(width 0.1)
		(layer "In7.Cu")
		(net 878)
	)
	(segment
		(start 149.7 97.4)
		(end 150.7 98.4)
		(width 0.1)
		(layer "In7.Cu")
		(net 878)
	)
	(segment
		(start 179.525 141.06)
		(end 179.525 140.465532)
		(width 0.2)
		(layer "F.Cu")
		(net 879)
	)
	(segment
		(start 179.525 140.465532)
		(end 178.989468 139.93)
		(width 0.2)
		(layer "F.Cu")
		(net 879)
	)
	(segment
		(start 183.05 141.06)
		(end 183.05 140.2)
		(width 0.2)
		(layer "F.Cu")
		(net 880)
	)
	(segment
		(start 182.475 141.06)
		(end 183.05 141.06)
		(width 0.2)
		(layer "F.Cu")
		(net 880)
	)
	(segment
		(start 183.05 140.2)
		(end 183.02 140.2)
		(width 0.2)
		(layer "F.Cu")
		(net 880)
	)
	(segment
		(start 182.77 139.95)
		(end 183.05 140.2)
		(width 0.2)
		(layer "F.Cu")
		(net 880)
	)
	(via
		(at 176.33 147.42)
		(size 0.45)
		(drill 0.1)
		(layers "F.Cu" "B.Cu")
		(net 880)
	)
	(via
		(at 183.05 141.06)
		(size 0.45)
		(drill 0.1)
		(layers "F.Cu" "B.Cu")
		(remove_unused_layers yes)
		(keep_end_layers yes)
		(zone_layer_connections)
		(net 880)
	)
	(segment
		(start 183.05 141.06)
		(end 183.05 142.8)
		(width 0.2)
		(layer "In5.Cu")
		(net 880)
	)
	(segment
		(start 183.05 142.8)
		(end 178.43 147.42)
		(width 0.2)
		(layer "In5.Cu")
		(net 880)
	)
	(segment
		(start 178.43 147.42)
		(end 176.33 147.42)
		(width 0.2)
		(layer "In5.Cu")
		(net 880)
	)
	(segment
		(start 211.45 79.35)
		(end 211.45 78.85)
		(width 0.1)
		(layer "F.Cu")
		(net 881)
	)
	(segment
		(start 211.45 78.85)
		(end 211.5 78.8)
		(width 0.1)
		(layer "F.Cu")
		(net 881)
	)
	(segment
		(start 211.5 78.8)
		(end 212.7 78.8)
		(width 0.1)
		(layer "F.Cu")
		(net 881)
	)
	(via
		(at 212.7 78.8)
		(size 0.45)
		(drill 0.1)
		(layers "F.Cu" "B.Cu")
		(net 881)
	)
	(segment
		(start 213.08 75.77)
		(end 213.148 75.702)
		(width 0.1)
		(layer "B.Cu")
		(net 881)
	)
	(segment
		(start 213.146 78.354)
		(end 212.7 78.8)
		(width 0.1)
		(layer "B.Cu")
		(net 881)
	)
	(segment
		(start 213.146 75.704)
		(end 213.148 75.702)
		(width 0.1)
		(layer "B.Cu")
		(net 881)
	)
	(segment
		(start 213.146 78.007)
		(end 213.146 75.704)
		(width 0.1)
		(layer "B.Cu")
		(net 881)
	)
	(segment
		(start 213.146 78.007)
		(end 213.146 78.354)
		(width 0.1)
		(layer "B.Cu")
		(net 881)
	)
	(segment
		(start 212.048 75.77)
		(end 213.08 75.77)
		(width 0.1)
		(layer "B.Cu")
		(net 881)
	)
	(segment
		(start 142.59 132.92)
		(end 142.61 132.94)
		(width 0.2)
		(layer "F.Cu")
		(net 883)
	)
	(segment
		(start 137.92 132.95)
		(end 142.6 132.95)
		(width 0.2)
		(layer "F.Cu")
		(net 883)
	)
	(segment
		(start 141.94 131.15)
		(end 142.59 131.8)
		(width 0.2)
		(layer "F.Cu")
		(net 883)
	)
	(segment
		(start 142.6 132.95)
		(end 142.61 132.94)
		(width 0.2)
		(layer "F.Cu")
		(net 883)
	)
	(segment
		(start 141.542 131.15)
		(end 141.94 131.15)
		(width 0.2)
		(layer "F.Cu")
		(net 883)
	)
	(segment
		(start 142.59 131.8)
		(end 142.59 132.92)
		(width 0.2)
		(layer "F.Cu")
		(net 883)
	)
	(segment
		(start 95.228 64.528)
		(end 94.8 64.1)
		(width 0.2)
		(layer "B.Cu")
		(net 884)
	)
	(segment
		(start 90.9 64.1)
		(end 90.5 64.5)
		(width 0.2)
		(layer "B.Cu")
		(net 884)
	)
	(segment
		(start 94.8 64.1)
		(end 90.9 64.1)
		(width 0.2)
		(layer "B.Cu")
		(net 884)
	)
	(segment
		(start 90.5 64.5)
		(end 90.5 66.099)
		(width 0.2)
		(layer "B.Cu")
		(net 884)
	)
	(segment
		(start 95.228 65.5)
		(end 95.228 64.528)
		(width 0.2)
		(layer "B.Cu")
		(net 884)
	)
	(segment
		(start 139.222 135.038)
		(end 139.21 135.05)
		(width 0.2)
		(layer "F.Cu")
		(net 885)
	)
	(segment
		(start 139.222 133.45)
		(end 139.222 135.038)
		(width 0.2)
		(layer "F.Cu")
		(net 885)
	)
	(segment
		(start 141.58 135.05)
		(end 141.58 134.138)
		(width 0.2)
		(layer "F.Cu")
		(net 886)
	)
	(segment
		(start 141.542 133.46)
		(end 141.542 134.1)
		(width 0.2)
		(layer "F.Cu")
		(net 886)
	)
	(segment
		(start 141.58 134.138)
		(end 141.542 134.1)
		(width 0.2)
		(layer "F.Cu")
		(net 886)
	)
	(segment
		(start 89.52 65.5)
		(end 88.77 66.25)
		(width 0.1)
		(layer "F.Cu")
		(net 887)
	)
	(segment
		(start 88.77 66.25)
		(end 86.25 66.25)
		(width 0.1)
		(layer "F.Cu")
		(net 887)
	)
	(segment
		(start 84.75 60.338)
		(end 84.162 59.75)
		(width 0.1)
		(layer "F.Cu")
		(net 887)
	)
	(segment
		(start 84.75 64.75)
		(end 84.75 60.338)
		(width 0.1)
		(layer "F.Cu")
		(net 887)
	)
	(segment
		(start 86.25 66.25)
		(end 84.75 64.75)
		(width 0.1)
		(layer "F.Cu")
		(net 887)
	)
	(segment
		(start 85.3 64.5)
		(end 85.3 59.89)
		(width 0.1)
		(layer "F.Cu")
		(net 888)
	)
	(segment
		(start 84.36 58.95)
		(end 84.36 57.708)
		(width 0.1)
		(layer "F.Cu")
		(net 888)
	)
	(segment
		(start 86.25 65.45)
		(end 85.3 64.5)
		(width 0.1)
		(layer "F.Cu")
		(net 888)
	)
	(segment
		(start 87.52 65.45)
		(end 86.25 65.45)
		(width 0.1)
		(layer "F.Cu")
		(net 888)
	)
	(segment
		(start 85.3 59.89)
		(end 84.36 58.95)
		(width 0.1)
		(layer "F.Cu")
		(net 888)
	)
	(segment
		(start 84.36 57.708)
		(end 84.152 57.5)
		(width 0.1)
		(layer "F.Cu")
		(net 888)
	)
	(segment
		(start 215.645 100.125)
		(end 215.645 99.655)
		(width 0.1)
		(layer "F.Cu")
		(net 889)
	)
	(segment
		(start 215.85 98.05)
		(end 215.9 98)
		(width 0.1)
		(layer "F.Cu")
		(net 889)
	)
	(segment
		(start 151.675 103.81)
		(end 150.075 103.81)
		(width 0.1)
		(layer "F.Cu")
		(net 889)
	)
	(segment
		(start 215.85 99.45)
		(end 215.85 98.05)
		(width 0.1)
		(layer "F.Cu")
		(net 889)
	)
	(segment
		(start 215.645 99.655)
		(end 215.85 99.45)
		(width 0.1)
		(layer "F.Cu")
		(net 889)
	)
	(via
		(at 150.075 103.81)
		(size 0.45)
		(drill 0.1)
		(layers "F.Cu" "B.Cu")
		(net 889)
	)
	(via
		(at 215.85 99)
		(size 0.45)
		(drill 0.1)
		(layers "F.Cu" "B.Cu")
		(net 889)
	)
	(segment
		(start 221.2 103.5)
		(end 221.2 100.5)
		(width 0.1)
		(layer "B.Cu")
		(net 889)
	)
	(segment
		(start 225 105.5)
		(end 223.2 105.5)
		(width 0.1)
		(layer "B.Cu")
		(net 889)
	)
	(segment
		(start 226 109.85)
		(end 227.17 109.85)
		(width 0.1)
		(layer "B.Cu")
		(net 889)
	)
	(segment
		(start 223.2 105.5)
		(end 221.2 103.5)
		(width 0.1)
		(layer "B.Cu")
		(net 889)
	)
	(segment
		(start 219.7 99)
		(end 215.85 99)
		(width 0.1)
		(layer "B.Cu")
		(net 889)
	)
	(segment
		(start 227.17 109.85)
		(end 227.2 109.88)
		(width 0.1)
		(layer "B.Cu")
		(net 889)
	)
	(segment
		(start 226 106.5)
		(end 225 105.5)
		(width 0.1)
		(layer "B.Cu")
		(net 889)
	)
	(segment
		(start 221.2 100.5)
		(end 219.7 99)
		(width 0.1)
		(layer "B.Cu")
		(net 889)
	)
	(segment
		(start 226 109.85)
		(end 226 106.5)
		(width 0.1)
		(layer "B.Cu")
		(net 889)
	)
	(segment
		(start 202.2 102)
		(end 206.6 106.4)
		(width 0.1)
		(layer "In7.Cu")
		(net 889)
	)
	(segment
		(start 150.075 103.81)
		(end 152.15 103.81)
		(width 0.1)
		(layer "In7.Cu")
		(net 889)
	)
	(segment
		(start 215.85 103.95)
		(end 215.85 99)
		(width 0.1)
		(layer "In7.Cu")
		(net 889)
	)
	(segment
		(start 153.74 102.22)
		(end 189.78 102.22)
		(width 0.1)
		(layer "In7.Cu")
		(net 889)
	)
	(segment
		(start 198.6 100.6)
		(end 200 102)
		(width 0.1)
		(layer "In7.Cu")
		(net 889)
	)
	(segment
		(start 206.6 106.4)
		(end 213.4 106.4)
		(width 0.1)
		(layer "In7.Cu")
		(net 889)
	)
	(segment
		(start 213.4 106.4)
		(end 215.85 103.95)
		(width 0.1)
		(layer "In7.Cu")
		(net 889)
	)
	(segment
		(start 200 102)
		(end 202.2 102)
		(width 0.1)
		(layer "In7.Cu")
		(net 889)
	)
	(segment
		(start 152.15 103.81)
		(end 153.74 102.22)
		(width 0.1)
		(layer "In7.Cu")
		(net 889)
	)
	(segment
		(start 189.78 102.22)
		(end 191.4 100.6)
		(width 0.1)
		(layer "In7.Cu")
		(net 889)
	)
	(segment
		(start 191.4 100.6)
		(end 198.6 100.6)
		(width 0.1)
		(layer "In7.Cu")
		(net 889)
	)
	(segment
		(start 228.8 107.8)
		(end 225.5 107.8)
		(width 0.1)
		(layer "F.Cu")
		(net 890)
	)
	(segment
		(start 232.376 106.8)
		(end 233.9 106.8)
		(width 0.1)
		(layer "F.Cu")
		(net 890)
	)
	(segment
		(start 231 108.176)
		(end 229.176 108.176)
		(width 0.1)
		(layer "F.Cu")
		(net 890)
	)
	(segment
		(start 229.176 108.176)
		(end 228.8 107.8)
		(width 0.1)
		(layer "F.Cu")
		(net 890)
	)
	(segment
		(start 231 108.176)
		(end 232.376 106.8)
		(width 0.1)
		(layer "F.Cu")
		(net 890)
	)
	(via
		(at 233.9 106.8)
		(size 0.45)
		(drill 0.1)
		(layers "F.Cu" "B.Cu")
		(net 890)
	)
	(via
		(at 225.5 107.8)
		(size 0.45)
		(drill 0.1)
		(layers "F.Cu" "B.Cu")
		(net 890)
	)
	(segment
		(start 234.6 107.8)
		(end 235.214 107.8)
		(width 0.1)
		(layer "B.Cu")
		(net 890)
	)
	(segment
		(start 225.5 107.8)
		(end 225.5 108.548)
		(width 0.1)
		(layer "B.Cu")
		(net 890)
	)
	(segment
		(start 235.214 107.8)
		(end 235.214 106.82)
		(width 0.1)
		(layer "B.Cu")
		(net 890)
	)
	(segment
		(start 235.22 106.814)
		(end 233.914 106.814)
		(width 0.1)
		(layer "B.Cu")
		(net 890)
	)
	(segment
		(start 235.214 106.82)
		(end 235.22 106.814)
		(width 0.1)
		(layer "B.Cu")
		(net 890)
	)
	(segment
		(start 233.7 107.7)
		(end 234.5 107.7)
		(width 0.1)
		(layer "B.Cu")
		(net 890)
	)
	(segment
		(start 234.5 107.7)
		(end 234.6 107.8)
		(width 0.1)
		(layer "B.Cu")
		(net 890)
	)
	(segment
		(start 233.914 106.814)
		(end 233.9 106.8)
		(width 0.1)
		(layer "B.Cu")
		(net 890)
	)
	(via
		(at 161.75 54.5)
		(size 0.45)
		(drill 0.1)
		(layers "F.Cu" "B.Cu")
		(net 891)
	)
	(segment
		(start 160.25 56)
		(end 161.75 54.5)
		(width 0.1)
		(layer "B.Cu")
		(net 891)
	)
	(segment
		(start 160.25 58.75)
		(end 160.25 56)
		(width 0.1)
		(layer "B.Cu")
		(net 891)
	)
	(segment
		(start 160.508 59.78)
		(end 160.508 59.008)
		(width 0.1)
		(layer "B.Cu")
		(net 891)
	)
	(segment
		(start 160.508 59.008)
		(end 160.25 58.75)
		(width 0.1)
		(layer "B.Cu")
		(net 891)
	)
	(segment
		(start 97.5 56.3)
		(end 97.751 56.049)
		(width 0.1)
		(layer "B.Cu")
		(net 892)
	)
	(segment
		(start 98.4 59.75)
		(end 97.65 59.75)
		(width 0.1)
		(layer "B.Cu")
		(net 892)
	)
	(segment
		(start 97.751 56.049)
		(end 99.101 56.049)
		(width 0.1)
		(layer "B.Cu")
		(net 892)
	)
	(segment
		(start 97.5 59.6)
		(end 97.5 56.3)
		(width 0.1)
		(layer "B.Cu")
		(net 892)
	)
	(segment
		(start 97.65 59.75)
		(end 97.5 59.6)
		(width 0.1)
		(layer "B.Cu")
		(net 892)
	)
	(segment
		(start 86.87 146.5915)
		(end 86.570001 146.891499)
		(width 0.2)
		(layer "F.Cu")
		(net 893)
	)
	(segment
		(start 86.87 145.65)
		(end 86.87 146.5915)
		(width 0.2)
		(layer "F.Cu")
		(net 893)
	)
	(segment
		(start 104.9 63.995)
		(end 104.9 64.02)
		(width 0.19)
		(layer "B.Cu")
		(net 894)
	)
	(segment
		(start 104.595 63.69)
		(end 104.9 63.995)
		(width 0.19)
		(layer "B.Cu")
		(net 894)
	)
	(segment
		(start 104.595 60.735)
		(end 104.595 63.69)
		(width 0.19)
		(layer "B.Cu")
		(net 894)
	)
	(segment
		(start 105.09 60.24)
		(end 104.595 60.735)
		(width 0.19)
		(layer "B.Cu")
		(net 894)
	)
	(segment
		(start 105.09 60.175)
		(end 105.09 60.24)
		(width 0.19)
		(layer "B.Cu")
		(net 894)
	)
	(segment
		(start 103.92 63.995)
		(end 103.92 64.02)
		(width 0.19)
		(layer "B.Cu")
		(net 895)
	)
	(segment
		(start 104.225 63.69)
		(end 103.92 63.995)
		(width 0.19)
		(layer "B.Cu")
		(net 895)
	)
	(segment
		(start 104.225 60.665)
		(end 104.225 63.69)
		(width 0.19)
		(layer "B.Cu")
		(net 895)
	)
	(segment
		(start 103.8 60.24)
		(end 104.225 60.665)
		(width 0.19)
		(layer "B.Cu")
		(net 895)
	)
	(segment
		(start 103.8 60.175)
		(end 103.8 60.24)
		(width 0.19)
		(layer "B.Cu")
		(net 895)
	)
	(segment
		(start 183.299 85.799)
		(end 185 87.5)
		(width 0.1)
		(layer "F.Cu")
		(net 896)
	)
	(segment
		(start 178.370468 85.799)
		(end 183.299 85.799)
		(width 0.1)
		(layer "F.Cu")
		(net 896)
	)
	(segment
		(start 183.616054 90.185)
		(end 182.764468 90.185)
		(width 0.1)
		(layer "F.Cu")
		(net 896)
	)
	(segment
		(start 182.764468 90.185)
		(end 182.654468 90.075)
		(width 0.2)
		(layer "F.Cu")
		(net 896)
	)
	(segment
		(start 182.654468 90.075)
		(end 181.64 90.075)
		(width 0.2)
		(layer "F.Cu")
		(net 896)
	)
	(segment
		(start 177.714468 86.455)
		(end 178.370468 85.799)
		(width 0.1)
		(layer "F.Cu")
		(net 896)
	)
	(segment
		(start 185 88.801054)
		(end 183.616054 90.185)
		(width 0.1)
		(layer "F.Cu")
		(net 896)
	)
	(segment
		(start 185 87.5)
		(end 185 88.801054)
		(width 0.1)
		(layer "F.Cu")
		(net 896)
	)
	(segment
		(start 88.2805 149.18)
		(end 88.171001 149.289499)
		(width 0.22)
		(layer "F.Cu")
		(net 897)
	)
	(segment
		(start 89.55 149.18)
		(end 88.2805 149.18)
		(width 0.22)
		(layer "F.Cu")
		(net 897)
	)
	(segment
		(start 92.5 149.18)
		(end 91.53 149.18)
		(width 0.19)
		(layer "F.Cu")
		(net 898)
	)
	(segment
		(start 91.53 149.18)
		(end 91.5 149.15)
		(width 0.19)
		(layer "F.Cu")
		(net 898)
	)
	(segment
		(start 91.47 149.18)
		(end 91.5 149.15)
		(width 0.19)
		(layer "F.Cu")
		(net 898)
	)
	(segment
		(start 90.51 149.18)
		(end 91.47 149.18)
		(width 0.19)
		(layer "F.Cu")
		(net 898)
	)
	(segment
		(start 181.64 91.425)
		(end 182.144468 91.425)
		(width 0.2)
		(layer "F.Cu")
		(net 900)
	)
	(segment
		(start 182.144468 91.425)
		(end 182.764468 92.045)
		(width 0.2)
		(layer "F.Cu")
		(net 900)
	)
	(segment
		(start 178.675 87.425)
		(end 178.68 87.42)
		(width 0.15)
		(layer "F.Cu")
		(net 901)
	)
	(segment
		(start 178.675 88.51)
		(end 178.675 87.425)
		(width 0.15)
		(layer "F.Cu")
		(net 901)
	)
	(segment
		(start 178.225 88.51)
		(end 178.225 87.925)
		(width 0.15)
		(layer "F.Cu")
		(net 902)
	)
	(segment
		(start 178.225 87.925)
		(end 177.72 87.42)
		(width 0.15)
		(layer "F.Cu")
		(net 902)
	)
	(segment
		(start 164.044468 96.225)
		(end 163.075 96.225)
		(width 0.1)
		(layer "F.Cu")
		(net 903)
	)
	(segment
		(start 181.6 88.4)
		(end 181.6 88.206979)
		(width 0.2)
		(layer "F.Cu")
		(net 903)
	)
	(segment
		(start 181.49 88.51)
		(end 181.6325 88.3675)
		(width 0.2)
		(layer "F.Cu")
		(net 903)
	)
	(segment
		(start 162.9 96.4)
		(end 162.9 97.1)
		(width 0.1)
		(layer "F.Cu")
		(net 903)
	)
	(segment
		(start 181.175 88.51)
		(end 181.49 88.51)
		(width 0.2)
		(layer "F.Cu")
		(net 903)
	)
	(segment
		(start 163.075 96.225)
		(end 162.9 96.4)
		(width 0.1)
		(layer "F.Cu")
		(net 903)
	)
	(segment
		(start 162.9 97.1)
		(end 162.694468 97.305532)
		(width 0.1)
		(layer "F.Cu")
		(net 903)
	)
	(segment
		(start 182.451979 87.355)
		(end 182.764468 87.355)
		(width 0.2)
		(layer "F.Cu")
		(net 903)
	)
	(segment
		(start 181.6325 88.3675)
		(end 181.6 88.4)
		(width 0.2)
		(layer "F.Cu")
		(net 903)
	)
	(segment
		(start 181.6325 88.25)
		(end 181.6325 88.3675)
		(width 0.2)
		(layer "F.Cu")
		(net 903)
	)
	(segment
		(start 162.694468 97.305532)
		(end 162.694468 97.665)
		(width 0.1)
		(layer "F.Cu")
		(net 903)
	)
	(segment
		(start 181.6 88.206979)
		(end 182.451979 87.355)
		(width 0.2)
		(layer "F.Cu")
		(net 903)
	)
	(via
		(at 175 93.73)
		(size 0.45)
		(drill 0.1)
		(layers "F.Cu" "B.Cu")
		(remove_unused_layers yes)
		(keep_end_layers yes)
		(zone_layer_connections)
		(net 903)
	)
	(via
		(at 181.6325 88.25)
		(size 0.45)
		(drill 0.1)
		(layers "F.Cu" "B.Cu")
		(remove_unused_layers yes)
		(keep_end_layers yes)
		(zone_layer_connections)
		(net 903)
	)
	(segment
		(start 175.05 93.78)
		(end 175 93.73)
		(width 0.1)
		(layer "In2.Cu")
		(net 903)
	)
	(segment
		(start 181.6325 90.1175)
		(end 177.97 93.78)
		(width 0.1)
		(layer "In2.Cu")
		(net 903)
	)
	(segment
		(start 181.6325 88.25)
		(end 181.6325 90.1175)
		(width 0.1)
		(layer "In2.Cu")
		(net 903)
	)
	(segment
		(start 177.97 93.78)
		(end 175.05 93.78)
		(width 0.1)
		(layer "In2.Cu")
		(net 903)
	)
	(segment
		(start 162.41 76.21)
		(end 162.6 76.4)
		(width 0.1)
		(layer "F.Cu")
		(net 904)
	)
	(segment
		(start 161.729468 77.63)
		(end 161.729468 77.570532)
		(width 0.1)
		(layer "F.Cu")
		(net 904)
	)
	(segment
		(start 182 57.16)
		(end 182 58)
		(width 0.1)
		(layer "F.Cu")
		(net 904)
	)
	(segment
		(start 161.729468 76.21)
		(end 162.41 76.21)
		(width 0.1)
		(layer "F.Cu")
		(net 904)
	)
	(segment
		(start 161.729468 77.570532)
		(end 162.6 76.7)
		(width 0.1)
		(layer "F.Cu")
		(net 904)
	)
	(segment
		(start 162.6 76.7)
		(end 162.6 76.4)
		(width 0.1)
		(layer "F.Cu")
		(net 904)
	)
	(via
		(at 159.3 75.2)
		(size 0.45)
		(drill 0.1)
		(layers "F.Cu" "B.Cu")
		(remove_unused_layers yes)
		(keep_end_layers yes)
		(free yes)
		(zone_layer_connections)
		(net 904)
	)
	(via
		(at 161.4 76.46)
		(size 0.45)
		(drill 0.1)
		(layers "F.Cu" "B.Cu")
		(remove_unused_layers yes)
		(keep_end_layers yes)
		(free yes)
		(zone_layer_connections)
		(net 904)
	)
	(via
		(at 161.3 75.2)
		(size 0.45)
		(drill 0.1)
		(layers "F.Cu" "B.Cu")
		(remove_unused_layers yes)
		(keep_end_layers yes)
		(free yes)
		(zone_layer_connections)
		(net 904)
	)
	(via
		(at 158.8375 76.46)
		(size 0.45)
		(drill 0.1)
		(layers "F.Cu" "B.Cu")
		(remove_unused_layers yes)
		(keep_end_layers yes)
		(free yes)
		(zone_layer_connections)
		(net 904)
	)
	(via
		(at 159.35 76.46)
		(size 0.45)
		(drill 0.1)
		(layers "F.Cu" "B.Cu")
		(remove_unused_layers yes)
		(keep_end_layers yes)
		(free yes)
		(zone_layer_connections)
		(net 904)
	)
	(via
		(at 160.3 75.2)
		(size 0.45)
		(drill 0.1)
		(layers "F.Cu" "B.Cu")
		(remove_unused_layers yes)
		(keep_end_layers yes)
		(free yes)
		(zone_layer_connections)
		(net 904)
	)
	(via
		(at 157.8125 76.46)
		(size 0.45)
		(drill 0.1)
		(layers "F.Cu" "B.Cu")
		(remove_unused_layers yes)
		(keep_end_layers yes)
		(free yes)
		(zone_layer_connections)
		(net 904)
	)
	(via
		(at 160.375 76.46)
		(size 0.45)
		(drill 0.1)
		(layers "F.Cu" "B.Cu")
		(remove_unused_layers yes)
		(keep_end_layers yes)
		(free yes)
		(zone_layer_connections)
		(net 904)
	)
	(via
		(at 160.8 75.2)
		(size 0.45)
		(drill 0.1)
		(layers "F.Cu" "B.Cu")
		(remove_unused_layers yes)
		(keep_end_layers yes)
		(free yes)
		(zone_layer_connections)
		(net 904)
	)
	(via
		(at 158.3 75.2)
		(size 0.45)
		(drill 0.1)
		(layers "F.Cu" "B.Cu")
		(remove_unused_layers yes)
		(keep_end_layers yes)
		(free yes)
		(zone_layer_connections)
		(net 904)
	)
	(via
		(at 160.8875 76.46)
		(size 0.45)
		(drill 0.1)
		(layers "F.Cu" "B.Cu")
		(remove_unused_layers yes)
		(keep_end_layers yes)
		(free yes)
		(zone_layer_connections)
		(net 904)
	)
	(via
		(at 159.8 75.2)
		(size 0.45)
		(drill 0.1)
		(layers "F.Cu" "B.Cu")
		(remove_unused_layers yes)
		(keep_end_layers yes)
		(free yes)
		(zone_layer_connections)
		(net 904)
	)
	(via
		(at 157.8 75.2)
		(size 0.45)
		(drill 0.1)
		(layers "F.Cu" "B.Cu")
		(remove_unused_layers yes)
		(keep_end_layers yes)
		(free yes)
		(zone_layer_connections)
		(net 904)
	)
	(via
		(at 157.3 75.2)
		(size 0.45)
		(drill 0.1)
		(layers "F.Cu" "B.Cu")
		(remove_unused_layers yes)
		(keep_end_layers yes)
		(free yes)
		(zone_layer_connections)
		(net 904)
	)
	(via
		(at 158.325 76.46)
		(size 0.45)
		(drill 0.1)
		(layers "F.Cu" "B.Cu")
		(remove_unused_layers yes)
		(keep_end_layers yes)
		(free yes)
		(zone_layer_connections)
		(net 904)
	)
	(via
		(at 157.3 76.46)
		(size 0.45)
		(drill 0.1)
		(layers "F.Cu" "B.Cu")
		(remove_unused_layers yes)
		(keep_end_layers yes)
		(free yes)
		(zone_layer_connections)
		(net 904)
	)
	(via
		(at 158.8 75.2)
		(size 0.45)
		(drill 0.1)
		(layers "F.Cu" "B.Cu")
		(remove_unused_layers yes)
		(keep_end_layers yes)
		(free yes)
		(zone_layer_connections)
		(net 904)
	)
	(via
		(at 159.8625 76.46)
		(size 0.45)
		(drill 0.1)
		(layers "F.Cu" "B.Cu")
		(remove_unused_layers yes)
		(keep_end_layers yes)
		(free yes)
		(zone_layer_connections)
		(net 904)
	)
	(via
		(at 182 58)
		(size 0.45)
		(drill 0.1)
		(layers "F.Cu" "B.Cu")
		(net 904)
	)
	(segment
		(start 181.573 73.5)
		(end 177.25 73.5)
		(width 2)
		(layer "B.Cu")
		(net 904)
	)
	(segment
		(start 182 59.9)
		(end 182.3 60.2)
		(width 0.1)
		(layer "B.Cu")
		(net 904)
	)
	(segment
		(start 183.08 75.007)
		(end 181.573 73.5)
		(width 2)
		(layer "B.Cu")
		(net 904)
	)
	(segment
		(start 181.573 71.627)
		(end 181.573 73.5)
		(width 0.1)
		(layer "B.Cu")
		(net 904)
	)
	(segment
		(start 177 87.4)
		(end 177 84.75)
		(width 0.2)
		(layer "B.Cu")
		(net 904)
	)
	(segment
		(start 176.171 83.921)
		(end 176 83.75)
		(width 2)
		(layer "B.Cu")
		(net 904)
	)
	(segment
		(start 177.89 88.85)
		(end 177.89 87.964)
		(width 0.2)
		(layer "B.Cu")
		(net 904)
	)
	(segment
		(start 178.15 87.704)
		(end 177.304 87.704)
		(width 0.2)
		(layer "B.Cu")
		(net 904)
	)
	(segment
		(start 182.909 83.921)
		(end 176.171 83.921)
		(width 2)
		(layer "B.Cu")
		(net 904)
	)
	(segment
		(start 177.89 87.964)
		(end 178.15 87.704)
		(width 0.2)
		(layer "B.Cu")
		(net 904)
	)
	(segment
		(start 177 84.75)
		(end 176.171 83.921)
		(width 0.2)
		(layer "B.Cu")
		(net 904)
	)
	(segment
		(start 183.08 83.75)
		(end 182.909 83.921)
		(width 2)
		(layer "B.Cu")
		(net 904)
	)
	(segment
		(start 182.3 70.9)
		(end 181.573 71.627)
		(width 0.1)
		(layer "B.Cu")
		(net 904)
	)
	(segment
		(start 183.14 58)
		(end 182 58)
		(width 0.1)
		(layer "B.Cu")
		(net 904)
	)
	(segment
		(start 177.304 87.704)
		(end 177 87.4)
		(width 0.2)
		(layer "B.Cu")
		(net 904)
	)
	(segment
		(start 182 57.98)
		(end 182 59.9)
		(width 0.1)
		(layer "B.Cu")
		(net 904)
	)
	(segment
		(start 182.3 60.2)
		(end 182.3 70.9)
		(width 0.1)
		(layer "B.Cu")
		(net 904)
	)
	(segment
		(start 181.64 70.075)
		(end 182.835 70.075)
		(width 0.15)
		(layer "F.Cu")
		(net 905)
	)
	(segment
		(start 184.305468 69.435586)
		(end 184.305468 67.8)
		(width 0.15)
		(layer "F.Cu")
		(net 905)
	)
	(segment
		(start 183.290468 65.990468)
		(end 182.819 65.519)
		(width 0.15)
		(layer "F.Cu")
		(net 905)
	)
	(segment
		(start 182.84 70.07)
		(end 183.671054 70.07)
		(width 0.15)
		(layer "F.Cu")
		(net 905)
	)
	(segment
		(start 179.040468 65.519)
		(end 179.001 65.519)
		(width 0.15)
		(layer "F.Cu")
		(net 905)
	)
	(segment
		(start 183.671054 70.07)
		(end 184.305468 69.435586)
		(width 0.15)
		(layer "F.Cu")
		(net 905)
	)
	(segment
		(start 182.835 70.075)
		(end 182.84 70.07)
		(width 0.15)
		(layer "F.Cu")
		(net 905)
	)
	(segment
		(start 179.040468 65.519)
		(end 179.009468 65.55)
		(width 0.15)
		(layer "F.Cu")
		(net 905)
	)
	(segment
		(start 183.290468 66.785)
		(end 183.290468 65.990468)
		(width 0.15)
		(layer "F.Cu")
		(net 905)
	)
	(segment
		(start 182.819 65.519)
		(end 179.040468 65.519)
		(width 0.15)
		(layer "F.Cu")
		(net 905)
	)
	(segment
		(start 184.305468 67.8)
		(end 183.290468 66.785)
		(width 0.15)
		(layer "F.Cu")
		(net 905)
	)
	(segment
		(start 124 84.8)
		(end 123.8 85)
		(width 0.1)
		(layer "F.Cu")
		(net 906)
	)
	(segment
		(start 123.8 85)
		(end 123.8 86)
		(width 0.1)
		(layer "F.Cu")
		(net 906)
	)
	(segment
		(start 124 83.7)
		(end 124 84.8)
		(width 0.1)
		(layer "F.Cu")
		(net 906)
	)
	(segment
		(start 131.55 88.8)
		(end 133.53137 88.8)
		(width 0.1)
		(layer "F.Cu")
		(net 906)
	)
	(segment
		(start 123.330532 82.65)
		(end 123.330532 83.030532)
		(width 0.1)
		(layer "F.Cu")
		(net 906)
	)
	(segment
		(start 123.330532 83.030532)
		(end 124 83.7)
		(width 0.1)
		(layer "F.Cu")
		(net 906)
	)
	(segment
		(start 124.6 86.8)
		(end 126.8 86.8)
		(width 0.1)
		(layer "F.Cu")
		(net 906)
	)
	(segment
		(start 133.53137 88.8)
		(end 142.73137 98)
		(width 0.1)
		(layer "F.Cu")
		(net 906)
	)
	(segment
		(start 127.35 86.25)
		(end 129 86.25)
		(width 0.1)
		(layer "F.Cu")
		(net 906)
	)
	(segment
		(start 129 86.25)
		(end 131.55 88.8)
		(width 0.1)
		(layer "F.Cu")
		(net 906)
	)
	(segment
		(start 126.8 86.8)
		(end 127.35 86.25)
		(width 0.1)
		(layer "F.Cu")
		(net 906)
	)
	(segment
		(start 123.8 86)
		(end 124.6 86.8)
		(width 0.1)
		(layer "F.Cu")
		(net 906)
	)
	(segment
		(start 142.73137 98)
		(end 151.8 98)
		(width 0.1)
		(layer "F.Cu")
		(net 906)
	)
	(via
		(at 137.730532 82.65)
		(size 0.45)
		(drill 0.1)
		(layers "F.Cu" "B.Cu")
		(net 907)
	)
	(segment
		(start 235.316 121.996)
		(end 235.32 122)
		(width 0.1)
		(layer "B.Cu")
		(net 909)
	)
	(segment
		(start 233.699 121.996)
		(end 235.316 121.996)
		(width 0.1)
		(layer "B.Cu")
		(net 909)
	)
	(segment
		(start 198.7 123.1)
		(end 198.899 122.901)
		(width 0.1)
		(layer "F.Cu")
		(net 910)
	)
	(segment
		(start 198.4 123.1)
		(end 198.7 123.1)
		(width 0.1)
		(layer "F.Cu")
		(net 910)
	)
	(segment
		(start 198.899 122.901)
		(end 199.565 122.901)
		(width 0.1)
		(layer "F.Cu")
		(net 910)
	)
	(via
		(at 198.4 123.1)
		(size 0.45)
		(drill 0.1)
		(layers "F.Cu" "B.Cu")
		(remove_unused_layers yes)
		(keep_end_layers yes)
		(zone_layer_connections)
		(net 910)
	)
	(segment
		(start 198.4 123.1)
		(end 197.1 123.1)
		(width 0.1)
		(layer "B.Cu")
		(net 910)
	)
	(segment
		(start 197.1 123.1)
		(end 197 123)
		(width 0.1)
		(layer "B.Cu")
		(net 910)
	)
	(segment
		(start 199.565 123.7)
		(end 198.5 123.7)
		(width 0.1)
		(layer "F.Cu")
		(net 911)
	)
	(via
		(at 198.5 123.7)
		(size 0.45)
		(drill 0.1)
		(layers "F.Cu" "B.Cu")
		(remove_unused_layers yes)
		(keep_end_layers yes)
		(zone_layer_connections)
		(net 911)
	)
	(via
		(at 231.1 121)
		(size 0.45)
		(drill 0.1)
		(layers "F.Cu" "B.Cu")
		(net 911)
	)
	(via
		(at 234.85 120.65)
		(size 0.45)
		(drill 0.1)
		(layers "F.Cu" "B.Cu")
		(net 911)
	)
	(segment
		(start 234.85 120.95)
		(end 234.754 121.046)
		(width 0.1)
		(layer "B.Cu")
		(net 911)
	)
	(segment
		(start 231.099 121.046)
		(end 231.099 121.001)
		(width 0.1)
		(layer "B.Cu")
		(net 911)
	)
	(segment
		(start 231.099 121.001)
		(end 231.1 121)
		(width 0.1)
		(layer "B.Cu")
		(net 911)
	)
	(segment
		(start 234.754 121.046)
		(end 233.699 121.046)
		(width 0.1)
		(layer "B.Cu")
		(net 911)
	)
	(segment
		(start 198.5 123.7)
		(end 199.3 123.7)
		(width 0.1)
		(layer "B.Cu")
		(net 911)
	)
	(segment
		(start 234.85 120.65)
		(end 234.85 120.95)
		(width 0.1)
		(layer "B.Cu")
		(net 911)
	)
	(segment
		(start 199.7 122.7)
		(end 199.8 122.6)
		(width 0.1)
		(layer "B.Cu")
		(net 911)
	)
	(segment
		(start 199.3 123.7)
		(end 199.7 123.3)
		(width 0.1)
		(layer "B.Cu")
		(net 911)
	)
	(segment
		(start 199.7 123.3)
		(end 199.7 122.7)
		(width 0.1)
		(layer "B.Cu")
		(net 911)
	)
	(segment
		(start 199.6 121.8)
		(end 201.3 120.1)
		(width 0.1)
		(layer "In5.Cu")
		(net 911)
	)
	(segment
		(start 199.1 123.7)
		(end 199.6 123.2)
		(width 0.1)
		(layer "In5.Cu")
		(net 911)
	)
	(segment
		(start 198.5 123.7)
		(end 199.1 123.7)
		(width 0.1)
		(layer "In5.Cu")
		(net 911)
	)
	(segment
		(start 224.8 120.1)
		(end 225.7 121)
		(width 0.1)
		(layer "In5.Cu")
		(net 911)
	)
	(segment
		(start 199.6 123.2)
		(end 199.6 121.8)
		(width 0.1)
		(layer "In5.Cu")
		(net 911)
	)
	(segment
		(start 234.85 120.65)
		(end 234.5 121)
		(width 0.1)
		(layer "In5.Cu")
		(net 911)
	)
	(segment
		(start 225.7 121)
		(end 231.1 121)
		(width 0.1)
		(layer "In5.Cu")
		(net 911)
	)
	(segment
		(start 234.5 121)
		(end 231.1 121)
		(width 0.1)
		(layer "In5.Cu")
		(net 911)
	)
	(segment
		(start 201.3 120.1)
		(end 224.8 120.1)
		(width 0.1)
		(layer "In5.Cu")
		(net 911)
	)
	(segment
		(start 197.901 124.101)
		(end 197.6 123.8)
		(width 0.1)
		(layer "F.Cu")
		(net 912)
	)
	(segment
		(start 197.6 123.8)
		(end 195.8 123.8)
		(width 0.1)
		(layer "F.Cu")
		(net 912)
	)
	(segment
		(start 199.565 124.101)
		(end 197.901 124.101)
		(width 0.1)
		(layer "F.Cu")
		(net 912)
	)
	(via
		(at 195.8 123.8)
		(size 0.45)
		(drill 0.1)
		(layers "F.Cu" "B.Cu")
		(net 912)
	)
	(segment
		(start 213.925 121.9)
		(end 215.3 121.9)
		(width 0.1)
		(layer "F.Cu")
		(net 913)
	)
	(segment
		(start 215.8 121.4)
		(end 215.8 120.58)
		(width 0.1)
		(layer "F.Cu")
		(net 913)
	)
	(segment
		(start 215.8 120.58)
		(end 216.8 120.58)
		(width 0.1)
		(layer "F.Cu")
		(net 913)
	)
	(segment
		(start 213.7125 122.1125)
		(end 213.925 121.9)
		(width 0.1)
		(layer "F.Cu")
		(net 913)
	)
	(segment
		(start 211.142 122.5)
		(end 211.625 122.5)
		(width 0.1)
		(layer "F.Cu")
		(net 913)
	)
	(segment
		(start 212.0125 122.1125)
		(end 213.7125 122.1125)
		(width 0.1)
		(layer "F.Cu")
		(net 913)
	)
	(segment
		(start 215.3 121.9)
		(end 215.8 121.4)
		(width 0.1)
		(layer "F.Cu")
		(net 913)
	)
	(segment
		(start 211.625 122.5)
		(end 212.0125 122.1125)
		(width 0.1)
		(layer "F.Cu")
		(net 913)
	)
	(segment
		(start 199.565 124.5)
		(end 198.6 124.5)
		(width 0.1)
		(layer "F.Cu")
		(net 914)
	)
	(via
		(at 231.1 132.3)
		(size 0.45)
		(drill 0.1)
		(layers "F.Cu" "B.Cu")
		(net 914)
	)
	(via
		(at 198.6 124.5)
		(size 0.45)
		(drill 0.1)
		(layers "F.Cu" "B.Cu")
		(remove_unused_layers yes)
		(keep_end_layers yes)
		(zone_layer_connections)
		(net 914)
	)
	(via
		(at 234.7 133)
		(size 0.45)
		(drill 0.1)
		(layers "F.Cu" "B.Cu")
		(net 914)
	)
	(segment
		(start 234.654 133.046)
		(end 234.7 133)
		(width 0.1)
		(layer "B.Cu")
		(net 914)
	)
	(segment
		(start 231.099 133.046)
		(end 231.099 132.301)
		(width 0.1)
		(layer "B.Cu")
		(net 914)
	)
	(segment
		(start 231.099 132.301)
		(end 231.1 132.3)
		(width 0.1)
		(layer "B.Cu")
		(net 914)
	)
	(segment
		(start 197.7 124.5)
		(end 197.5 124.3)
		(width 0.1)
		(layer "B.Cu")
		(net 914)
	)
	(segment
		(start 198.6 124.5)
		(end 197.7 124.5)
		(width 0.1)
		(layer "B.Cu")
		(net 914)
	)
	(segment
		(start 233.699 133.046)
		(end 234.654 133.046)
		(width 0.1)
		(layer "B.Cu")
		(net 914)
	)
	(segment
		(start 232.7 132.3)
		(end 231.1 132.3)
		(width 0.1)
		(layer "In5.Cu")
		(net 914)
	)
	(segment
		(start 216 130)
		(end 213.6 127.6)
		(width 0.1)
		(layer "In5.Cu")
		(net 914)
	)
	(segment
		(start 234.7 133)
		(end 233.4 133)
		(width 0.1)
		(layer "In5.Cu")
		(net 914)
	)
	(segment
		(start 220.4 129.6)
		(end 220 130)
		(width 0.1)
		(layer "In5.Cu")
		(net 914)
	)
	(segment
		(start 223.6 129.6)
		(end 220.4 129.6)
		(width 0.1)
		(layer "In5.Cu")
		(net 914)
	)
	(segment
		(start 226.3 132.3)
		(end 223.6 129.6)
		(width 0.1)
		(layer "In5.Cu")
		(net 914)
	)
	(segment
		(start 201.7 127.6)
		(end 198.6 124.5)
		(width 0.1)
		(layer "In5.Cu")
		(net 914)
	)
	(segment
		(start 220 130)
		(end 216 130)
		(width 0.1)
		(layer "In5.Cu")
		(net 914)
	)
	(segment
		(start 231.1 132.3)
		(end 226.3 132.3)
		(width 0.1)
		(layer "In5.Cu")
		(net 914)
	)
	(segment
		(start 213.6 127.6)
		(end 201.7 127.6)
		(width 0.1)
		(layer "In5.Cu")
		(net 914)
	)
	(segment
		(start 233.4 133)
		(end 232.7 132.3)
		(width 0.1)
		(layer "In5.Cu")
		(net 914)
	)
	(segment
		(start 211.142 122.099)
		(end 211.601 122.099)
		(width 0.1)
		(layer "F.Cu")
		(net 915)
	)
	(segment
		(start 214.5 121.5)
		(end 214.8 121.2)
		(width 0.1)
		(layer "F.Cu")
		(net 915)
	)
	(segment
		(start 211.601 122.099)
		(end 211.8 121.9)
		(width 0.1)
		(layer "F.Cu")
		(net 915)
	)
	(segment
		(start 214.8 121.2)
		(end 214.8 120.58)
		(width 0.1)
		(layer "F.Cu")
		(net 915)
	)
	(segment
		(start 213.5 121.9)
		(end 213.9 121.5)
		(width 0.1)
		(layer "F.Cu")
		(net 915)
	)
	(segment
		(start 213.9 121.5)
		(end 214.5 121.5)
		(width 0.1)
		(layer "F.Cu")
		(net 915)
	)
	(segment
		(start 211.8 121.9)
		(end 213.5 121.9)
		(width 0.1)
		(layer "F.Cu")
		(net 915)
	)
	(segment
		(start 198.6 126.6)
		(end 196.28 126.6)
		(width 0.1)
		(layer "F.Cu")
		(net 916)
	)
	(segment
		(start 198.699 126.501)
		(end 199.565 126.501)
		(width 0.1)
		(layer "F.Cu")
		(net 916)
	)
	(segment
		(start 198.6 126.6)
		(end 198.699 126.501)
		(width 0.1)
		(layer "F.Cu")
		(net 916)
	)
	(segment
		(start 196.28 126.6)
		(end 195.58 127.3)
		(width 0.1)
		(layer "F.Cu")
		(net 916)
	)
	(segment
		(start 198.7 126.1)
		(end 199.565 126.1)
		(width 0.1)
		(layer "F.Cu")
		(net 917)
	)
	(segment
		(start 198.5 126.3)
		(end 198.7 126.1)
		(width 0.1)
		(layer "F.Cu")
		(net 917)
	)
	(segment
		(start 195.58 126.3)
		(end 198.5 126.3)
		(width 0.1)
		(layer "F.Cu")
		(net 917)
	)
	(segment
		(start 210.153 132.153)
		(end 210.4 132.4)
		(width 0.1)
		(layer "F.Cu")
		(net 919)
	)
	(segment
		(start 210.4 132.4)
		(end 210.95 132.4)
		(width 0.1)
		(layer "F.Cu")
		(net 919)
	)
	(segment
		(start 211.62 133.1)
		(end 211.62 133.07)
		(width 0.1)
		(layer "F.Cu")
		(net 919)
	)
	(segment
		(start 210.153 131.488)
		(end 210.153 132.153)
		(width 0.1)
		(layer "F.Cu")
		(net 919)
	)
	(segment
		(start 211.62 133.07)
		(end 210.95 132.4)
		(width 0.1)
		(layer "F.Cu")
		(net 919)
	)
	(segment
		(start 196.18 125.9)
		(end 198.3 125.9)
		(width 0.1)
		(layer "F.Cu")
		(net 920)
	)
	(segment
		(start 198.3 125.9)
		(end 198.501 125.699)
		(width 0.1)
		(layer "F.Cu")
		(net 920)
	)
	(segment
		(start 195.58 125.3)
		(end 196.18 125.9)
		(width 0.1)
		(layer "F.Cu")
		(net 920)
	)
	(segment
		(start 198.501 125.699)
		(end 199.565 125.699)
		(width 0.1)
		(layer "F.Cu")
		(net 920)
	)
	(segment
		(start 188.7 123.68)
		(end 189.3 123.08)
		(width 0.1)
		(layer "F.Cu")
		(net 921)
	)
	(segment
		(start 199.565 129.3)
		(end 198.5 129.3)
		(width 0.1)
		(layer "F.Cu")
		(net 921)
	)
	(segment
		(start 188.7 123.8)
		(end 188.7 123.68)
		(width 0.1)
		(layer "F.Cu")
		(net 921)
	)
	(via
		(at 188.7 123.8)
		(size 0.45)
		(drill 0.1)
		(layers "F.Cu" "B.Cu")
		(net 921)
	)
	(via
		(at 198.5 129.3)
		(size 0.45)
		(drill 0.1)
		(layers "F.Cu" "B.Cu")
		(net 921)
	)
	(segment
		(start 192.65 129.3)
		(end 198.5 129.3)
		(width 0.1)
		(layer "B.Cu")
		(net 921)
	)
	(segment
		(start 199.7 127.4)
		(end 199.7 128.5)
		(width 0.1)
		(layer "B.Cu")
		(net 921)
	)
	(segment
		(start 198.9 129.3)
		(end 198.5 129.3)
		(width 0.1)
		(layer "B.Cu")
		(net 921)
	)
	(segment
		(start 199.9 127.2)
		(end 199.7 127.4)
		(width 0.1)
		(layer "B.Cu")
		(net 921)
	)
	(segment
		(start 200.32 127.2)
		(end 199.9 127.2)
		(width 0.1)
		(layer "B.Cu")
		(net 921)
	)
	(segment
		(start 199.7 128.5)
		(end 198.9 129.3)
		(width 0.1)
		(layer "B.Cu")
		(net 921)
	)
	(segment
		(start 188.7 125.35)
		(end 192.65 129.3)
		(width 0.1)
		(layer "B.Cu")
		(net 921)
	)
	(segment
		(start 188.7 123.8)
		(end 188.7 125.35)
		(width 0.1)
		(layer "B.Cu")
		(net 921)
	)
	(segment
		(start 198.3 128.9)
		(end 198.2 128.8)
		(width 0.1)
		(layer "F.Cu")
		(net 922)
	)
	(segment
		(start 190.12 123.08)
		(end 190.3 123.08)
		(width 0.1)
		(layer "F.Cu")
		(net 922)
	)
	(segment
		(start 189.4 123.8)
		(end 190.12 123.08)
		(width 0.1)
		(layer "F.Cu")
		(net 922)
	)
	(segment
		(start 189.4 123.8)
		(end 189.568255 123.8)
		(width 0.1)
		(layer "F.Cu")
		(net 922)
	)
	(segment
		(start 199.565 128.9)
		(end 198.3 128.9)
		(width 0.1)
		(layer "F.Cu")
		(net 922)
	)
	(segment
		(start 190.288255 123.08)
		(end 190.5 123.08)
		(width 0.1)
		(layer "F.Cu")
		(net 922)
	)
	(via
		(at 198.2 128.8)
		(size 0.45)
		(drill 0.1)
		(layers "F.Cu" "B.Cu")
		(net 922)
	)
	(via
		(at 189.4 123.8)
		(size 0.45)
		(drill 0.1)
		(layers "F.Cu" "B.Cu")
		(net 922)
	)
	(segment
		(start 199.8 126.2)
		(end 200.32 126.2)
		(width 0.1)
		(layer "B.Cu")
		(net 922)
	)
	(segment
		(start 196.3 128.8)
		(end 198.2 128.8)
		(width 0.1)
		(layer "B.Cu")
		(net 922)
	)
	(segment
		(start 198.8 128.8)
		(end 199.425 128.175)
		(width 0.1)
		(layer "B.Cu")
		(net 922)
	)
	(segment
		(start 189.4 125.3)
		(end 193.1 129)
		(width 0.1)
		(layer "B.Cu")
		(net 922)
	)
	(segment
		(start 199.425 128.175)
		(end 199.425 126.575)
		(width 0.1)
		(layer "B.Cu")
		(net 922)
	)
	(segment
		(start 196.1 129)
		(end 196.3 128.8)
		(width 0.1)
		(layer "B.Cu")
		(net 922)
	)
	(segment
		(start 199.425 126.575)
		(end 199.8 126.2)
		(width 0.1)
		(layer "B.Cu")
		(net 922)
	)
	(segment
		(start 193.1 129)
		(end 196.1 129)
		(width 0.1)
		(layer "B.Cu")
		(net 922)
	)
	(segment
		(start 189.4 123.8)
		(end 189.4 125.3)
		(width 0.1)
		(layer "B.Cu")
		(net 922)
	)
	(segment
		(start 198.2 128.8)
		(end 198.8 128.8)
		(width 0.1)
		(layer "B.Cu")
		(net 922)
	)
	(segment
		(start 187.095 116.6)
		(end 188.1 116.6)
		(width 0.1)
		(layer "F.Cu")
		(net 923)
	)
	(segment
		(start 189.8 120.2)
		(end 191.3 121.7)
		(width 0.1)
		(layer "F.Cu")
		(net 923)
	)
	(segment
		(start 191.3 121.7)
		(end 191.3 122.12)
		(width 0.1)
		(layer "F.Cu")
		(net 923)
	)
	(segment
		(start 188.1 116.6)
		(end 189.8 118.3)
		(width 0.1)
		(layer "F.Cu")
		(net 923)
	)
	(segment
		(start 189.8 118.3)
		(end 189.8 120.2)
		(width 0.1)
		(layer "F.Cu")
		(net 923)
	)
	(segment
		(start 187.1 116.595)
		(end 187.095 116.6)
		(width 0.1)
		(layer "F.Cu")
		(net 923)
	)
	(via
		(at 187.1 116.7)
		(size 0.45)
		(drill 0.1)
		(layers "F.Cu" "B.Cu")
		(net 923)
	)
	(segment
		(start 187.8 120.6)
		(end 187.8 121.22)
		(width 0.1)
		(layer "B.Cu")
		(net 923)
	)
	(segment
		(start 186.4 119.2)
		(end 186.4 117.4)
		(width 0.1)
		(layer "B.Cu")
		(net 923)
	)
	(segment
		(start 186.4 119.2)
		(end 187.8 120.6)
		(width 0.1)
		(layer "B.Cu")
		(net 923)
	)
	(segment
		(start 186.4 117.4)
		(end 187.1 116.7)
		(width 0.1)
		(layer "B.Cu")
		(net 923)
	)
	(segment
		(start 188.3 123.5)
		(end 188.3 123.08)
		(width 0.1)
		(layer "F.Cu")
		(net 924)
	)
	(segment
		(start 199.565 129.699)
		(end 198.701 129.699)
		(width 0.1)
		(layer "F.Cu")
		(net 924)
	)
	(segment
		(start 198.701 129.699)
		(end 198.5 129.9)
		(width 0.1)
		(layer "F.Cu")
		(net 924)
	)
	(segment
		(start 188 123.8)
		(end 188.3 123.5)
		(width 0.1)
		(layer "F.Cu")
		(net 924)
	)
	(via
		(at 188 123.8)
		(size 0.45)
		(drill 0.1)
		(layers "F.Cu" "B.Cu")
		(net 924)
	)
	(via
		(at 198.5 129.9)
		(size 0.45)
		(drill 0.1)
		(layers "F.Cu" "B.Cu")
		(net 924)
	)
	(segment
		(start 199.1 129.9)
		(end 200.32 128.68)
		(width 0.1)
		(layer "B.Cu")
		(net 924)
	)
	(segment
		(start 188 125.25)
		(end 192.65 129.9)
		(width 0.1)
		(layer "B.Cu")
		(net 924)
	)
	(segment
		(start 192.65 129.9)
		(end 198.5 129.9)
		(width 0.1)
		(layer "B.Cu")
		(net 924)
	)
	(segment
		(start 188 123.8)
		(end 188 125.25)
		(width 0.1)
		(layer "B.Cu")
		(net 924)
	)
	(segment
		(start 198.5 129.9)
		(end 199.1 129.9)
		(width 0.1)
		(layer "B.Cu")
		(net 924)
	)
	(segment
		(start 200.32 128.68)
		(end 200.32 128.2)
		(width 0.1)
		(layer "B.Cu")
		(net 924)
	)
	(segment
		(start 190.1 123.8)
		(end 190.58 123.8)
		(width 0.1)
		(layer "F.Cu")
		(net 925)
	)
	(segment
		(start 190.58 123.8)
		(end 191.3 123.08)
		(width 0.1)
		(layer "F.Cu")
		(net 925)
	)
	(segment
		(start 198.7 128.5)
		(end 198.5 128.3)
		(width 0.1)
		(layer "F.Cu")
		(net 925)
	)
	(segment
		(start 199.565 128.5)
		(end 198.7 128.5)
		(width 0.1)
		(layer "F.Cu")
		(net 925)
	)
	(via
		(at 190.1 123.8)
		(size 0.45)
		(drill 0.1)
		(layers "F.Cu" "B.Cu")
		(net 925)
	)
	(via
		(at 198.5 128.3)
		(size 0.45)
		(drill 0.1)
		(layers "F.Cu" "B.Cu")
		(net 925)
	)
	(segment
		(start 199.8 125.2)
		(end 200.32 125.2)
		(width 0.1)
		(layer "B.Cu")
		(net 925)
	)
	(segment
		(start 194.9 128.3)
		(end 195.4 128.3)
		(width 0.1)
		(layer "B.Cu")
		(net 925)
	)
	(segment
		(start 194.375 127.775)
		(end 194.9 128.3)
		(width 0.1)
		(layer "B.Cu")
		(net 925)
	)
	(segment
		(start 199.2 127.6)
		(end 199.2 125.8)
		(width 0.1)
		(layer "B.Cu")
		(net 925)
	)
	(segment
		(start 199.2 125.8)
		(end 199.8 125.2)
		(width 0.1)
		(layer "B.Cu")
		(net 925)
	)
	(segment
		(start 198.5 128.3)
		(end 195.4 128.3)
		(width 0.1)
		(layer "B.Cu")
		(net 925)
	)
	(segment
		(start 198.5 128.3)
		(end 199.2 127.6)
		(width 0.1)
		(layer "B.Cu")
		(net 925)
	)
	(segment
		(start 190.1 123.8)
		(end 190.1 124.65)
		(width 0.1)
		(layer "B.Cu")
		(net 925)
	)
	(segment
		(start 193.225 127.775)
		(end 194.375 127.775)
		(width 0.1)
		(layer "B.Cu")
		(net 925)
	)
	(segment
		(start 190.1 124.65)
		(end 193.225 127.775)
		(width 0.1)
		(layer "B.Cu")
		(net 925)
	)
	(segment
		(start 195.4 127.56)
		(end 195.4 128.3)
		(width 0.1)
		(layer "B.Cu")
		(net 925)
	)
	(segment
		(start 189.002 120.002)
		(end 189 120)
		(width 0.1)
		(layer "F.Cu")
		(net 926)
	)
	(segment
		(start 194.3 119.235)
		(end 191.235 119.235)
		(width 0.1)
		(layer "F.Cu")
		(net 926)
	)
	(segment
		(start 191.235 119.235)
		(end 191.2 119.2)
		(width 0.1)
		(layer "F.Cu")
		(net 926)
	)
	(segment
		(start 194.4 119.135)
		(end 194.3 119.235)
		(width 0.1)
		(layer "F.Cu")
		(net 926)
	)
	(segment
		(start 190.3 122)
		(end 190.3 122.12)
		(width 0.1)
		(layer "F.Cu")
		(net 926)
	)
	(segment
		(start 189 120)
		(end 189 120.7)
		(width 0.1)
		(layer "F.Cu")
		(net 926)
	)
	(segment
		(start 189 120.7)
		(end 190.3 122)
		(width 0.1)
		(layer "F.Cu")
		(net 926)
	)
	(via
		(at 189 120)
		(size 0.45)
		(drill 0.1)
		(layers "F.Cu" "B.Cu")
		(net 926)
	)
	(via
		(at 191.2 119.2)
		(size 0.45)
		(drill 0.1)
		(layers "F.Cu" "B.Cu")
		(net 926)
	)
	(segment
		(start 189.8 119.2)
		(end 191.2 119.2)
		(width 0.1)
		(layer "B.Cu")
		(net 926)
	)
	(segment
		(start 189 120)
		(end 189.8 119.2)
		(width 0.1)
		(layer "B.Cu")
		(net 926)
	)
	(segment
		(start 189 120)
		(end 190 121)
		(width 0.1)
		(layer "B.Cu")
		(net 926)
	)
	(segment
		(start 190 121)
		(end 190 121.22)
		(width 0.1)
		(layer "B.Cu")
		(net 926)
	)
	(segment
		(start 198 127.9)
		(end 197.3 127.9)
		(width 0.1)
		(layer "F.Cu")
		(net 927)
	)
	(segment
		(start 198.201 127.699)
		(end 199.565 127.699)
		(width 0.1)
		(layer "F.Cu")
		(net 927)
	)
	(segment
		(start 195.58 128.3)
		(end 196.9 128.3)
		(width 0.1)
		(layer "F.Cu")
		(net 927)
	)
	(segment
		(start 198 127.9)
		(end 198.201 127.699)
		(width 0.1)
		(layer "F.Cu")
		(net 927)
	)
	(segment
		(start 196.9 128.3)
		(end 197.3 127.9)
		(width 0.1)
		(layer "F.Cu")
		(net 927)
	)
	(via
		(at 197.3 127.9)
		(size 0.45)
		(drill 0.1)
		(layers "F.Cu" "B.Cu")
		(net 927)
	)
	(segment
		(start 198.5 127.9)
		(end 198.9 127.5)
		(width 0.1)
		(layer "B.Cu")
		(net 927)
	)
	(segment
		(start 199.8 124.2)
		(end 200.32 124.2)
		(width 0.1)
		(layer "B.Cu")
		(net 927)
	)
	(segment
		(start 198.9 127.5)
		(end 198.9 125.1)
		(width 0.1)
		(layer "B.Cu")
		(net 927)
	)
	(segment
		(start 198.9 125.1)
		(end 199.8 124.2)
		(width 0.1)
		(layer "B.Cu")
		(net 927)
	)
	(segment
		(start 197.3 127.9)
		(end 198.5 127.9)
		(width 0.1)
		(layer "B.Cu")
		(net 927)
	)
	(segment
		(start 187 118)
		(end 187.1 117.9)
		(width 0.1)
		(layer "F.Cu")
		(net 928)
	)
	(segment
		(start 194.1 128.3)
		(end 194 128.2)
		(width 0.1)
		(layer "F.Cu")
		(net 928)
	)
	(segment
		(start 194.62 128.3)
		(end 194.1 128.3)
		(width 0.1)
		(layer "F.Cu")
		(net 928)
	)
	(segment
		(start 187.1 117.9)
		(end 187.1 117.865)
		(width 0.1)
		(layer "F.Cu")
		(net 928)
	)
	(via
		(at 194 128.2)
		(size 0.45)
		(drill 0.1)
		(layers "F.Cu" "B.Cu")
		(net 928)
	)
	(via
		(at 187 118)
		(size 0.45)
		(drill 0.1)
		(layers "F.Cu" "B.Cu")
		(net 928)
	)
	(segment
		(start 187 118.8)
		(end 188.9 120.7)
		(width 0.1)
		(layer "B.Cu")
		(net 928)
	)
	(segment
		(start 188.9 120.7)
		(end 188.9 121.22)
		(width 0.1)
		(layer "B.Cu")
		(net 928)
	)
	(segment
		(start 187 118)
		(end 187 118.8)
		(width 0.1)
		(layer "B.Cu")
		(net 928)
	)
	(segment
		(start 192 117.4)
		(end 187.6 117.4)
		(width 0.1)
		(layer "In5.Cu")
		(net 928)
	)
	(segment
		(start 192.4 126.6)
		(end 192.4 117.8)
		(width 0.1)
		(layer "In5.Cu")
		(net 928)
	)
	(segment
		(start 194 128.2)
		(end 192.4 126.6)
		(width 0.1)
		(layer "In5.Cu")
		(net 928)
	)
	(segment
		(start 187.6 117.4)
		(end 187 118)
		(width 0.1)
		(layer "In5.Cu")
		(net 928)
	)
	(segment
		(start 192.4 117.8)
		(end 192 117.4)
		(width 0.1)
		(layer "In5.Cu")
		(net 928)
	)
	(segment
		(start 192.95 120.405)
		(end 194.4 120.405)
		(width 0.1)
		(layer "F.Cu")
		(net 929)
	)
	(segment
		(start 191.2 120.6)
		(end 192.755 120.6)
		(width 0.1)
		(layer "F.Cu")
		(net 929)
	)
	(segment
		(start 194.3 129.3)
		(end 193.6 128.6)
		(width 0.1)
		(layer "F.Cu")
		(net 929)
	)
	(segment
		(start 194.62 129.3)
		(end 194.3 129.3)
		(width 0.1)
		(layer "F.Cu")
		(net 929)
	)
	(segment
		(start 192.755 120.6)
		(end 192.95 120.405)
		(width 0.1)
		(layer "F.Cu")
		(net 929)
	)
	(via
		(at 191.2 120.6)
		(size 0.45)
		(drill 0.1)
		(layers "F.Cu" "B.Cu")
		(net 929)
	)
	(via
		(at 193.6 128.6)
		(size 0.45)
		(drill 0.1)
		(layers "F.Cu" "B.Cu")
		(net 929)
	)
	(segment
		(start 191.12 121.22)
		(end 191.12 120.68)
		(width 0.1)
		(layer "B.Cu")
		(net 929)
	)
	(segment
		(start 191.12 120.68)
		(end 191.2 120.6)
		(width 0.1)
		(layer "B.Cu")
		(net 929)
	)
	(segment
		(start 192.2 123.4)
		(end 192.2 127.2)
		(width 0.1)
		(layer "In5.Cu")
		(net 929)
	)
	(segment
		(start 192.2 127.2)
		(end 193.6 128.6)
		(width 0.1)
		(layer "In5.Cu")
		(net 929)
	)
	(segment
		(start 191.2 120.6)
		(end 191.2 122.4)
		(width 0.1)
		(layer "In5.Cu")
		(net 929)
	)
	(segment
		(start 191.2 122.4)
		(end 192.2 123.4)
		(width 0.1)
		(layer "In5.Cu")
		(net 929)
	)
	(segment
		(start 197.2 129.3)
		(end 196.6 129.3)
		(width 0.1)
		(layer "F.Cu")
		(net 930)
	)
	(segment
		(start 196.6 130.35)
		(end 196.6 129.3)
		(width 0.1)
		(layer "F.Cu")
		(net 930)
	)
	(segment
		(start 198.899 128.099)
		(end 198.7 127.9)
		(width 0.1)
		(layer "F.Cu")
		(net 930)
	)
	(segment
		(start 199.565 128.099)
		(end 198.899 128.099)
		(width 0.1)
		(layer "F.Cu")
		(net 930)
	)
	(segment
		(start 197.7 128.5)
		(end 197.7 128.8)
		(width 0.1)
		(layer "F.Cu")
		(net 930)
	)
	(segment
		(start 196.6 129.3)
		(end 195.58 129.3)
		(width 0.1)
		(layer "F.Cu")
		(net 930)
	)
	(segment
		(start 198.7 127.9)
		(end 198.3 127.9)
		(width 0.1)
		(layer "F.Cu")
		(net 930)
	)
	(segment
		(start 197.7 128.8)
		(end 197.2 129.3)
		(width 0.1)
		(layer "F.Cu")
		(net 930)
	)
	(segment
		(start 198.3 127.9)
		(end 197.7 128.5)
		(width 0.1)
		(layer "F.Cu")
		(net 930)
	)
	(via
		(at 196.6 130.35)
		(size 0.45)
		(drill 0.1)
		(layers "F.Cu" "B.Cu")
		(net 930)
	)
	(segment
		(start 196.6 131.17)
		(end 196.6 130.35)
		(width 0.1)
		(layer "B.Cu")
		(net 930)
	)
	(segment
		(start 195.6 131.17)
		(end 196.6 131.17)
		(width 0.1)
		(layer "B.Cu")
		(net 930)
	)
	(segment
		(start 213.3 121.7)
		(end 213.8 121.2)
		(width 0.1)
		(layer "F.Cu")
		(net 931)
	)
	(segment
		(start 213.8 121.2)
		(end 213.8 120.58)
		(width 0.1)
		(layer "F.Cu")
		(net 931)
	)
	(segment
		(start 211.142 121.7)
		(end 213.3 121.7)
		(width 0.1)
		(layer "F.Cu")
		(net 931)
	)
	(segment
		(start 212.2 129.8)
		(end 211.7 129.3)
		(width 0.1)
		(layer "F.Cu")
		(net 932)
	)
	(segment
		(start 212.2 130)
		(end 212.2 129.8)
		(width 0.1)
		(layer "F.Cu")
		(net 932)
	)
	(segment
		(start 213 130.8)
		(end 212.2 130)
		(width 0.1)
		(layer "F.Cu")
		(net 932)
	)
	(segment
		(start 211.7 129.3)
		(end 211.142 129.3)
		(width 0.1)
		(layer "F.Cu")
		(net 932)
	)
	(segment
		(start 213.52 131.8)
		(end 213.52 130.8)
		(width 0.1)
		(layer "F.Cu")
		(net 932)
	)
	(segment
		(start 213.52 130.8)
		(end 213 130.8)
		(width 0.1)
		(layer "F.Cu")
		(net 932)
	)
	(segment
		(start 198.399 82.999)
		(end 198.399 81.831)
		(width 0.1)
		(layer "F.Cu")
		(net 933)
	)
	(segment
		(start 198.4 83)
		(end 198.399 82.999)
		(width 0.1)
		(layer "F.Cu")
		(net 933)
	)
	(segment
		(start 198.25 83.15)
		(end 198.4 83)
		(width 0.1)
		(layer "F.Cu")
		(net 933)
	)
	(segment
		(start 198.25 83.52)
		(end 198.25 83.15)
		(width 0.1)
		(layer "F.Cu")
		(net 933)
	)
	(segment
		(start 204.22 79.08)
		(end 204.8 78.5)
		(width 0.1)
		(layer "F.Cu")
		(net 934)
	)
	(segment
		(start 203.95 79.08)
		(end 204.22 79.08)
		(width 0.1)
		(layer "F.Cu")
		(net 934)
	)
	(segment
		(start 204.8 78.5)
		(end 207.3 78.5)
		(width 0.1)
		(layer "F.Cu")
		(net 934)
	)
	(via
		(at 207.3 78.5)
		(size 0.45)
		(drill 0.1)
		(layers "F.Cu" "B.Cu")
		(net 934)
	)
	(segment
		(start 207.32 78.52)
		(end 207.3 78.5)
		(width 0.1)
		(layer "B.Cu")
		(net 934)
	)
	(segment
		(start 207.32 79)
		(end 207.32 78.52)
		(width 0.1)
		(layer "B.Cu")
		(net 934)
	)
	(segment
		(start 207.32 80)
		(end 207.32 79)
		(width 0.1)
		(layer "B.Cu")
		(net 934)
	)
	(segment
		(start 203.95 77.482)
		(end 204.882 77.482)
		(width 0.1)
		(layer "F.Cu")
		(net 935)
	)
	(segment
		(start 204.882 77.482)
		(end 204.9 77.5)
		(width 0.1)
		(layer "F.Cu")
		(net 935)
	)
	(via
		(at 204.9 77.5)
		(size 0.45)
		(drill 0.1)
		(layers "F.Cu" "B.Cu")
		(net 935)
	)
	(segment
		(start 205.5 82.3)
		(end 207.32 82.3)
		(width 0.1)
		(layer "B.Cu")
		(net 935)
	)
	(segment
		(start 204.1 80.9)
		(end 205.5 82.3)
		(width 0.1)
		(layer "B.Cu")
		(net 935)
	)
	(segment
		(start 207.32 82.3)
		(end 207.32 81.3)
		(width 0.1)
		(layer "B.Cu")
		(net 935)
	)
	(segment
		(start 204.9 77.5)
		(end 204.5 77.5)
		(width 0.1)
		(layer "B.Cu")
		(net 935)
	)
	(segment
		(start 204.5 77.5)
		(end 204.1 77.9)
		(width 0.1)
		(layer "B.Cu")
		(net 935)
	)
	(segment
		(start 204.1 77.9)
		(end 204.1 80.9)
		(width 0.1)
		(layer "B.Cu")
		(net 935)
	)
	(segment
		(start 197.249 78.682)
		(end 196.818 78.682)
		(width 0.1)
		(layer "F.Cu")
		(net 936)
	)
	(segment
		(start 195.35 79.65)
		(end 195.1 79.9)
		(width 0.1)
		(layer "F.Cu")
		(net 936)
	)
	(segment
		(start 196.818 78.682)
		(end 195.85 79.65)
		(width 0.1)
		(layer "F.Cu")
		(net 936)
	)
	(segment
		(start 195.1 81.1)
		(end 195 81.2)
		(width 0.1)
		(layer "F.Cu")
		(net 936)
	)
	(segment
		(start 195.1 79.9)
		(end 195.1 81.1)
		(width 0.1)
		(layer "F.Cu")
		(net 936)
	)
	(segment
		(start 190.95 83.35)
		(end 190.95 84.15)
		(width 0.1)
		(layer "F.Cu")
		(net 936)
	)
	(segment
		(start 191 84.2)
		(end 191.677 84.2)
		(width 0.1)
		(layer "F.Cu")
		(net 936)
	)
	(segment
		(start 195.85 79.65)
		(end 195.35 79.65)
		(width 0.1)
		(layer "F.Cu")
		(net 936)
	)
	(segment
		(start 193.1 81.2)
		(end 190.95 83.35)
		(width 0.1)
		(layer "F.Cu")
		(net 936)
	)
	(segment
		(start 195 81.2)
		(end 193.1 81.2)
		(width 0.1)
		(layer "F.Cu")
		(net 936)
	)
	(via
		(at 190.95 84.15)
		(size 0.45)
		(drill 0.1)
		(layers "F.Cu" "B.Cu")
		(net 936)
	)
	(segment
		(start 193.22 84.92)
		(end 193.22 84.1)
		(width 0.1)
		(layer "B.Cu")
		(net 936)
	)
	(segment
		(start 193.7 85.4)
		(end 193.22 84.92)
		(width 0.1)
		(layer "B.Cu")
		(net 936)
	)
	(segment
		(start 191 84.1)
		(end 193.22 84.1)
		(width 0.1)
		(layer "B.Cu")
		(net 936)
	)
	(segment
		(start 190.95 84.15)
		(end 191 84.1)
		(width 0.1)
		(layer "B.Cu")
		(net 936)
	)
	(segment
		(start 193.7 87.32)
		(end 193.7 85.4)
		(width 0.1)
		(layer "B.Cu")
		(net 936)
	)
	(via
		(at 216 56.3)
		(size 0.45)
		(drill 0.1)
		(layers "F.Cu" "B.Cu")
		(net 937)
	)
	(via
		(at 72.6 65.9)
		(size 0.45)
		(drill 0.1)
		(layers "F.Cu" "B.Cu")
		(net 937)
	)
	(segment
		(start 72 65.3)
		(end 72.6 65.9)
		(width 0.1)
		(layer "B.Cu")
		(net 937)
	)
	(segment
		(start 213.657 57.043)
		(end 213.657 58.39)
		(width 0.1)
		(layer "B.Cu")
		(net 937)
	)
	(segment
		(start 214.4 56.3)
		(end 213.657 57.043)
		(width 0.1)
		(layer "B.Cu")
		(net 937)
	)
	(segment
		(start 216 56.3)
		(end 214.4 56.3)
		(width 0.1)
		(layer "B.Cu")
		(net 937)
	)
	(segment
		(start 71.58 65.3)
		(end 72 65.3)
		(width 0.1)
		(layer "B.Cu")
		(net 937)
	)
	(segment
		(start 213.5 56.3)
		(end 211.9 57.9)
		(width 0.1)
		(layer "In5.Cu")
		(net 937)
	)
	(segment
		(start 75.434316 67.799998)
		(end 74.234315 66.599997)
		(width 0.1)
		(layer "In5.Cu")
		(net 937)
	)
	(segment
		(start 74.234315 66.599997)
		(end 73.568258 66.599997)
		(width 0.1)
		(layer "In5.Cu")
		(net 937)
	)
	(segment
		(start 112 66.5)
		(end 111.4 67.1)
		(width 0.1)
		(layer "In5.Cu")
		(net 937)
	)
	(segment
		(start 182.25 63.6)
		(end 160 63.6)
		(width 0.1)
		(layer "In5.Cu")
		(net 937)
	)
	(segment
		(start 155.4 68.2)
		(end 147.9 68.2)
		(width 0.1)
		(layer "In5.Cu")
		(net 937)
	)
	(segment
		(start 85.634314 66.6)
		(end 84.434316 67.799998)
		(width 0.1)
		(layer "In5.Cu")
		(net 937)
	)
	(segment
		(start 160 63.6)
		(end 155.4 68.2)
		(width 0.1)
		(layer "In5.Cu")
		(net 937)
	)
	(segment
		(start 216 56.3)
		(end 213.5 56.3)
		(width 0.1)
		(layer "In5.Cu")
		(net 937)
	)
	(segment
		(start 73.468255 66.7)
		(end 73.168249 66.7)
		(width 0.1)
		(layer "In5.Cu")
		(net 937)
	)
	(segment
		(start 211.9 57.9)
		(end 194.5 57.9)
		(width 0.1)
		(layer "In5.Cu")
		(net 937)
	)
	(segment
		(start 124.5 66.5)
		(end 112 66.5)
		(width 0.1)
		(layer "In5.Cu")
		(net 937)
	)
	(segment
		(start 104.4 66.6)
		(end 85.634314 66.6)
		(width 0.1)
		(layer "In5.Cu")
		(net 937)
	)
	(segment
		(start 189.7 62.7)
		(end 183.15 62.7)
		(width 0.1)
		(layer "In5.Cu")
		(net 937)
	)
	(segment
		(start 147.9 68.2)
		(end 144.1 64.4)
		(width 0.1)
		(layer "In5.Cu")
		(net 937)
	)
	(segment
		(start 144.1 64.4)
		(end 126.6 64.4)
		(width 0.1)
		(layer "In5.Cu")
		(net 937)
	)
	(segment
		(start 73.168249 66.7)
		(end 72.6 66.131751)
		(width 0.1)
		(layer "In5.Cu")
		(net 937)
	)
	(segment
		(start 104.9 67.1)
		(end 104.4 66.6)
		(width 0.1)
		(layer "In5.Cu")
		(net 937)
	)
	(segment
		(start 73.568258 66.599997)
		(end 73.468255 66.7)
		(width 0.1)
		(layer "In5.Cu")
		(net 937)
	)
	(segment
		(start 183.15 62.7)
		(end 182.25 63.6)
		(width 0.1)
		(layer "In5.Cu")
		(net 937)
	)
	(segment
		(start 126.6 64.4)
		(end 124.5 66.5)
		(width 0.1)
		(layer "In5.Cu")
		(net 937)
	)
	(segment
		(start 111.4 67.1)
		(end 104.9 67.1)
		(width 0.1)
		(layer "In5.Cu")
		(net 937)
	)
	(segment
		(start 72.6 66.131751)
		(end 72.6 65.9)
		(width 0.1)
		(layer "In5.Cu")
		(net 937)
	)
	(segment
		(start 84.434316 67.799998)
		(end 75.434316 67.799998)
		(width 0.1)
		(layer "In5.Cu")
		(net 937)
	)
	(segment
		(start 194.5 57.9)
		(end 189.7 62.7)
		(width 0.1)
		(layer "In5.Cu")
		(net 937)
	)
	(via
		(at 215.25 56.7)
		(size 0.45)
		(drill 0.1)
		(layers "F.Cu" "B.Cu")
		(net 938)
	)
	(via
		(at 73.7 67)
		(size 0.45)
		(drill 0.1)
		(layers "F.Cu" "B.Cu")
		(net 938)
	)
	(segment
		(start 72.2 64.3)
		(end 73.7 65.8)
		(width 0.1)
		(layer "B.Cu")
		(net 938)
	)
	(segment
		(start 214.157 57.243)
		(end 214.157 58.39)
		(width 0.1)
		(layer "B.Cu")
		(net 938)
	)
	(segment
		(start 214.7 56.7)
		(end 214.157 57.243)
		(width 0.1)
		(layer "B.Cu")
		(net 938)
	)
	(segment
		(start 73.7 65.8)
		(end 73.7 67)
		(width 0.1)
		(layer "B.Cu")
		(net 938)
	)
	(segment
		(start 215.25 56.7)
		(end 214.7 56.7)
		(width 0.1)
		(layer "B.Cu")
		(net 938)
	)
	(segment
		(start 71.58 64.3)
		(end 72.2 64.3)
		(width 0.1)
		(layer "B.Cu")
		(net 938)
	)
	(segment
		(start 74.068629 66.999999)
		(end 73.700001 66.999999)
		(width 0.1)
		(layer "In5.Cu")
		(net 938)
	)
	(segment
		(start 75.16863 68.1)
		(end 74.068629 66.999999)
		(width 0.1)
		(layer "In5.Cu")
		(net 938)
	)
	(segment
		(start 189.882843 63.082843)
		(end 183.467157 63.082843)
		(width 0.1)
		(layer "In5.Cu")
		(net 938)
	)
	(segment
		(start 147.5 68.6)
		(end 143.6 64.7)
		(width 0.1)
		(layer "In5.Cu")
		(net 938)
	)
	(segment
		(start 155.565686 68.6)
		(end 147.5 68.6)
		(width 0.1)
		(layer "In5.Cu")
		(net 938)
	)
	(segment
		(start 183.467157 63.082843)
		(end 182.65 63.9)
		(width 0.1)
		(layer "In5.Cu")
		(net 938)
	)
	(segment
		(start 126.7 64.7)
		(end 124.6 66.8)
		(width 0.1)
		(layer "In5.Cu")
		(net 938)
	)
	(segment
		(start 182.65 63.9)
		(end 160.265686 63.9)
		(width 0.1)
		(layer "In5.Cu")
		(net 938)
	)
	(segment
		(start 84.7 68.1)
		(end 75.16863 68.1)
		(width 0.1)
		(layer "In5.Cu")
		(net 938)
	)
	(segment
		(start 143.6 64.7)
		(end 126.7 64.7)
		(width 0.1)
		(layer "In5.Cu")
		(net 938)
	)
	(segment
		(start 124.6 66.8)
		(end 112.1 66.8)
		(width 0.1)
		(layer "In5.Cu")
		(net 938)
	)
	(segment
		(start 104.234314 67)
		(end 85.8 67)
		(width 0.1)
		(layer "In5.Cu")
		(net 938)
	)
	(segment
		(start 194.765686 58.2)
		(end 189.882843 63.082843)
		(width 0.1)
		(layer "In5.Cu")
		(net 938)
	)
	(segment
		(start 160.265686 63.9)
		(end 155.565686 68.6)
		(width 0.1)
		(layer "In5.Cu")
		(net 938)
	)
	(segment
		(start 104.634314 67.4)
		(end 104.234314 67)
		(width 0.1)
		(layer "In5.Cu")
		(net 938)
	)
	(segment
		(start 112.1 66.8)
		(end 111.5 67.4)
		(width 0.1)
		(layer "In5.Cu")
		(net 938)
	)
	(segment
		(start 73.700001 66.999999)
		(end 73.7 67)
		(width 0.1)
		(layer "In5.Cu")
		(net 938)
	)
	(segment
		(start 85.8 67)
		(end 84.7 68.1)
		(width 0.1)
		(layer "In5.Cu")
		(net 938)
	)
	(segment
		(start 212.2 58.2)
		(end 194.765686 58.2)
		(width 0.1)
		(layer "In5.Cu")
		(net 938)
	)
	(segment
		(start 111.5 67.4)
		(end 104.634314 67.4)
		(width 0.1)
		(layer "In5.Cu")
		(net 938)
	)
	(segment
		(start 215.25 56.7)
		(end 213.7 56.7)
		(width 0.1)
		(layer "In5.Cu")
		(net 938)
	)
	(segment
		(start 213.7 56.7)
		(end 212.2 58.2)
		(width 0.1)
		(layer "In5.Cu")
		(net 938)
	)
	(segment
		(start 191.677 83.7)
		(end 192.2 83.7)
		(width 0.1)
		(layer "F.Cu")
		(net 939)
	)
	(segment
		(start 196.3 80.2)
		(end 196.3 84.6)
		(width 0.1)
		(layer "F.Cu")
		(net 939)
	)
	(segment
		(start 192.4 83.9)
		(end 192.4 85.5)
		(width 0.1)
		(layer "F.Cu")
		(net 939)
	)
	(segment
		(start 196.3 84.6)
		(end 195.6 85.3)
		(width 0.1)
		(layer "F.Cu")
		(net 939)
	)
	(segment
		(start 196.619 79.881)
		(end 196.3 80.2)
		(width 0.1)
		(layer "F.Cu")
		(net 939)
	)
	(segment
		(start 197.249 79.881)
		(end 196.619 79.881)
		(width 0.1)
		(layer "F.Cu")
		(net 939)
	)
	(segment
		(start 192.2 83.7)
		(end 192.4 83.9)
		(width 0.1)
		(layer "F.Cu")
		(net 939)
	)
	(segment
		(start 195.2 85.7)
		(end 195.6 85.3)
		(width 0.1)
		(layer "F.Cu")
		(net 939)
	)
	(segment
		(start 192.6 85.7)
		(end 195.2 85.7)
		(width 0.1)
		(layer "F.Cu")
		(net 939)
	)
	(segment
		(start 192.4 85.5)
		(end 192.6 85.7)
		(width 0.1)
		(layer "F.Cu")
		(net 939)
	)
	(via
		(at 195.6 85.3)
		(size 0.45)
		(drill 0.1)
		(layers "F.Cu" "B.Cu")
		(net 939)
	)
	(segment
		(start 197 86.8)
		(end 197 87.32)
		(width 0.1)
		(layer "B.Cu")
		(net 939)
	)
	(segment
		(start 195.6 85.3)
		(end 195.6 85.4)
		(width 0.1)
		(layer "B.Cu")
		(net 939)
	)
	(segment
		(start 195.6 85.4)
		(end 197 86.8)
		(width 0.1)
		(layer "B.Cu")
		(net 939)
	)
	(segment
		(start 193.798 85.198)
		(end 194.226 85.198)
		(width 0.1)
		(layer "F.Cu")
		(net 940)
	)
	(segment
		(start 195.2 81.6)
		(end 193.2 81.6)
		(width 0.1)
		(layer "F.Cu")
		(net 940)
	)
	(segment
		(start 193.6 85)
		(end 193.798 85.198)
		(width 0.1)
		(layer "F.Cu")
		(net 940)
	)
	(segment
		(start 194.898 85.198)
		(end 195 85.3)
		(width 0.1)
		(layer "F.Cu")
		(net 940)
	)
	(segment
		(start 194.226 85.198)
		(end 194.898 85.198)
		(width 0.1)
		(layer "F.Cu")
		(net 940)
	)
	(segment
		(start 196.72 79.08)
		(end 195.9 79.9)
		(width 0.1)
		(layer "F.Cu")
		(net 940)
	)
	(segment
		(start 192.7 82.1)
		(end 192.7 82.9)
		(width 0.1)
		(layer "F.Cu")
		(net 940)
	)
	(segment
		(start 193.2 81.6)
		(end 192.7 82.1)
		(width 0.1)
		(layer "F.Cu")
		(net 940)
	)
	(segment
		(start 192.7 82.9)
		(end 193.6 83.8)
		(width 0.1)
		(layer "F.Cu")
		(net 940)
	)
	(segment
		(start 197.249 79.08)
		(end 196.72 79.08)
		(width 0.1)
		(layer "F.Cu")
		(net 940)
	)
	(segment
		(start 195.5 80.1)
		(end 195.5 81.3)
		(width 0.1)
		(layer "F.Cu")
		(net 940)
	)
	(segment
		(start 193.6 83.8)
		(end 193.6 85)
		(width 0.1)
		(layer "F.Cu")
		(net 940)
	)
	(segment
		(start 195.5 81.3)
		(end 195.2 81.6)
		(width 0.1)
		(layer "F.Cu")
		(net 940)
	)
	(segment
		(start 195.7 79.9)
		(end 195.5 80.1)
		(width 0.1)
		(layer "F.Cu")
		(net 940)
	)
	(segment
		(start 195.9 79.9)
		(end 195.7 79.9)
		(width 0.1)
		(layer "F.Cu")
		(net 940)
	)
	(via
		(at 195 85.3)
		(size 0.45)
		(drill 0.1)
		(layers "F.Cu" "B.Cu")
		(net 940)
	)
	(segment
		(start 195 85.7)
		(end 195.9 86.6)
		(width 0.1)
		(layer "B.Cu")
		(net 940)
	)
	(segment
		(start 195 85.3)
		(end 195 85.7)
		(width 0.1)
		(layer "B.Cu")
		(net 940)
	)
	(segment
		(start 195.9 86.6)
		(end 195.9 87.32)
		(width 0.1)
		(layer "B.Cu")
		(net 940)
	)
	(segment
		(start 195.85 80.25)
		(end 196.62 79.48)
		(width 0.1)
		(layer "F.Cu")
		(net 941)
	)
	(segment
		(start 195.302 84.698)
		(end 195.4 84.6)
		(width 0.1)
		(layer "F.Cu")
		(net 941)
	)
	(segment
		(start 195.4 84.6)
		(end 195.4 84)
		(width 0.1)
		(layer "F.Cu")
		(net 941)
	)
	(segment
		(start 195.4 84)
		(end 195.4 83.15)
		(width 0.1)
		(layer "F.Cu")
		(net 941)
	)
	(segment
		(start 196.62 79.48)
		(end 197.249 79.48)
		(width 0.1)
		(layer "F.Cu")
		(net 941)
	)
	(segment
		(start 195.4 83.15)
		(end 195.85 82.7)
		(width 0.1)
		(layer "F.Cu")
		(net 941)
	)
	(segment
		(start 195.85 82.7)
		(end 195.85 80.25)
		(width 0.1)
		(layer "F.Cu")
		(net 941)
	)
	(segment
		(start 194.226 84.698)
		(end 195.302 84.698)
		(width 0.1)
		(layer "F.Cu")
		(net 941)
	)
	(via
		(at 195.4 84)
		(size 0.45)
		(drill 0.1)
		(layers "F.Cu" "B.Cu")
		(net 941)
	)
	(segment
		(start 194.8 86.500001)
		(end 194.8 87.32)
		(width 0.1)
		(layer "B.Cu")
		(net 941)
	)
	(segment
		(start 194.4 86.100001)
		(end 194.8 86.500001)
		(width 0.1)
		(layer "B.Cu")
		(net 941)
	)
	(segment
		(start 195.4 84)
		(end 194.4 85)
		(width 0.1)
		(layer "B.Cu")
		(net 941)
	)
	(segment
		(start 194.4 85)
		(end 194.4 86.100001)
		(width 0.1)
		(layer "B.Cu")
		(net 941)
	)
	(segment
		(start 213.065632 92.670856)
		(end 213.065632 93.034368)
		(width 0.1)
		(layer "F.Cu")
		(net 942)
	)
	(segment
		(start 211.973 93.627)
		(end 212.4 93.2)
		(width 0.1)
		(layer "F.Cu")
		(net 942)
	)
	(segment
		(start 212.9 93.2)
		(end 212.4 93.2)
		(width 0.1)
		(layer "F.Cu")
		(net 942)
	)
	(segment
		(start 202.801 74.5)
		(end 202.801 75.13)
		(width 0.1)
		(layer "F.Cu")
		(net 942)
	)
	(segment
		(start 210.594132 93.627)
		(end 211.973 93.627)
		(width 0.1)
		(layer "F.Cu")
		(net 942)
	)
	(segment
		(start 213.065632 93.034368)
		(end 212.9 93.2)
		(width 0.1)
		(layer "F.Cu")
		(net 942)
	)
	(via
		(at 202.801 74.5)
		(size 0.45)
		(drill 0.1)
		(layers "F.Cu" "B.Cu")
		(net 942)
	)
	(via
		(at 212.4 93.2)
		(size 0.45)
		(drill 0.1)
		(layers "F.Cu" "B.Cu")
		(net 942)
	)
	(segment
		(start 202.851471 86.199999)
		(end 208.451472 91.8)
		(width 0.1)
		(layer "In5.Cu")
		(net 942)
	)
	(segment
		(start 211.9 91.8)
		(end 212.4 92.3)
		(width 0.1)
		(layer "In5.Cu")
		(net 942)
	)
	(segment
		(start 202.8 74.499)
		(end 202.8 73.6)
		(width 0.1)
		(layer "In5.Cu")
		(net 942)
	)
	(segment
		(start 202.801 74.5)
		(end 202.8 74.499)
		(width 0.1)
		(layer "In5.Cu")
		(net 942)
	)
	(segment
		(start 208.451472 91.8)
		(end 211.9 91.8)
		(width 0.1)
		(layer "In5.Cu")
		(net 942)
	)
	(segment
		(start 196.751472 73.200002)
		(end 195.500002 74.451472)
		(width 0.1)
		(layer "In5.Cu")
		(net 942)
	)
	(segment
		(start 202.8 73.6)
		(end 202.400002 73.200002)
		(width 0.1)
		(layer "In5.Cu")
		(net 942)
	)
	(segment
		(start 195.500002 74.451472)
		(end 195.500002 75.748528)
		(width 0.1)
		(layer "In5.Cu")
		(net 942)
	)
	(segment
		(start 197.751473 86.199999)
		(end 202.851471 86.199999)
		(width 0.1)
		(layer "In5.Cu")
		(net 942)
	)
	(segment
		(start 212.4 92.3)
		(end 212.4 93.2)
		(width 0.1)
		(layer "In5.Cu")
		(net 942)
	)
	(segment
		(start 202.400002 73.200002)
		(end 196.751472 73.200002)
		(width 0.1)
		(layer "In5.Cu")
		(net 942)
	)
	(segment
		(start 195.500002 75.748528)
		(end 196.700002 76.948528)
		(width 0.1)
		(layer "In5.Cu")
		(net 942)
	)
	(segment
		(start 196.700002 76.948528)
		(end 196.700002 85.148528)
		(width 0.1)
		(layer "In5.Cu")
		(net 942)
	)
	(segment
		(start 196.700002 85.148528)
		(end 197.751473 86.199999)
		(width 0.1)
		(layer "In5.Cu")
		(net 942)
	)
	(segment
		(start 202.4 75.13)
		(end 202.4 74.147183)
		(width 0.1)
		(layer "F.Cu")
		(net 943)
	)
	(segment
		(start 213.1 93.6)
		(end 212.9 93.6)
		(width 0.1)
		(layer "F.Cu")
		(net 943)
	)
	(segment
		(start 211.858 94.642)
		(end 212.9 93.6)
		(width 0.1)
		(layer "F.Cu")
		(net 943)
	)
	(segment
		(start 202.4 74.147183)
		(end 202.388745 74.135928)
		(width 0.1)
		(layer "F.Cu")
		(net 943)
	)
	(segment
		(start 210.594132 94.642)
		(end 211.858 94.642)
		(width 0.1)
		(layer "F.Cu")
		(net 943)
	)
	(segment
		(start 213.465632 92.934368)
		(end 213.4 93)
		(width 0.1)
		(layer "F.Cu")
		(net 943)
	)
	(segment
		(start 213.4 93)
		(end 213.4 93.3)
		(width 0.1)
		(layer "F.Cu")
		(net 943)
	)
	(segment
		(start 213.465632 92.670856)
		(end 213.465632 92.934368)
		(width 0.1)
		(layer "F.Cu")
		(net 943)
	)
	(segment
		(start 213.4 93.3)
		(end 213.1 93.6)
		(width 0.1)
		(layer "F.Cu")
		(net 943)
	)
	(via
		(at 202.388745 74.135928)
		(size 0.45)
		(drill 0.1)
		(layers "F.Cu" "B.Cu")
		(net 943)
	)
	(via
		(at 212.9 93.6)
		(size 0.45)
		(drill 0.1)
		(layers "F.Cu" "B.Cu")
		(net 943)
	)
	(segment
		(start 202.975735 85.899999)
		(end 208.575736 91.5)
		(width 0.1)
		(layer "In5.Cu")
		(net 943)
	)
	(segment
		(start 197.875737 85.899999)
		(end 202.975735 85.899999)
		(width 0.1)
		(layer "In5.Cu")
		(net 943)
	)
	(segment
		(start 197.000002 85.024264)
		(end 197.875737 85.899999)
		(width 0.1)
		(layer "In5.Cu")
		(net 943)
	)
	(segment
		(start 212.2 91.5)
		(end 212.9 92.2)
		(width 0.1)
		(layer "In5.Cu")
		(net 943)
	)
	(segment
		(start 202.388745 73.988745)
		(end 201.900002 73.500002)
		(width 0.1)
		(layer "In5.Cu")
		(net 943)
	)
	(segment
		(start 208.575736 91.5)
		(end 212.2 91.5)
		(width 0.1)
		(layer "In5.Cu")
		(net 943)
	)
	(segment
		(start 201.900002 73.500002)
		(end 196.875736 73.500002)
		(width 0.1)
		(layer "In5.Cu")
		(net 943)
	)
	(segment
		(start 202.388745 74.135928)
		(end 202.388745 73.988745)
		(width 0.1)
		(layer "In5.Cu")
		(net 943)
	)
	(segment
		(start 195.800002 74.575736)
		(end 195.800002 75.624264)
		(width 0.1)
		(layer "In5.Cu")
		(net 943)
	)
	(segment
		(start 196.875736 73.500002)
		(end 195.800002 74.575736)
		(width 0.1)
		(layer "In5.Cu")
		(net 943)
	)
	(segment
		(start 212.9 92.2)
		(end 212.9 93.6)
		(width 0.1)
		(layer "In5.Cu")
		(net 943)
	)
	(segment
		(start 195.800002 75.624264)
		(end 197.000002 76.824264)
		(width 0.1)
		(layer "In5.Cu")
		(net 943)
	)
	(segment
		(start 197.000002 76.824264)
		(end 197.000002 85.024264)
		(width 0.1)
		(layer "In5.Cu")
		(net 943)
	)
	(segment
		(start 202 74.516021)
		(end 201.945389 74.46141)
		(width 0.1)
		(layer "F.Cu")
		(net 944)
	)
	(segment
		(start 213.865632 93.134368)
		(end 213.8 93.2)
		(width 0.1)
		(layer "F.Cu")
		(net 944)
	)
	(segment
		(start 213.865632 92.670856)
		(end 213.865632 93.134368)
		(width 0.1)
		(layer "F.Cu")
		(net 944)
	)
	(segment
		(start 202 75.13)
		(end 202 74.516021)
		(width 0.1)
		(layer "F.Cu")
		(net 944)
	)
	(via
		(at 213.8 93.2)
		(size 0.45)
		(drill 0.1)
		(layers "F.Cu" "B.Cu")
		(net 944)
	)
	(via
		(at 201.945389 74.46141)
		(size 0.45)
		(drill 0.1)
		(layers "F.Cu" "B.Cu")
		(net 944)
	)
	(segment
		(start 198.355745 85.676)
		(end 198.431745 85.6)
		(width 0.1)
		(layer "In5.Cu")
		(net 944)
	)
	(segment
		(start 202 74.4)
		(end 201.4 73.8)
		(width 0.1)
		(layer "In5.Cu")
		(net 944)
	)
	(segment
		(start 203.1 85.6)
		(end 208.7 91.2)
		(width 0.1)
		(layer "In5.Cu")
		(net 944)
	)
	(segment
		(start 197.3 84.9)
		(end 197.824 85.424)
		(width 0.1)
		(layer "In5.Cu")
		(net 944)
	)
	(segment
		(start 198.431745 85.6)
		(end 198.968255 85.6)
		(width 0.1)
		(layer "In5.Cu")
		(net 944)
	)
	(segment
		(start 199.355745 85.676)
		(end 199.431745 85.6)
		(width 0.1)
		(layer "In5.Cu")
		(net 944)
	)
	(segment
		(start 197.824 85.424)
		(end 197.824 85.455745)
		(width 0.1)
		(layer "In5.Cu")
		(net 944)
	)
	(segment
		(start 197 73.8)
		(end 196.1 74.7)
		(width 0.1)
		(layer "In5.Cu")
		(net 944)
	)
	(segment
		(start 202 74.406799)
		(end 202 74.4)
		(width 0.1)
		(layer "In5.Cu")
		(net 944)
	)
	(segment
		(start 198.044255 85.676)
		(end 198.355745 85.676)
		(width 0.1)
		(layer "In5.Cu")
		(net 944)
	)
	(segment
		(start 197.3 76.7)
		(end 197.3 84.9)
		(width 0.1)
		(layer "In5.Cu")
		(net 944)
	)
	(segment
		(start 201.945389 74.46141)
		(end 202 74.406799)
		(width 0.1)
		(layer "In5.Cu")
		(net 944)
	)
	(segment
		(start 199.044255 85.676)
		(end 199.355745 85.676)
		(width 0.1)
		(layer "In5.Cu")
		(net 944)
	)
	(segment
		(start 208.7 91.2)
		(end 212.8 91.2)
		(width 0.1)
		(layer "In5.Cu")
		(net 944)
	)
	(segment
		(start 198.968255 85.6)
		(end 199.044255 85.676)
		(width 0.1)
		(layer "In5.Cu")
		(net 944)
	)
	(segment
		(start 199.431745 85.6)
		(end 203.1 85.6)
		(width 0.1)
		(layer "In5.Cu")
		(net 944)
	)
	(segment
		(start 197.824 85.455745)
		(end 198.044255 85.676)
		(width 0.1)
		(layer "In5.Cu")
		(net 944)
	)
	(segment
		(start 201.4 73.8)
		(end 197 73.8)
		(width 0.1)
		(layer "In5.Cu")
		(net 944)
	)
	(segment
		(start 196.1 75.5)
		(end 197.3 76.7)
		(width 0.1)
		(layer "In5.Cu")
		(net 944)
	)
	(segment
		(start 212.8 91.2)
		(end 213.8 92.2)
		(width 0.1)
		(layer "In5.Cu")
		(net 944)
	)
	(segment
		(start 213.8 92.2)
		(end 213.8 93.2)
		(width 0.1)
		(layer "In5.Cu")
		(net 944)
	)
	(segment
		(start 196.1 74.7)
		(end 196.1 75.5)
		(width 0.1)
		(layer "In5.Cu")
		(net 944)
	)
	(segment
		(start 210.45 80.25)
		(end 210.45 80.55)
		(width 0.1)
		(layer "F.Cu")
		(net 945)
	)
	(segment
		(start 198.3 74.502)
		(end 198.399 74.601)
		(width 0.1)
		(layer "F.Cu")
		(net 945)
	)
	(segment
		(start 209.6 80.9)
		(end 209.1 80.4)
		(width 0.1)
		(layer "F.Cu")
		(net 945)
	)
	(segment
		(start 210.1 80.9)
		(end 209.6 80.9)
		(width 0.1)
		(layer "F.Cu")
		(net 945)
	)
	(segment
		(start 210.1 80.9)
		(end 210.45 80.55)
		(width 0.1)
		(layer "F.Cu")
		(net 945)
	)
	(segment
		(start 198.3 74.5)
		(end 198.3 74.502)
		(width 0.1)
		(layer "F.Cu")
		(net 945)
	)
	(segment
		(start 198.399 74.601)
		(end 198.399 75.13)
		(width 0.1)
		(layer "F.Cu")
		(net 945)
	)
	(segment
		(start 209.1 80.4)
		(end 209.1 79.1)
		(width 0.1)
		(layer "F.Cu")
		(net 945)
	)
	(segment
		(start 198.1 74.3)
		(end 198.3 74.5)
		(width 0.1)
		(layer "F.Cu")
		(net 945)
	)
	(via
		(at 198.1 74.3)
		(size 0.45)
		(drill 0.1)
		(layers "F.Cu" "B.Cu")
		(net 945)
	)
	(via
		(at 209.1 79.1)
		(size 0.45)
		(drill 0.1)
		(layers "F.Cu" "B.Cu")
		(net 945)
	)
	(segment
		(start 198.3 73.75)
		(end 198.3 73.5)
		(width 0.1)
		(layer "B.Cu")
		(net 945)
	)
	(segment
		(start 198.9 73.5)
		(end 199 73.6)
		(width 0.1)
		(layer "B.Cu")
		(net 945)
	)
	(segment
		(start 198.7 72.9)
		(end 198.7 71.18)
		(width 0.1)
		(layer "B.Cu")
		(net 945)
	)
	(segment
		(start 198.3 73.3)
		(end 198.7 72.9)
		(width 0.1)
		(layer "B.Cu")
		(net 945)
	)
	(segment
		(start 198.1 73.95)
		(end 198.3 73.75)
		(width 0.1)
		(layer "B.Cu")
		(net 945)
	)
	(segment
		(start 198.3 73.5)
		(end 198.3 73.3)
		(width 0.1)
		(layer "B.Cu")
		(net 945)
	)
	(segment
		(start 198.3 73.5)
		(end 198.9 73.5)
		(width 0.1)
		(layer "B.Cu")
		(net 945)
	)
	(segment
		(start 198.7 71.18)
		(end 198.6 71.08)
		(width 0.1)
		(layer "B.Cu")
		(net 945)
	)
	(segment
		(start 198.1 74.3)
		(end 198.1 73.95)
		(width 0.1)
		(layer "B.Cu")
		(net 945)
	)
	(segment
		(start 199.6 71.08)
		(end 198.6 71.08)
		(width 0.1)
		(layer "B.Cu")
		(net 945)
	)
	(segment
		(start 207.169669 79.1)
		(end 206.569669 78.5)
		(width 0.1)
		(layer "In5.Cu")
		(net 945)
	)
	(segment
		(start 201.6 78.5)
		(end 200.8 77.7)
		(width 0.1)
		(layer "In5.Cu")
		(net 945)
	)
	(segment
		(start 197.7 77.2)
		(end 197.7 75.9)
		(width 0.1)
		(layer "In5.Cu")
		(net 945)
	)
	(segment
		(start 197.1 75.3)
		(end 197.1 74.2)
		(width 0.1)
		(layer "In5.Cu")
		(net 945)
	)
	(segment
		(start 197.1 74.2)
		(end 197.3 74)
		(width 0.1)
		(layer "In5.Cu")
		(net 945)
	)
	(segment
		(start 198.2 77.7)
		(end 197.7 77.2)
		(width 0.1)
		(layer "In5.Cu")
		(net 945)
	)
	(segment
		(start 209.1 79.1)
		(end 207.169669 79.1)
		(width 0.1)
		(layer "In5.Cu")
		(net 945)
	)
	(segment
		(start 197.3 74)
		(end 197.8 74)
		(width 0.1)
		(layer "In5.Cu")
		(net 945)
	)
	(segment
		(start 200.8 77.7)
		(end 198.2 77.7)
		(width 0.1)
		(layer "In5.Cu")
		(net 945)
	)
	(segment
		(start 197.8 74)
		(end 198.1 74.3)
		(width 0.1)
		(layer "In5.Cu")
		(net 945)
	)
	(segment
		(start 197.7 75.9)
		(end 197.1 75.3)
		(width 0.1)
		(layer "In5.Cu")
		(net 945)
	)
	(segment
		(start 206.569669 78.5)
		(end 201.6 78.5)
		(width 0.1)
		(layer "In5.Cu")
		(net 945)
	)
	(segment
		(start 210.2 78.7)
		(end 210.45 78.95)
		(width 0.1)
		(layer "F.Cu")
		(net 946)
	)
	(segment
		(start 197.5 74.4)
		(end 197.999 74.899)
		(width 0.1)
		(layer "F.Cu")
		(net 946)
	)
	(segment
		(start 210.2 78.7)
		(end 209.6 78.7)
		(width 0.1)
		(layer "F.Cu")
		(net 946)
	)
	(segment
		(start 197.999 74.899)
		(end 197.999 75.13)
		(width 0.1)
		(layer "F.Cu")
		(net 946)
	)
	(segment
		(start 210.45 79.35)
		(end 210.45 78.95)
		(width 0.1)
		(layer "F.Cu")
		(net 946)
	)
	(via
		(at 197.5 74.4)
		(size 0.45)
		(drill 0.1)
		(layers "F.Cu" "B.Cu")
		(net 946)
	)
	(via
		(at 209.6 78.7)
		(size 0.45)
		(drill 0.1)
		(layers "F.Cu" "B.Cu")
		(net 946)
	)
	(segment
		(start 197.5 74.4)
		(end 197 74.4)
		(width 0.1)
		(layer "B.Cu")
		(net 946)
	)
	(segment
		(start 197 74.4)
		(end 196.6 74)
		(width 0.1)
		(layer "B.Cu")
		(net 946)
	)
	(segment
		(start 197.5 74.4)
		(end 197.5 73.62)
		(width 0.1)
		(layer "B.Cu")
		(net 946)
	)
	(segment
		(start 196.6 71.08)
		(end 197.6 71.08)
		(width 0.1)
		(layer "B.Cu")
		(net 946)
	)
	(segment
		(start 196.6 74)
		(end 196.6 71.08)
		(width 0.1)
		(layer "B.Cu")
		(net 946)
	)
	(segment
		(start 208.2 78.7)
		(end 209.6 78.7)
		(width 0.1)
		(layer "In5.Cu")
		(net 946)
	)
	(segment
		(start 199 76.6)
		(end 203.8 76.6)
		(width 0.1)
		(layer "In5.Cu")
		(net 946)
	)
	(segment
		(start 197.5 74.4)
		(end 197.5 75.1)
		(width 0.1)
		(layer "In5.Cu")
		(net 946)
	)
	(segment
		(start 203.8 76.6)
		(end 204.1 76.9)
		(width 0.1)
		(layer "In5.Cu")
		(net 946)
	)
	(segment
		(start 204.1 76.9)
		(end 206.4 76.9)
		(width 0.1)
		(layer "In5.Cu")
		(net 946)
	)
	(segment
		(start 197.5 75.1)
		(end 199 76.6)
		(width 0.1)
		(layer "In5.Cu")
		(net 946)
	)
	(segment
		(start 206.4 76.9)
		(end 208.2 78.7)
		(width 0.1)
		(layer "In5.Cu")
		(net 946)
	)
	(segment
		(start 193 79.8)
		(end 193 78.8)
		(width 0.1)
		(layer "F.Cu")
		(net 947)
	)
	(segment
		(start 191.8 80.6815)
		(end 192.1185 80.6815)
		(width 0.1)
		(layer "F.Cu")
		(net 947)
	)
	(segment
		(start 194.718 77.082)
		(end 197.249 77.082)
		(width 0.1)
		(layer "F.Cu")
		(net 947)
	)
	(segment
		(start 192.1185 80.6815)
		(end 193 79.8)
		(width 0.1)
		(layer "F.Cu")
		(net 947)
	)
	(segment
		(start 191.0815 81.4)
		(end 191.8 80.6815)
		(width 0.1)
		(layer "F.Cu")
		(net 947)
	)
	(segment
		(start 193 78.8)
		(end 194.718 77.082)
		(width 0.1)
		(layer "F.Cu")
		(net 947)
	)
	(segment
		(start 191.08 81.4)
		(end 191.0815 81.4)
		(width 0.1)
		(layer "F.Cu")
		(net 947)
	)
	(via
		(at 191.8 80.6815)
		(size 0.45)
		(drill 0.1)
		(layers "F.Cu" "B.Cu")
		(net 947)
	)
	(via
		(at 215.6 96.4)
		(size 0.45)
		(drill 0.1)
		(layers "F.Cu" "B.Cu")
		(net 948)
	)
	(via
		(at 194.8 76.6)
		(size 0.45)
		(drill 0.1)
		(layers "F.Cu" "B.Cu")
		(net 948)
	)
	(segment
		(start 195.084127 76.384127)
		(end 195 76.468255)
		(width 0.1)
		(layer "B.Cu")
		(net 948)
	)
	(segment
		(start 195.244255 76.224)
		(end 195.084127 76.384127)
		(width 0.1)
		(layer "B.Cu")
		(net 948)
	)
	(segment
		(start 195.244255 76.224)
		(end 195.56777 76.224)
		(width 0.1)
		(layer "B.Cu")
		(net 948)
	)
	(segment
		(start 195 76.468255)
		(end 195 76.5)
		(width 0.1)
		(layer "B.Cu")
		(net 948)
	)
	(segment
		(start 196.689 76.689)
		(end 196.03277 76.689)
		(width 0.1)
		(layer "B.Cu")
		(net 948)
	)
	(segment
		(start 215.93 95.58)
		(end 215.93 96.07)
		(width 0.1)
		(layer "B.Cu")
		(net 948)
	)
	(segment
		(start 197.16 77.16)
		(end 196.689 76.689)
		(width 0.1)
		(layer "B.Cu")
		(net 948)
	)
	(segment
		(start 215.93 96.07)
		(end 215.6 96.4)
		(width 0.1)
		(layer "B.Cu")
		(net 948)
	)
	(segment
		(start 195.015873 76.384127)
		(end 194.8 76.6)
		(width 0.1)
		(layer "B.Cu")
		(net 948)
	)
	(segment
		(start 196.03277 76.689)
		(end 195.56777 76.224)
		(width 0.1)
		(layer "B.Cu")
		(net 948)
	)
	(segment
		(start 195.084127 76.384127)
		(end 195.015873 76.384127)
		(width 0.1)
		(layer "B.Cu")
		(net 948)
	)
	(segment
		(start 212.35 95.5)
		(end 214.7 95.5)
		(width 0.1)
		(layer "In5.Cu")
		(net 948)
	)
	(segment
		(start 204.55 93.45)
		(end 205.25 92.75)
		(width 0.1)
		(layer "In5.Cu")
		(net 948)
	)
	(segment
		(start 194.8 76.6)
		(end 194.8 77.3)
		(width 0.1)
		(layer "In5.Cu")
		(net 948)
	)
	(segment
		(start 205.25 92.75)
		(end 209.6 92.75)
		(width 0.1)
		(layer "In5.Cu")
		(net 948)
	)
	(segment
		(start 214.7 95.5)
		(end 215.6 96.4)
		(width 0.1)
		(layer "In5.Cu")
		(net 948)
	)
	(segment
		(start 203.05 93.45)
		(end 204.55 93.45)
		(width 0.1)
		(layer "In5.Cu")
		(net 948)
	)
	(segment
		(start 196.3 78.8)
		(end 196.3 86.7)
		(width 0.1)
		(layer "In5.Cu")
		(net 948)
	)
	(segment
		(start 196.3 86.7)
		(end 203.05 93.45)
		(width 0.1)
		(layer "In5.Cu")
		(net 948)
	)
	(segment
		(start 194.8 77.3)
		(end 196.3 78.8)
		(width 0.1)
		(layer "In5.Cu")
		(net 948)
	)
	(segment
		(start 209.6 92.75)
		(end 212.35 95.5)
		(width 0.1)
		(layer "In5.Cu")
		(net 948)
	)
	(segment
		(start 197.249 76.68)
		(end 195.48 76.68)
		(width 0.1)
		(layer "F.Cu")
		(net 949)
	)
	(segment
		(start 195.48 76.68)
		(end 195.4 76.6)
		(width 0.1)
		(layer "F.Cu")
		(net 949)
	)
	(via
		(at 195.4 76.6)
		(size 0.45)
		(drill 0.1)
		(layers "F.Cu" "B.Cu")
		(net 949)
	)
	(segment
		(start 195.56 77.16)
		(end 195.4 77)
		(width 0.1)
		(layer "B.Cu")
		(net 949)
	)
	(segment
		(start 196.2 77.16)
		(end 195.56 77.16)
		(width 0.1)
		(layer "B.Cu")
		(net 949)
	)
	(segment
		(start 195.4 77)
		(end 195.4 76.6)
		(width 0.1)
		(layer "B.Cu")
		(net 949)
	)
	(segment
		(start 193.28 80.6815)
		(end 193.28 79.12)
		(width 0.1)
		(layer "F.Cu")
		(net 950)
	)
	(segment
		(start 192.1 81.8)
		(end 192.1 81.4)
		(width 0.1)
		(layer "F.Cu")
		(net 950)
	)
	(segment
		(start 192.8185 80.6815)
		(end 193.28 80.6815)
		(width 0.1)
		(layer "F.Cu")
		(net 950)
	)
	(segment
		(start 191.5 82.4)
		(end 192.1 81.8)
		(width 0.1)
		(layer "F.Cu")
		(net 950)
	)
	(segment
		(start 191.08 82.4)
		(end 191.5 82.4)
		(width 0.1)
		(layer "F.Cu")
		(net 950)
	)
	(segment
		(start 193.28 79.12)
		(end 194.918 77.482)
		(width 0.1)
		(layer "F.Cu")
		(net 950)
	)
	(segment
		(start 194.918 77.482)
		(end 197.249 77.482)
		(width 0.1)
		(layer "F.Cu")
		(net 950)
	)
	(segment
		(start 192.1 81.4)
		(end 192.8185 80.6815)
		(width 0.1)
		(layer "F.Cu")
		(net 950)
	)
	(via
		(at 193.28 80.6815)
		(size 0.45)
		(drill 0.1)
		(layers "F.Cu" "B.Cu")
		(net 950)
	)
	(segment
		(start 196.6 81.2)
		(end 196.6 84.8)
		(width 0.1)
		(layer "F.Cu")
		(net 951)
	)
	(segment
		(start 196.35 85.05)
		(end 196.6 84.8)
		(width 0.1)
		(layer "F.Cu")
		(net 951)
	)
	(segment
		(start 196.719 81.081)
		(end 196.6 81.2)
		(width 0.1)
		(layer "F.Cu")
		(net 951)
	)
	(segment
		(start 197.249 81.081)
		(end 196.719 81.081)
		(width 0.1)
		(layer "F.Cu")
		(net 951)
	)
	(segment
		(start 196.35 85.44)
		(end 196.35 85.05)
		(width 0.1)
		(layer "F.Cu")
		(net 951)
	)
	(segment
		(start 197.999 82.401)
		(end 197.999 81.831)
		(width 0.1)
		(layer "F.Cu")
		(net 952)
	)
	(segment
		(start 197.38 83.02)
		(end 197.999 82.401)
		(width 0.1)
		(layer "F.Cu")
		(net 952)
	)
	(segment
		(start 197.38 85.44)
		(end 197.38 83.02)
		(width 0.1)
		(layer "F.Cu")
		(net 952)
	)
	(segment
		(start 196.6 75.2)
		(end 196.7 75.3)
		(width 0.1)
		(layer "F.Cu")
		(net 953)
	)
	(segment
		(start 197.249 75.88)
		(end 196.78 75.88)
		(width 0.1)
		(layer "F.Cu")
		(net 953)
	)
	(segment
		(start 196.6 73.98)
		(end 196.6 75.2)
		(width 0.1)
		(layer "F.Cu")
		(net 953)
	)
	(segment
		(start 196.7 75.8)
		(end 196.7 75.3)
		(width 0.1)
		(layer "F.Cu")
		(net 953)
	)
	(segment
		(start 196.78 75.88)
		(end 196.7 75.8)
		(width 0.1)
		(layer "F.Cu")
		(net 953)
	)
	(via
		(at 196.7 75.3)
		(size 0.45)
		(drill 0.1)
		(layers "F.Cu" "B.Cu")
		(net 953)
	)
	(segment
		(start 197.05 75.3)
		(end 196.7 75.3)
		(width 0.1)
		(layer "B.Cu")
		(net 953)
	)
	(segment
		(start 197.15 75.4)
		(end 197.05 75.3)
		(width 0.1)
		(layer "B.Cu")
		(net 953)
	)
	(segment
		(start 197.15 76.1)
		(end 197.15 75.4)
		(width 0.1)
		(layer "B.Cu")
		(net 953)
	)
	(segment
		(start 158.4 99.2)
		(end 158.6 99)
		(width 0.1)
		(layer "F.Cu")
		(net 954)
	)
	(segment
		(start 151.2 102.7)
		(end 150.1 102.7)
		(width 0.1)
		(layer "F.Cu")
		(net 954)
	)
	(segment
		(start 151.675 102.61)
		(end 151.29 102.61)
		(width 0.1)
		(layer "F.Cu")
		(net 954)
	)
	(segment
		(start 150.1 102.7)
		(end 149.75 102.35)
		(width 0.1)
		(layer "F.Cu")
		(net 954)
	)
	(segment
		(start 158.6 99)
		(end 160.4 99)
		(width 0.1)
		(layer "F.Cu")
		(net 954)
	)
	(segment
		(start 151.29 102.61)
		(end 151.2 102.7)
		(width 0.1)
		(layer "F.Cu")
		(net 954)
	)
	(via
		(at 149.75 102.35)
		(size 0.45)
		(drill 0.1)
		(layers "F.Cu" "B.Cu")
		(net 954)
	)
	(via
		(at 192.2 88.4)
		(size 0.45)
		(drill 0.1)
		(layers "F.Cu" "B.Cu")
		(net 954)
	)
	(via
		(at 192.3 75.2)
		(size 0.45)
		(drill 0.1)
		(layers "F.Cu" "B.Cu")
		(net 954)
	)
	(via
		(at 158.4 99.2)
		(size 0.45)
		(drill 0.1)
		(layers "F.Cu" "B.Cu")
		(net 954)
	)
	(via
		(at 160.4 99)
		(size 0.45)
		(drill 0.1)
		(layers "F.Cu" "B.Cu")
		(net 954)
	)
	(segment
		(start 152 102.7)
		(end 154.3 100.4)
		(width 0.1)
		(layer "B.Cu")
		(net 954)
	)
	(segment
		(start 154.3 100.4)
		(end 154.3 98.3)
		(width 0.1)
		(layer "B.Cu")
		(net 954)
	)
	(segment
		(start 157.1 97.9)
		(end 158.4 99.2)
		(width 0.1)
		(layer "B.Cu")
		(net 954)
	)
	(segment
		(start 149.75 102.35)
		(end 150.1 102.7)
		(width 0.1)
		(layer "B.Cu")
		(net 954)
	)
	(segment
		(start 196.19 75.49)
		(end 196.19 76.1)
		(width 0.1)
		(layer "B.Cu")
		(net 954)
	)
	(segment
		(start 192.3 75.2)
		(end 195.9 75.2)
		(width 0.1)
		(layer "B.Cu")
		(net 954)
	)
	(segment
		(start 191.7 86)
		(end 192.6 86)
		(width 0.1)
		(layer "B.Cu")
		(net 954)
	)
	(segment
		(start 150.1 102.7)
		(end 151.7 102.7)
		(width 0.1)
		(layer "B.Cu")
		(net 954)
	)
	(segment
		(start 195.9 75.2)
		(end 196.19 75.49)
		(width 0.1)
		(layer "B.Cu")
		(net 954)
	)
	(segment
		(start 154.7 97.9)
		(end 157.1 97.9)
		(width 0.1)
		(layer "B.Cu")
		(net 954)
	)
	(segment
		(start 151.7 102.7)
		(end 152 102.7)
		(width 0.1)
		(layer "B.Cu")
		(net 954)
	)
	(segment
		(start 187.7 90)
		(end 191.7 86)
		(width 0.1)
		(layer "B.Cu")
		(net 954)
	)
	(segment
		(start 192.89 87.71)
		(end 192.2 88.4)
		(width 0.1)
		(layer "B.Cu")
		(net 954)
	)
	(segment
		(start 154.3 98.3)
		(end 154.7 97.9)
		(width 0.1)
		(layer "B.Cu")
		(net 954)
	)
	(segment
		(start 192.6 86)
		(end 192.89 86.29)
		(width 0.1)
		(layer "B.Cu")
		(net 954)
	)
	(segment
		(start 160.4 99)
		(end 180.9 99)
		(width 0.1)
		(layer "B.Cu")
		(net 954)
	)
	(segment
		(start 187.7 92.2)
		(end 187.7 90)
		(width 0.1)
		(layer "B.Cu")
		(net 954)
	)
	(segment
		(start 192.89 86.29)
		(end 192.89 87.71)
		(width 0.1)
		(layer "B.Cu")
		(net 954)
	)
	(segment
		(start 180.9 99)
		(end 187.7 92.2)
		(width 0.1)
		(layer "B.Cu")
		(net 954)
	)
	(segment
		(start 192.3 78.5)
		(end 191.9 78.9)
		(width 0.1)
		(layer "In5.Cu")
		(net 954)
	)
	(segment
		(start 189.3 85.1)
		(end 192.2 88)
		(width 0.1)
		(layer "In5.Cu")
		(net 954)
	)
	(segment
		(start 192.3 75.2)
		(end 192.3 78.5)
		(width 0.1)
		(layer "In5.Cu")
		(net 954)
	)
	(segment
		(start 191.9 78.9)
		(end 190.4 78.9)
		(width 0.1)
		(layer "In5.Cu")
		(net 954)
	)
	(segment
		(start 190.4 78.9)
		(end 189.3 80)
		(width 0.1)
		(layer "In5.Cu")
		(net 954)
	)
	(segment
		(start 189.3 80)
		(end 189.3 85.1)
		(width 0.1)
		(layer "In5.Cu")
		(net 954)
	)
	(segment
		(start 192.2 88)
		(end 192.2 88.4)
		(width 0.1)
		(layer "In5.Cu")
		(net 954)
	)
	(segment
		(start 211.95 80.65)
		(end 213 81.7)
		(width 0.1)
		(layer "F.Cu")
		(net 955)
	)
	(segment
		(start 215 80.92)
		(end 214.28 80.2)
		(width 0.1)
		(layer "F.Cu")
		(net 955)
	)
	(segment
		(start 211.95 80.25)
		(end 211.95 80.65)
		(width 0.1)
		(layer "F.Cu")
		(net 955)
	)
	(segment
		(start 213 81.7)
		(end 214.7 81.7)
		(width 0.1)
		(layer "F.Cu")
		(net 955)
	)
	(segment
		(start 214.7 81.7)
		(end 215 81.4)
		(width 0.1)
		(layer "F.Cu")
		(net 955)
	)
	(segment
		(start 215 81.4)
		(end 215 80.92)
		(width 0.1)
		(layer "F.Cu")
		(net 955)
	)
	(via
		(at 214.28 80.2)
		(size 0.45)
		(drill 0.1)
		(layers "F.Cu" "B.Cu")
		(net 955)
	)
	(segment
		(start 214.28 80.2)
		(end 215.4 80.2)
		(width 0.1)
		(layer "B.Cu")
		(net 955)
	)
	(segment
		(start 215.4 80.2)
		(end 216.935 78.665)
		(width 0.1)
		(layer "B.Cu")
		(net 955)
	)
	(segment
		(start 216.935 78.665)
		(end 218.1 78.665)
		(width 0.1)
		(layer "B.Cu")
		(net 955)
	)
	(segment
		(start 212.35 79.35)
		(end 214.2 81.2)
		(width 0.1)
		(layer "F.Cu")
		(net 956)
	)
	(segment
		(start 211.95 79.35)
		(end 212.35 79.35)
		(width 0.1)
		(layer "F.Cu")
		(net 956)
	)
	(segment
		(start 214.2 81.2)
		(end 214.3 81.2)
		(width 0.1)
		(layer "F.Cu")
		(net 956)
	)
	(via
		(at 214.3 81.2)
		(size 0.45)
		(drill 0.1)
		(layers "F.Cu" "B.Cu")
		(net 956)
	)
	(segment
		(start 214.269 81.225)
		(end 218.675 81.225)
		(width 0.1)
		(layer "B.Cu")
		(net 956)
	)
	(segment
		(start 218.675 81.225)
		(end 219.025 80.875)
		(width 0.1)
		(layer "B.Cu")
		(net 956)
	)
	(segment
		(start 219.025 80.875)
		(end 219.025 80.24)
		(width 0.1)
		(layer "B.Cu")
		(net 956)
	)
	(segment
		(start 216.364632 90.770856)
		(end 217.370856 90.770856)
		(width 0.1)
		(layer "F.Cu")
		(net 957)
	)
	(segment
		(start 217.370856 90.770856)
		(end 217.4 90.8)
		(width 0.1)
		(layer "F.Cu")
		(net 957)
	)
	(via
		(at 217.4 90.8)
		(size 0.45)
		(drill 0.1)
		(layers "F.Cu" "B.Cu")
		(net 957)
	)
	(segment
		(start 215.93 92.27)
		(end 217.4 90.8)
		(width 0.1)
		(layer "B.Cu")
		(net 957)
	)
	(segment
		(start 221.78 94.58)
		(end 220.9 93.7)
		(width 0.1)
		(layer "B.Cu")
		(net 957)
	)
	(segment
		(start 215.93 94.62)
		(end 215.93 93.7)
		(width 0.1)
		(layer "B.Cu")
		(net 957)
	)
	(segment
		(start 221.78 95.392)
		(end 221.78 95.994132)
		(width 0.1)
		(layer "B.Cu")
		(net 957)
	)
	(segment
		(start 221.78 95.994132)
		(end 221.182132 96.592)
		(width 0.1)
		(layer "B.Cu")
		(net 957)
	)
	(segment
		(start 220.9 93.7)
		(end 215.93 93.7)
		(width 0.1)
		(layer "B.Cu")
		(net 957)
	)
	(segment
		(start 215.93 93.7)
		(end 215.93 92.27)
		(width 0.1)
		(layer "B.Cu")
		(net 957)
	)
	(segment
		(start 221.78 95.392)
		(end 221.78 94.58)
		(width 0.1)
		(layer "B.Cu")
		(net 957)
	)
	(segment
		(start 217.3 78)
		(end 216.68 78)
		(width 0.1)
		(layer "F.Cu")
		(net 958)
	)
	(via
		(at 217.3 78)
		(size 0.45)
		(drill 0.1)
		(layers "F.Cu" "B.Cu")
		(net 958)
	)
	(segment
		(start 217.315 78.015)
		(end 217.3 78)
		(width 0.1)
		(layer "B.Cu")
		(net 958)
	)
	(segment
		(start 218.1 78.015)
		(end 217.315 78.015)
		(width 0.1)
		(layer "B.Cu")
		(net 958)
	)
	(segment
		(start 214.55 76.8)
		(end 215.52 76.8)
		(width 0.1)
		(layer "F.Cu")
		(net 959)
	)
	(segment
		(start 153.2 99.2)
		(end 154.8 99.2)
		(width 0.1)
		(layer "F.Cu")
		(net 959)
	)
	(segment
		(start 215.52 76.8)
		(end 215.72 77)
		(width 0.1)
		(layer "F.Cu")
		(net 959)
	)
	(via
		(at 214.55 76.8)
		(size 0.45)
		(drill 0.1)
		(layers "F.Cu" "B.Cu")
		(net 959)
	)
	(via
		(at 205.4 93.15)
		(size 0.45)
		(drill 0.1)
		(layers "F.Cu" "B.Cu")
		(net 959)
	)
	(via
		(at 154.8 99.2)
		(size 0.45)
		(drill 0.1)
		(layers "F.Cu" "B.Cu")
		(net 959)
	)
	(segment
		(start 214.2 77.834314)
		(end 214.2 77.15)
		(width 0.1)
		(layer "In2.Cu")
		(net 959)
	)
	(segment
		(start 214.2 77.15)
		(end 214.55 76.8)
		(width 0.1)
		(layer "In2.Cu")
		(net 959)
	)
	(segment
		(start 207.6 93)
		(end 207.8 92.8)
		(width 0.1)
		(layer "In2.Cu")
		(net 959)
	)
	(segment
		(start 205.55 93)
		(end 207.6 93)
		(width 0.1)
		(layer "In2.Cu")
		(net 959)
	)
	(segment
		(start 205.4 93.15)
		(end 205.55 93)
		(width 0.1)
		(layer "In2.Cu")
		(net 959)
	)
	(segment
		(start 210.6 81.434314)
		(end 214.2 77.834314)
		(width 0.1)
		(layer "In2.Cu")
		(net 959)
	)
	(segment
		(start 207.8 92.8)
		(end 207.8 90.034314)
		(width 0.1)
		(layer "In2.Cu")
		(net 959)
	)
	(segment
		(start 207.8 90.034314)
		(end 210.6 87.234314)
		(width 0.1)
		(layer "In2.Cu")
		(net 959)
	)
	(segment
		(start 210.6 87.234314)
		(end 210.6 81.434314)
		(width 0.1)
		(layer "In2.Cu")
		(net 959)
	)
	(segment
		(start 205.4 93.3)
		(end 205.4 93.15)
		(width 0.1)
		(layer "In7.Cu")
		(net 959)
	)
	(segment
		(start 193.7 94)
		(end 204.7 94)
		(width 0.1)
		(layer "In7.Cu")
		(net 959)
	)
	(segment
		(start 189.4 98.3)
		(end 193.7 94)
		(width 0.1)
		(layer "In7.Cu")
		(net 959)
	)
	(segment
		(start 157.1 99.2)
		(end 158 98.3)
		(width 0.1)
		(layer "In7.Cu")
		(net 959)
	)
	(segment
		(start 204.7 94)
		(end 205.4 93.3)
		(width 0.1)
		(layer "In7.Cu")
		(net 959)
	)
	(segment
		(start 154.8 99.2)
		(end 157.1 99.2)
		(width 0.1)
		(layer "In7.Cu")
		(net 959)
	)
	(segment
		(start 158 98.3)
		(end 189.4 98.3)
		(width 0.1)
		(layer "In7.Cu")
		(net 959)
	)
	(segment
		(start 215.62 77.9)
		(end 215.72 78)
		(width 0.1)
		(layer "F.Cu")
		(net 960)
	)
	(segment
		(start 153.2 99.6)
		(end 155.6 99.6)
		(width 0.1)
		(layer "F.Cu")
		(net 960)
	)
	(segment
		(start 215.21 77.89)
		(end 215.22 77.9)
		(width 0.1)
		(layer "F.Cu")
		(net 960)
	)
	(segment
		(start 215.22 77.9)
		(end 215.62 77.9)
		(width 0.1)
		(layer "F.Cu")
		(net 960)
	)
	(via
		(at 215.21 77.89)
		(size 0.45)
		(drill 0.1)
		(layers "F.Cu" "B.Cu")
		(net 960)
	)
	(via
		(at 155.6 99.6)
		(size 0.45)
		(drill 0.1)
		(layers "F.Cu" "B.Cu")
		(net 960)
	)
	(via
		(at 206 93.4)
		(size 0.45)
		(drill 0.1)
		(layers "F.Cu" "B.Cu")
		(net 960)
	)
	(segment
		(start 211 81.6)
		(end 214.71 77.89)
		(width 0.1)
		(layer "In2.Cu")
		(net 960)
	)
	(segment
		(start 207.8 93.4)
		(end 208.2 93)
		(width 0.1)
		(layer "In2.Cu")
		(net 960)
	)
	(segment
		(start 208.2 90.2)
		(end 211 87.4)
		(width 0.1)
		(layer "In2.Cu")
		(net 960)
	)
	(segment
		(start 214.71 77.89)
		(end 215.21 77.89)
		(width 0.1)
		(layer "In2.Cu")
		(net 960)
	)
	(segment
		(start 206 93.4)
		(end 207.8 93.4)
		(width 0.1)
		(layer "In2.Cu")
		(net 960)
	)
	(segment
		(start 208.2 93)
		(end 208.2 90.2)
		(width 0.1)
		(layer "In2.Cu")
		(net 960)
	)
	(segment
		(start 211 87.4)
		(end 211 81.6)
		(width 0.1)
		(layer "In2.Cu")
		(net 960)
	)
	(segment
		(start 193.824265 94.299999)
		(end 204.824263 94.299999)
		(width 0.1)
		(layer "In7.Cu")
		(net 960)
	)
	(segment
		(start 189.524264 98.6)
		(end 193.824265 94.299999)
		(width 0.1)
		(layer "In7.Cu")
		(net 960)
	)
	(segment
		(start 204.824263 94.299999)
		(end 205.724262 93.4)
		(width 0.1)
		(layer "In7.Cu")
		(net 960)
	)
	(segment
		(start 155.6 99.6)
		(end 157.2 99.6)
		(width 0.1)
		(layer "In7.Cu")
		(net 960)
	)
	(segment
		(start 205.724262 93.4)
		(end 206 93.4)
		(width 0.1)
		(layer "In7.Cu")
		(net 960)
	)
	(segment
		(start 158.2 98.6)
		(end 189.524264 98.6)
		(width 0.1)
		(layer "In7.Cu")
		(net 960)
	)
	(segment
		(start 157.2 99.6)
		(end 158.2 98.6)
		(width 0.1)
		(layer "In7.Cu")
		(net 960)
	)
	(segment
		(start 216.68 77)
		(end 218.3 77)
		(width 0.1)
		(layer "F.Cu")
		(net 961)
	)
	(segment
		(start 218.3 77)
		(end 219.6 75.7)
		(width 0.1)
		(layer "F.Cu")
		(net 961)
	)
	(via
		(at 219.6 75.7)
		(size 0.45)
		(drill 0.1)
		(layers "F.Cu" "B.Cu")
		(net 961)
	)
	(segment
		(start 219.675 75.775)
		(end 219.6 75.7)
		(width 0.1)
		(layer "B.Cu")
		(net 961)
	)
	(segment
		(start 219.675 76.44)
		(end 219.675 75.775)
		(width 0.1)
		(layer "B.Cu")
		(net 961)
	)
	(segment
		(start 153.2 100)
		(end 154.8 100)
		(width 0.1)
		(layer "F.Cu")
		(net 962)
	)
	(via
		(at 226.4 95)
		(size 0.45)
		(drill 0.1)
		(layers "F.Cu" "B.Cu")
		(net 962)
	)
	(via
		(at 158.4 100)
		(size 0.45)
		(drill 0.1)
		(layers "F.Cu" "B.Cu")
		(net 962)
	)
	(via
		(at 210 98.4)
		(size 0.45)
		(drill 0.1)
		(layers "F.Cu" "B.Cu")
		(net 962)
	)
	(via
		(at 154.8 100)
		(size 0.45)
		(drill 0.1)
		(layers "F.Cu" "B.Cu")
		(net 962)
	)
	(segment
		(start 230.204 94.146)
		(end 231.099 94.146)
		(width 0.1)
		(layer "B.Cu")
		(net 962)
	)
	(segment
		(start 227.4 94.92)
		(end 227.64 95.16)
		(width 0.1)
		(layer "B.Cu")
		(net 962)
	)
	(segment
		(start 154.8 100)
		(end 154.8 99.8)
		(width 0.1)
		(layer "B.Cu")
		(net 962)
	)
	(segment
		(start 157.6 99.2)
		(end 158.4 100)
		(width 0.1)
		(layer "B.Cu")
		(net 962)
	)
	(segment
		(start 226.48 94.92)
		(end 226.4 95)
		(width 0.1)
		(layer "B.Cu")
		(net 962)
	)
	(segment
		(start 227.4 94.92)
		(end 226.48 94.92)
		(width 0.1)
		(layer "B.Cu")
		(net 962)
	)
	(segment
		(start 154.8 99.8)
		(end 155.4 99.2)
		(width 0.1)
		(layer "B.Cu")
		(net 962)
	)
	(segment
		(start 230.1 94.5)
		(end 230.1 94.25)
		(width 0.1)
		(layer "B.Cu")
		(net 962)
	)
	(segment
		(start 229.44 95.16)
		(end 230.1 94.5)
		(width 0.1)
		(layer "B.Cu")
		(net 962)
	)
	(segment
		(start 227.64 95.16)
		(end 229.44 95.16)
		(width 0.1)
		(layer "B.Cu")
		(net 962)
	)
	(segment
		(start 230.1 94.25)
		(end 230.204 94.146)
		(width 0.1)
		(layer "B.Cu")
		(net 962)
	)
	(segment
		(start 155.4 99.2)
		(end 157.6 99.2)
		(width 0.1)
		(layer "B.Cu")
		(net 962)
	)
	(segment
		(start 210 98.4)
		(end 210 99)
		(width 0.1)
		(layer "In5.Cu")
		(net 962)
	)
	(segment
		(start 216.6 97.6)
		(end 217.4 96.8)
		(width 0.1)
		(layer "In5.Cu")
		(net 962)
	)
	(segment
		(start 210 99)
		(end 210.4 99.4)
		(width 0.1)
		(layer "In5.Cu")
		(net 962)
	)
	(segment
		(start 212 99.4)
		(end 213.8 97.6)
		(width 0.1)
		(layer "In5.Cu")
		(net 962)
	)
	(segment
		(start 217.4 96.8)
		(end 224.6 96.8)
		(width 0.1)
		(layer "In5.Cu")
		(net 962)
	)
	(segment
		(start 210.4 99.4)
		(end 212 99.4)
		(width 0.1)
		(layer "In5.Cu")
		(net 962)
	)
	(segment
		(start 224.6 96.8)
		(end 226.4 95)
		(width 0.1)
		(layer "In5.Cu")
		(net 962)
	)
	(segment
		(start 213.8 97.6)
		(end 216.6 97.6)
		(width 0.1)
		(layer "In5.Cu")
		(net 962)
	)
	(segment
		(start 186.9 100)
		(end 187.93 98.97)
		(width 0.1)
		(layer "In7.Cu")
		(net 962)
	)
	(segment
		(start 194.22 98.97)
		(end 194.45 99.2)
		(width 0.1)
		(layer "In7.Cu")
		(net 962)
	)
	(segment
		(start 187.93 98.97)
		(end 194.22 98.97)
		(width 0.1)
		(layer "In7.Cu")
		(net 962)
	)
	(segment
		(start 194.45 99.2)
		(end 209.2 99.2)
		(width 0.1)
		(layer "In7.Cu")
		(net 962)
	)
	(segment
		(start 209.2 99.2)
		(end 210 98.4)
		(width 0.1)
		(layer "In7.Cu")
		(net 962)
	)
	(segment
		(start 158.4 100)
		(end 186.9 100)
		(width 0.1)
		(layer "In7.Cu")
		(net 962)
	)
	(segment
		(start 211.55 90.8)
		(end 211.579144 90.770856)
		(width 0.1)
		(layer "F.Cu")
		(net 963)
	)
	(segment
		(start 211.579144 90.770856)
		(end 212.565632 90.770856)
		(width 0.1)
		(layer "F.Cu")
		(net 963)
	)
	(via
		(at 211.55 90.8)
		(size 0.45)
		(drill 0.1)
		(layers "F.Cu" "B.Cu")
		(net 963)
	)
	(segment
		(start 212.305001 90.8)
		(end 212.32 90.785001)
		(width 0.1)
		(layer "B.Cu")
		(net 963)
	)
	(segment
		(start 212.32 90.785001)
		(end 212.32 91.8)
		(width 0.1)
		(layer "B.Cu")
		(net 963)
	)
	(segment
		(start 211.55 90.8)
		(end 212.305001 90.8)
		(width 0.1)
		(layer "B.Cu")
		(net 963)
	)
	(segment
		(start 211.45 88.25)
		(end 211.828144 88.25)
		(width 0.1)
		(layer "F.Cu")
		(net 964)
	)
	(segment
		(start 211.828144 88.25)
		(end 211.95 88.371856)
		(width 0.1)
		(layer "F.Cu")
		(net 964)
	)
	(segment
		(start 212.565632 88.371856)
		(end 211.95 88.371856)
		(width 0.1)
		(layer "F.Cu")
		(net 964)
	)
	(via
		(at 211.45 88.25)
		(size 0.45)
		(drill 0.1)
		(layers "F.Cu" "B.Cu")
		(net 964)
	)
	(segment
		(start 212.32 87.7)
		(end 212.32 86.66)
		(width 0.1)
		(layer "B.Cu")
		(net 964)
	)
	(segment
		(start 211.45 88.25)
		(end 211.77 88.25)
		(width 0.1)
		(layer "B.Cu")
		(net 964)
	)
	(segment
		(start 211.77 88.25)
		(end 212.32 87.7)
		(width 0.1)
		(layer "B.Cu")
		(net 964)
	)
	(segment
		(start 215.4875 85.6125)
		(end 215.4875 85.8125)
		(width 0.1)
		(layer "F.Cu")
		(net 965)
	)
	(segment
		(start 215.063632 86.236368)
		(end 215.063632 86.872856)
		(width 0.1)
		(layer "F.Cu")
		(net 965)
	)
	(segment
		(start 215.675 85.425)
		(end 215.4875 85.6125)
		(width 0.1)
		(layer "F.Cu")
		(net 965)
	)
	(segment
		(start 215.4875 85.8125)
		(end 215.063632 86.236368)
		(width 0.1)
		(layer "F.Cu")
		(net 965)
	)
	(via
		(at 215.675 85.425)
		(size 0.45)
		(drill 0.1)
		(layers "F.Cu" "B.Cu")
		(net 965)
	)
	(segment
		(start 217.038 86.238)
		(end 218.714999 86.238)
		(width 0.1)
		(layer "B.Cu")
		(net 965)
	)
	(segment
		(start 216.225 85.425)
		(end 217.038 86.238)
		(width 0.1)
		(layer "B.Cu")
		(net 965)
	)
	(segment
		(start 215.675 85.425)
		(end 216.225 85.425)
		(width 0.1)
		(layer "B.Cu")
		(net 965)
	)
	(segment
		(start 210.504144 89.570856)
		(end 210.425 89.65)
		(width 0.1)
		(layer "F.Cu")
		(net 966)
	)
	(segment
		(start 212.565632 89.570856)
		(end 210.504144 89.570856)
		(width 0.1)
		(layer "F.Cu")
		(net 966)
	)
	(via
		(at 210.425 89.65)
		(size 0.45)
		(drill 0.1)
		(layers "F.Cu" "B.Cu")
		(net 966)
	)
	(segment
		(start 212.17 89.65)
		(end 212.32 89.8)
		(width 0.1)
		(layer "B.Cu")
		(net 966)
	)
	(segment
		(start 210.425 89.65)
		(end 212.17 89.65)
		(width 0.1)
		(layer "B.Cu")
		(net 966)
	)
	(segment
		(start 212.32 89.8)
		(end 212.32 88.775001)
		(width 0.1)
		(layer "B.Cu")
		(net 966)
	)
	(segment
		(start 215.463632 86.311368)
		(end 215.8 85.975)
		(width 0.1)
		(layer "F.Cu")
		(net 967)
	)
	(segment
		(start 215.8 85.975)
		(end 215.825 85.975)
		(width 0.1)
		(layer "F.Cu")
		(net 967)
	)
	(segment
		(start 215.463632 86.872856)
		(end 215.463632 86.311368)
		(width 0.1)
		(layer "F.Cu")
		(net 967)
	)
	(via
		(at 215.825 85.975)
		(size 0.45)
		(drill 0.1)
		(layers "F.Cu" "B.Cu")
		(net 967)
	)
	(segment
		(start 215.5 84.78)
		(end 214.5 84.78)
		(width 0.1)
		(layer "B.Cu")
		(net 967)
	)
	(segment
		(start 214.5 85.3)
		(end 215.175 85.975)
		(width 0.1)
		(layer "B.Cu")
		(net 967)
	)
	(segment
		(start 214.5 84.78)
		(end 214.5 85.3)
		(width 0.1)
		(layer "B.Cu")
		(net 967)
	)
	(segment
		(start 215.175 85.975)
		(end 215.825 85.975)
		(width 0.1)
		(layer "B.Cu")
		(net 967)
	)
	(segment
		(start 216.364632 88.371856)
		(end 217.328144 88.371856)
		(width 0.1)
		(layer "F.Cu")
		(net 968)
	)
	(segment
		(start 217.328144 88.371856)
		(end 217.4 88.3)
		(width 0.1)
		(layer "F.Cu")
		(net 968)
	)
	(via
		(at 217.4 88.3)
		(size 0.45)
		(drill 0.1)
		(layers "F.Cu" "B.Cu")
		(net 968)
	)
	(segment
		(start 216.48 88.2)
		(end 217.3 88.2)
		(width 0.1)
		(layer "B.Cu")
		(net 968)
	)
	(segment
		(start 217.3 88.2)
		(end 217.4 88.3)
		(width 0.1)
		(layer "B.Cu")
		(net 968)
	)
	(segment
		(start 216.48 87.185)
		(end 216.48 88.2)
		(width 0.1)
		(layer "B.Cu")
		(net 968)
	)
	(segment
		(start 216.364632 89.570856)
		(end 218.529144 89.570856)
		(width 0.1)
		(layer "F.Cu")
		(net 969)
	)
	(segment
		(start 218.529144 89.570856)
		(end 218.6 89.5)
		(width 0.1)
		(layer "F.Cu")
		(net 969)
	)
	(via
		(at 218.6 89.5)
		(size 0.45)
		(drill 0.1)
		(layers "F.Cu" "B.Cu")
		(net 969)
	)
	(segment
		(start 216.48 89.2)
		(end 218.3 89.2)
		(width 0.1)
		(layer "B.Cu")
		(net 969)
	)
	(segment
		(start 216.48 89.2)
		(end 216.48 90.22)
		(width 0.1)
		(layer "B.Cu")
		(net 969)
	)
	(segment
		(start 218.3 89.2)
		(end 218.6 89.5)
		(width 0.1)
		(layer "B.Cu")
		(net 969)
	)
	(segment
		(start 200.65 82.65)
		(end 200.399 82.399)
		(width 0.1)
		(layer "F.Cu")
		(net 970)
	)
	(segment
		(start 200.399 82.399)
		(end 200.399 81.831)
		(width 0.1)
		(layer "F.Cu")
		(net 970)
	)
	(segment
		(start 200.65 82.7)
		(end 200.65 82.65)
		(width 0.1)
		(layer "F.Cu")
		(net 970)
	)
	(via
		(at 237.8 95.4)
		(size 0.45)
		(drill 0.1)
		(layers "F.Cu" "B.Cu")
		(net 970)
	)
	(via
		(at 200.65 82.7)
		(size 0.45)
		(drill 0.1)
		(layers "F.Cu" "B.Cu")
		(net 970)
	)
	(segment
		(start 238.16 93.484999)
		(end 238.099002 93.424001)
		(width 0.1)
		(layer "B.Cu")
		(net 970)
	)
	(segment
		(start 238.16 94.4)
		(end 238.16 93.484999)
		(width 0.1)
		(layer "B.Cu")
		(net 970)
	)
	(segment
		(start 238.16 94.4)
		(end 238.16 95.04)
		(width 0.1)
		(layer "B.Cu")
		(net 970)
	)
	(segment
		(start 238.16 95.04)
		(end 237.8 95.4)
		(width 0.1)
		(layer "B.Cu")
		(net 970)
	)
	(segment
		(start 205.075 84.6)
		(end 206.0625 85.5875)
		(width 0.1)
		(layer "In5.Cu")
		(net 970)
	)
	(segment
		(start 199.2 84.6)
		(end 205.075 84.6)
		(width 0.1)
		(layer "In5.Cu")
		(net 970)
	)
	(segment
		(start 206.0625 86.1625)
		(end 208.9 89)
		(width 0.1)
		(layer "In5.Cu")
		(net 970)
	)
	(segment
		(start 230.9 93.7)
		(end 232.6 95.4)
		(width 0.1)
		(layer "In5.Cu")
		(net 970)
	)
	(segment
		(start 198.3 81.8)
		(end 198 82.1)
		(width 0.1)
		(layer "In5.Cu")
		(net 970)
	)
	(segment
		(start 232.6 95.4)
		(end 237.8 95.4)
		(width 0.1)
		(layer "In5.Cu")
		(net 970)
	)
	(segment
		(start 206.0625 85.5875)
		(end 206.0625 86.1625)
		(width 0.1)
		(layer "In5.Cu")
		(net 970)
	)
	(segment
		(start 199.75 81.8)
		(end 198.3 81.8)
		(width 0.1)
		(layer "In5.Cu")
		(net 970)
	)
	(segment
		(start 214.2 89)
		(end 217.1 91.9)
		(width 0.1)
		(layer "In5.Cu")
		(net 970)
	)
	(segment
		(start 208.9 89)
		(end 214.2 89)
		(width 0.1)
		(layer "In5.Cu")
		(net 970)
	)
	(segment
		(start 217.1 91.9)
		(end 223.1 91.9)
		(width 0.1)
		(layer "In5.Cu")
		(net 970)
	)
	(segment
		(start 224.9 93.7)
		(end 230.9 93.7)
		(width 0.1)
		(layer "In5.Cu")
		(net 970)
	)
	(segment
		(start 223.1 91.9)
		(end 224.9 93.7)
		(width 0.1)
		(layer "In5.Cu")
		(net 970)
	)
	(segment
		(start 198 83.4)
		(end 199.2 84.6)
		(width 0.1)
		(layer "In5.Cu")
		(net 970)
	)
	(segment
		(start 200.65 82.7)
		(end 199.75 81.8)
		(width 0.1)
		(layer "In5.Cu")
		(net 970)
	)
	(segment
		(start 198 82.1)
		(end 198 83.4)
		(width 0.1)
		(layer "In5.Cu")
		(net 970)
	)
	(segment
		(start 235.546 94.146)
		(end 235.8 94.4)
		(width 0.1)
		(layer "B.Cu")
		(net 971)
	)
	(segment
		(start 237.2 94.4)
		(end 237.2 93.454999)
		(width 0.1)
		(layer "B.Cu")
		(net 971)
	)
	(segment
		(start 233.699 94.146)
		(end 235.546 94.146)
		(width 0.1)
		(layer "B.Cu")
		(net 971)
	)
	(segment
		(start 237.2 93.454999)
		(end 237.169002 93.424001)
		(width 0.1)
		(layer "B.Cu")
		(net 971)
	)
	(segment
		(start 235.8 94.4)
		(end 237.2 94.4)
		(width 0.1)
		(layer "B.Cu")
		(net 971)
	)
	(segment
		(start 233.699 95.096)
		(end 234.816 95.096)
		(width 0.1)
		(layer "B.Cu")
		(net 972)
	)
	(segment
		(start 234.816 95.096)
		(end 235.32 95.6)
		(width 0.1)
		(layer "B.Cu")
		(net 972)
	)
	(segment
		(start 223.416 78.015)
		(end 221.9 78.015)
		(width 0.17)
		(layer "B.Cu")
		(net 973)
	)
	(segment
		(start 223.566 77.865)
		(end 223.416 78.015)
		(width 0.17)
		(layer "B.Cu")
		(net 973)
	)
	(segment
		(start 223.345 78.665)
		(end 221.9 78.665)
		(width 0.17)
		(layer "B.Cu")
		(net 974)
	)
	(segment
		(start 223.56 78.88)
		(end 223.345 78.665)
		(width 0.17)
		(layer "B.Cu")
		(net 974)
	)
	(segment
		(start 200.3 82.9)
		(end 200.3 83.1)
		(width 0.1)
		(layer "F.Cu")
		(net 975)
	)
	(segment
		(start 200.3 83.1)
		(end 200.6 83.4)
		(width 0.1)
		(layer "F.Cu")
		(net 975)
	)
	(segment
		(start 200.3 82.9)
		(end 200.001 82.601)
		(width 0.1)
		(layer "F.Cu")
		(net 975)
	)
	(segment
		(start 200.001 82.601)
		(end 200.001 81.831)
		(width 0.1)
		(layer "F.Cu")
		(net 975)
	)
	(via
		(at 200.6 83.4)
		(size 0.45)
		(drill 0.1)
		(layers "F.Cu" "B.Cu")
		(net 975)
	)
	(via
		(at 239.2 81.45)
		(size 0.45)
		(drill 0.1)
		(layers "F.Cu" "B.Cu")
		(net 975)
	)
	(segment
		(start 238.58 80.45)
		(end 238.58 81.45)
		(width 0.15)
		(layer "B.Cu")
		(net 975)
	)
	(segment
		(start 238.58 81.45)
		(end 239.2 81.45)
		(width 0.2)
		(layer "B.Cu")
		(net 975)
	)
	(segment
		(start 239 82.4)
		(end 235 82.4)
		(width 0.1)
		(layer "In5.Cu")
		(net 975)
	)
	(segment
		(start 225.9 85.5)
		(end 229 82.4)
		(width 0.1)
		(layer "In5.Cu")
		(net 975)
	)
	(segment
		(start 207.3 83.4)
		(end 208.9 85)
		(width 0.1)
		(layer "In5.Cu")
		(net 975)
	)
	(segment
		(start 217.4 85.5)
		(end 225.9 85.5)
		(width 0.1)
		(layer "In5.Cu")
		(net 975)
	)
	(segment
		(start 239.2 82.2)
		(end 239 82.4)
		(width 0.1)
		(layer "In5.Cu")
		(net 975)
	)
	(segment
		(start 216.9 85)
		(end 217.4 85.5)
		(width 0.1)
		(layer "In5.Cu")
		(net 975)
	)
	(segment
		(start 239.2 81.45)
		(end 239.2 82.2)
		(width 0.1)
		(layer "In5.Cu")
		(net 975)
	)
	(segment
		(start 229 82.4)
		(end 235 82.4)
		(width 0.1)
		(layer "In5.Cu")
		(net 975)
	)
	(segment
		(start 208.9 85)
		(end 216.9 85)
		(width 0.1)
		(layer "In5.Cu")
		(net 975)
	)
	(segment
		(start 200.6 83.4)
		(end 207.3 83.4)
		(width 0.1)
		(layer "In5.Cu")
		(net 975)
	)
	(segment
		(start 232.499 80.846)
		(end 232.754 80.846)
		(width 0.1)
		(layer "B.Cu")
		(net 976)
	)
	(segment
		(start 232.754 80.846)
		(end 233.22 80.38)
		(width 0.1)
		(layer "B.Cu")
		(net 976)
	)
	(segment
		(start 233.22 79.6)
		(end 232.3 79.6)
		(width 0.1)
		(layer "B.Cu")
		(net 976)
	)
	(segment
		(start 233.22 80.38)
		(end 233.22 79.6)
		(width 0.1)
		(layer "B.Cu")
		(net 976)
	)
	(segment
		(start 237.62 81.45)
		(end 237.15 81.45)
		(width 0.15)
		(layer "B.Cu")
		(net 977)
	)
	(segment
		(start 237.62 82.495001)
		(end 237.615 82.500001)
		(width 0.15)
		(layer "B.Cu")
		(net 977)
	)
	(segment
		(start 237.15 81.45)
		(end 236.546 80.846)
		(width 0.15)
		(layer "B.Cu")
		(net 977)
	)
	(segment
		(start 236.546 80.846)
		(end 235.099 80.846)
		(width 0.15)
		(layer "B.Cu")
		(net 977)
	)
	(segment
		(start 237.62 81.45)
		(end 237.62 82.495001)
		(width 0.15)
		(layer "B.Cu")
		(net 977)
	)
	(segment
		(start 236.6 82.5)
		(end 236.6 82.1)
		(width 0.15)
		(layer "B.Cu")
		(net 978)
	)
	(segment
		(start 236.6 82.1)
		(end 236.296 81.796)
		(width 0.15)
		(layer "B.Cu")
		(net 978)
	)
	(segment
		(start 237.62 83.52)
		(end 236.6 82.5)
		(width 0.15)
		(layer "B.Cu")
		(net 978)
	)
	(segment
		(start 237.62 83.55)
		(end 237.62 83.52)
		(width 0.15)
		(layer "B.Cu")
		(net 978)
	)
	(segment
		(start 236.296 81.796)
		(end 235.099 81.796)
		(width 0.15)
		(layer "B.Cu")
		(net 978)
	)
	(segment
		(start 63.97 64.06)
		(end 63.965 64.065)
		(width 0.1)
		(layer "B.Cu")
		(net 979)
	)
	(segment
		(start 64.18 66.02)
		(end 64.2 66.04)
		(width 0.1)
		(layer "B.Cu")
		(net 979)
	)
	(segment
		(start 63.97 64.47)
		(end 63.2 65.24)
		(width 0.1)
		(layer "B.Cu")
		(net 979)
	)
	(segment
		(start 65 64.44)
		(end 65 64.06)
		(width 0.1)
		(layer "B.Cu")
		(net 979)
	)
	(segment
		(start 65 64.44)
		(end 64.2 65.24)
		(width 0.1)
		(layer "B.Cu")
		(net 979)
	)
	(segment
		(start 64.2 65.24)
		(end 64.2 66.04)
		(width 0.1)
		(layer "B.Cu")
		(net 979)
	)
	(segment
		(start 63.97 64.47)
		(end 63.97 64.06)
		(width 0.1)
		(layer "B.Cu")
		(net 979)
	)
	(segment
		(start 61.2 66.02)
		(end 64.18 66.02)
		(width 0.1)
		(layer "B.Cu")
		(net 979)
	)
	(segment
		(start 63.97 64.06)
		(end 63.902 64.128)
		(width 0.1)
		(layer "B.Cu")
		(net 979)
	)
	(segment
		(start 63.2 65.24)
		(end 63.2 66.02)
		(width 0.1)
		(layer "B.Cu")
		(net 979)
	)
	(segment
		(start 65.1 64.16)
		(end 65 64.06)
		(width 0.1)
		(layer "B.Cu")
		(net 979)
	)
	(segment
		(start 62.08 63.2)
		(end 62.08 62.2)
		(width 0.1)
		(layer "F.Cu")
		(net 980)
	)
	(segment
		(start 62.899 62.299)
		(end 62.8 62.2)
		(width 0.1)
		(layer "F.Cu")
		(net 980)
	)
	(segment
		(start 63.67 62.299)
		(end 62.899 62.299)
		(width 0.1)
		(layer "F.Cu")
		(net 980)
	)
	(segment
		(start 62.8 62.2)
		(end 62.08 62.2)
		(width 0.1)
		(layer "F.Cu")
		(net 980)
	)
	(segment
		(start 62.809 56.891)
		(end 62.9 56.8)
		(width 0.1)
		(layer "F.Cu")
		(net 981)
	)
	(segment
		(start 62.809 57.697)
		(end 62.809 56.891)
		(width 0.1)
		(layer "F.Cu")
		(net 981)
	)
	(via
		(at 62.9 56.8)
		(size 0.45)
		(drill 0.1)
		(layers "F.Cu" "B.Cu")
		(net 981)
	)
	(via
		(at 142.230532 79.65)
		(size 0.45)
		(drill 0.1)
		(layers "F.Cu" "B.Cu")
		(net 981)
	)
	(via
		(at 137.9 111.7)
		(size 0.45)
		(drill 0.1)
		(layers "F.Cu" "B.Cu")
		(net 981)
	)
	(via
		(at 149 116.2)
		(size 0.45)
		(drill 0.1)
		(layers "F.Cu" "B.Cu")
		(net 981)
	)
	(segment
		(start 147.6 115.8)
		(end 145.4 113.6)
		(width 0.1)
		(layer "B.Cu")
		(net 981)
	)
	(segment
		(start 145.4 113.6)
		(end 139.8 113.6)
		(width 0.1)
		(layer "B.Cu")
		(net 981)
	)
	(segment
		(start 149 116.2)
		(end 148.8 116.2)
		(width 0.1)
		(layer "B.Cu")
		(net 981)
	)
	(segment
		(start 148.4 115.8)
		(end 147.6 115.8)
		(width 0.1)
		(layer "B.Cu")
		(net 981)
	)
	(segment
		(start 139.8 113.6)
		(end 137.9 111.7)
		(width 0.1)
		(layer "B.Cu")
		(net 981)
	)
	(segment
		(start 148.8 116.2)
		(end 148.4 115.8)
		(width 0.1)
		(layer "B.Cu")
		(net 981)
	)
	(segment
		(start 142.930532 80.35)
		(end 145.55 80.35)
		(width 0.1)
		(layer "In5.Cu")
		(net 981)
	)
	(segment
		(start 148.6 118.765686)
		(end 148.6 117.2)
		(width 0.1)
		(layer "In5.Cu")
		(net 981)
	)
	(segment
		(start 136.75 105.6)
		(end 137.1 105.95)
		(width 0.1)
		(layer "In5.Cu")
		(net 981)
	)
	(segment
		(start 144.55196 84.926001)
		(end 144.373999 84.926001)
		(width 0.1)
		(layer "In5.Cu")
		(net 981)
	)
	(segment
		(start 148.6 117.2)
		(end 149 116.8)
		(width 0.1)
		(layer "In5.Cu")
		(net 981)
	)
	(segment
		(start 62.9 59.1)
		(end 63.5 59.7)
		(width 0.1)
		(layer "In5.Cu")
		(net 981)
	)
	(segment
		(start 125.2 130.1)
		(end 137.265686 130.1)
		(width 0.1)
		(layer "In5.Cu")
		(net 981)
	)
	(segment
		(start 137.1 105.95)
		(end 137.1 110.975738)
		(width 0.1)
		(layer "In5.Cu")
		(net 981)
	)
	(segment
		(start 136.75 103.9)
		(end 136.75 105.6)
		(width 0.1)
		(layer "In5.Cu")
		(net 981)
	)
	(segment
		(start 62.9 56.8)
		(end 62.9 59.1)
		(width 0.1)
		(layer "In5.Cu")
		(net 981)
	)
	(segment
		(start 137.1 103.55)
		(end 136.75 103.9)
		(width 0.1)
		(layer "In5.Cu")
		(net 981)
	)
	(segment
		(start 137.1 110.975738)
		(end 137.712131 111.587869)
		(width 0.1)
		(layer "In5.Cu")
		(net 981)
	)
	(segment
		(start 64.2 86.046019)
		(end 64.2 114.734314)
		(width 0.1)
		(layer "In5.Cu")
		(net 981)
	)
	(segment
		(start 65.7 70.6)
		(end 65.7 75.45)
		(width 0.1)
		(layer "In5.Cu")
		(net 981)
	)
	(segment
		(start 144.826 84.874)
		(end 144.603962 84.874)
		(width 0.1)
		(layer "In5.Cu")
		(net 981)
	)
	(segment
		(start 92.8 139.4)
		(end 96.967157 135.232843)
		(width 0.1)
		(layer "In5.Cu")
		(net 981)
	)
	(segment
		(start 144.603962 84.874)
		(end 144.55196 84.926001)
		(width 0.1)
		(layer "In5.Cu")
		(net 981)
	)
	(segment
		(start 137.265686 130.1)
		(end 148.6 118.765686)
		(width 0.1)
		(layer "In5.Cu")
		(net 981)
	)
	(segment
		(start 63.5 64.5)
		(end 65.5 66.5)
		(width 0.1)
		(layer "In5.Cu")
		(net 981)
	)
	(segment
		(start 145.55 80.35)
		(end 146.2 81)
		(width 0.1)
		(layer "In5.Cu")
		(net 981)
	)
	(segment
		(start 64.2 114.734314)
		(end 61 117.934314)
		(width 0.1)
		(layer "In5.Cu")
		(net 981)
	)
	(segment
		(start 146.2 83.5)
		(end 144.826 84.874)
		(width 0.1)
		(layer "In5.Cu")
		(net 981)
	)
	(segment
		(start 64.1 130.665686)
		(end 72.834314 139.4)
		(width 0.1)
		(layer "In5.Cu")
		(net 981)
	)
	(segment
		(start 121.5 133.8)
		(end 125.2 130.1)
		(width 0.1)
		(layer "In5.Cu")
		(net 981)
	)
	(segment
		(start 61 117.934314)
		(end 61 121)
		(width 0.1)
		(layer "In5.Cu")
		(net 981)
	)
	(segment
		(start 137.787869 111.587869)
		(end 137.9 111.7)
		(width 0.1)
		(layer "In5.Cu")
		(net 981)
	)
	(segment
		(start 64.896019 76.253981)
		(end 64.896019 85.35)
		(width 0.1)
		(layer "In5.Cu")
		(net 981)
	)
	(segment
		(start 143.5 88.7)
		(end 137.1 95.1)
		(width 0.1)
		(layer "In5.Cu")
		(net 981)
	)
	(segment
		(start 65.5 70.4)
		(end 65.7 70.6)
		(width 0.1)
		(layer "In5.Cu")
		(net 981)
	)
	(segment
		(start 65.7 75.45)
		(end 64.896019 76.253981)
		(width 0.1)
		(layer "In5.Cu")
		(net 981)
	)
	(segment
		(start 106.367157 135.232843)
		(end 107.8 133.8)
		(width 0.1)
		(layer "In5.Cu")
		(net 981)
	)
	(segment
		(start 142.230532 79.65)
		(end 142.930532 80.35)
		(width 0.1)
		(layer "In5.Cu")
		(net 981)
	)
	(segment
		(start 63.5 59.7)
		(end 63.5 64.5)
		(width 0.1)
		(layer "In5.Cu")
		(net 981)
	)
	(segment
		(start 146.2 81)
		(end 146.2 83.5)
		(width 0.1)
		(layer "In5.Cu")
		(net 981)
	)
	(segment
		(start 137.712131 111.587869)
		(end 137.787869 111.587869)
		(width 0.1)
		(layer "In5.Cu")
		(net 981)
	)
	(segment
		(start 144.373999 84.926001)
		(end 144 85.3)
		(width 0.1)
		(layer "In5.Cu")
		(net 981)
	)
	(segment
		(start 144 85.3)
		(end 144 87)
		(width 0.1)
		(layer "In5.Cu")
		(net 981)
	)
	(segment
		(start 137.1 95.1)
		(end 137.1 103.55)
		(width 0.1)
		(layer "In5.Cu")
		(net 981)
	)
	(segment
		(start 65.5 66.5)
		(end 65.5 70.4)
		(width 0.1)
		(layer "In5.Cu")
		(net 981)
	)
	(segment
		(start 64.896019 85.35)
		(end 64.2 86.046019)
		(width 0.1)
		(layer "In5.Cu")
		(net 981)
	)
	(segment
		(start 72.834314 139.4)
		(end 92.8 139.4)
		(width 0.1)
		(layer "In5.Cu")
		(net 981)
	)
	(segment
		(start 107.8 133.8)
		(end 121.5 133.8)
		(width 0.1)
		(layer "In5.Cu")
		(net 981)
	)
	(segment
		(start 96.967157 135.232843)
		(end 106.367157 135.232843)
		(width 0.1)
		(layer "In5.Cu")
		(net 981)
	)
	(segment
		(start 144 87)
		(end 143.5 87.5)
		(width 0.1)
		(layer "In5.Cu")
		(net 981)
	)
	(segment
		(start 149 116.8)
		(end 149 116.2)
		(width 0.1)
		(layer "In5.Cu")
		(net 981)
	)
	(segment
		(start 61 121)
		(end 64.1 124.1)
		(width 0.1)
		(layer "In5.Cu")
		(net 981)
	)
	(segment
		(start 64.1 124.1)
		(end 64.1 130.665686)
		(width 0.1)
		(layer "In5.Cu")
		(net 981)
	)
	(segment
		(start 143.5 87.5)
		(end 143.5 88.7)
		(width 0.1)
		(layer "In5.Cu")
		(net 981)
	)
	(segment
		(start 62.8 61)
		(end 62.8 58.666)
		(width 0.1)
		(layer "F.Cu")
		(net 982)
	)
	(segment
		(start 63.101 61.301)
		(end 62.8 61)
		(width 0.1)
		(layer "F.Cu")
		(net 982)
	)
	(segment
		(start 62.8 58.666)
		(end 62.809 58.657)
		(width 0.1)
		(layer "F.Cu")
		(net 982)
	)
	(segment
		(start 63.67 61.301)
		(end 63.101 61.301)
		(width 0.1)
		(layer "F.Cu")
		(net 982)
	)
	(segment
		(start 63.839 57.691)
		(end 63.839 56.839)
		(width 0.1)
		(layer "F.Cu")
		(net 983)
	)
	(segment
		(start 63.839 56.839)
		(end 63.8 56.8)
		(width 0.1)
		(layer "F.Cu")
		(net 983)
	)
	(via
		(at 143.330532 81.15)
		(size 0.45)
		(drill 0.1)
		(layers "F.Cu" "B.Cu")
		(net 983)
	)
	(via
		(at 137.3 112.3)
		(size 0.45)
		(drill 0.1)
		(layers "F.Cu" "B.Cu")
		(net 983)
	)
	(via
		(at 63.8 56.8)
		(size 0.45)
		(drill 0.1)
		(layers "F.Cu" "B.Cu")
		(net 983)
	)
	(via
		(at 148 116.4)
		(size 0.45)
		(drill 0.1)
		(layers "F.Cu" "B.Cu")
		(net 983)
	)
	(segment
		(start 146.8 116.4)
		(end 144.4 114)
		(width 0.1)
		(layer "B.Cu")
		(net 983)
	)
	(segment
		(start 139 114)
		(end 137.3 112.3)
		(width 0.1)
		(layer "B.Cu")
		(net 983)
	)
	(segment
		(start 144.4 114)
		(end 139 114)
		(width 0.1)
		(layer "B.Cu")
		(net 983)
	)
	(segment
		(start 148 116.4)
		(end 146.8 116.4)
		(width 0.1)
		(layer "B.Cu")
		(net 983)
	)
	(segment
		(start 65.296019 76.653981)
		(end 65.296019 85.95)
		(width 0.1)
		(layer "In5.Cu")
		(net 983)
	)
	(segment
		(start 136.800001 94.975735)
		(end 136.800001 103.3)
		(width 0.1)
		(layer "In5.Cu")
		(net 983)
	)
	(segment
		(start 145.9 81.7)
		(end 145.9 83.441422)
		(width 0.1)
		(layer "In5.Cu")
		(net 983)
	)
	(segment
		(start 144.274 84.726)
		(end 143.7 85.3)
		(width 0.1)
		(layer "In5.Cu")
		(net 983)
	)
	(segment
		(start 121.334314 133.4)
		(end 125.034314 129.7)
		(width 0.1)
		(layer "In5.Cu")
		(net 983)
	)
	(segment
		(start 137.5 111.8)
		(end 137.5 112.1)
		(width 0.1)
		(layer "In5.Cu")
		(net 983)
	)
	(segment
		(start 143.780532 81.6)
		(end 145.8 81.6)
		(width 0.1)
		(layer "In5.Cu")
		(net 983)
	)
	(segment
		(start 137.1 129.7)
		(end 148.2 118.6)
		(width 0.1)
		(layer "In5.Cu")
		(net 983)
	)
	(segment
		(start 106.1 134.8)
		(end 107.5 133.4)
		(width 0.1)
		(layer "In5.Cu")
		(net 983)
	)
	(segment
		(start 107.5 133.4)
		(end 121.334314 133.4)
		(width 0.1)
		(layer "In5.Cu")
		(net 983)
	)
	(segment
		(start 136.45 105.749998)
		(end 136.800002 106.1)
		(width 0.1)
		(layer "In5.Cu")
		(net 983)
	)
	(segment
		(start 64.582843 130.582843)
		(end 73 139)
		(width 0.1)
		(layer "In5.Cu")
		(net 983)
	)
	(segment
		(start 143.2 88.575736)
		(end 136.800001 94.975735)
		(width 0.1)
		(layer "In5.Cu")
		(net 983)
	)
	(segment
		(start 145.8 81.6)
		(end 145.9 81.7)
		(width 0.1)
		(layer "In5.Cu")
		(net 983)
	)
	(segment
		(start 143.7 86.9)
		(end 143.2 87.4)
		(width 0.1)
		(layer "In5.Cu")
		(net 983)
	)
	(segment
		(start 66.1 70.5)
		(end 66.1 75.85)
		(width 0.1)
		(layer "In5.Cu")
		(net 983)
	)
	(segment
		(start 73 139)
		(end 92.634314 139)
		(width 0.1)
		(layer "In5.Cu")
		(net 983)
	)
	(segment
		(start 61.4 120.834314)
		(end 64.582843 124.017157)
		(width 0.1)
		(layer "In5.Cu")
		(net 983)
	)
	(segment
		(start 143.7 85.3)
		(end 143.7 86.9)
		(width 0.1)
		(layer "In5.Cu")
		(net 983)
	)
	(segment
		(start 143.330532 81.15)
		(end 143.780532 81.6)
		(width 0.1)
		(layer "In5.Cu")
		(net 983)
	)
	(segment
		(start 136.800002 106.1)
		(end 136.800002 111.100002)
		(width 0.1)
		(layer "In5.Cu")
		(net 983)
	)
	(segment
		(start 136.45 103.650001)
		(end 136.45 105.749998)
		(width 0.1)
		(layer "In5.Cu")
		(net 983)
	)
	(segment
		(start 63.8 64.1)
		(end 65.7 66)
		(width 0.1)
		(layer "In5.Cu")
		(net 983)
	)
	(segment
		(start 148.2 118.6)
		(end 148.2 116.6)
		(width 0.1)
		(layer "In5.Cu")
		(net 983)
	)
	(segment
		(start 61.4 118.1)
		(end 61.4 120.834314)
		(width 0.1)
		(layer "In5.Cu")
		(net 983)
	)
	(segment
		(start 64.582843 124.017157)
		(end 64.582843 130.582843)
		(width 0.1)
		(layer "In5.Cu")
		(net 983)
	)
	(segment
		(start 148.2 116.6)
		(end 148 116.4)
		(width 0.1)
		(layer "In5.Cu")
		(net 983)
	)
	(segment
		(start 145.9 83.441422)
		(end 144.667422 84.674)
		(width 0.1)
		(layer "In5.Cu")
		(net 983)
	)
	(segment
		(start 63.8 56.8)
		(end 63.8 64.1)
		(width 0.1)
		(layer "In5.Cu")
		(net 983)
	)
	(segment
		(start 144.469119 84.726)
		(end 144.274 84.726)
		(width 0.1)
		(layer "In5.Cu")
		(net 983)
	)
	(segment
		(start 136.800002 111.100002)
		(end 137.5 111.8)
		(width 0.1)
		(layer "In5.Cu")
		(net 983)
	)
	(segment
		(start 136.800001 103.3)
		(end 136.45 103.650001)
		(width 0.1)
		(layer "In5.Cu")
		(net 983)
	)
	(segment
		(start 125.034314 129.7)
		(end 137.1 129.7)
		(width 0.1)
		(layer "In5.Cu")
		(net 983)
	)
	(segment
		(start 64.6 114.9)
		(end 61.4 118.1)
		(width 0.1)
		(layer "In5.Cu")
		(net 983)
	)
	(segment
		(start 96.834314 134.8)
		(end 106.1 134.8)
		(width 0.1)
		(layer "In5.Cu")
		(net 983)
	)
	(segment
		(start 137.5 112.1)
		(end 137.3 112.3)
		(width 0.1)
		(layer "In5.Cu")
		(net 983)
	)
	(segment
		(start 64.6 86.646019)
		(end 64.6 114.9)
		(width 0.1)
		(layer "In5.Cu")
		(net 983)
	)
	(segment
		(start 92.634314 139)
		(end 96.834314 134.8)
		(width 0.1)
		(layer "In5.Cu")
		(net 983)
	)
	(segment
		(start 65.7 66)
		(end 65.7 70.1)
		(width 0.1)
		(layer "In5.Cu")
		(net 983)
	)
	(segment
		(start 66.1 75.85)
		(end 65.296019 76.653981)
		(width 0.1)
		(layer "In5.Cu")
		(net 983)
	)
	(segment
		(start 144.52112 84.674)
		(end 144.469119 84.726)
		(width 0.1)
		(layer "In5.Cu")
		(net 983)
	)
	(segment
		(start 143.2 87.4)
		(end 143.2 88.575736)
		(width 0.1)
		(layer "In5.Cu")
		(net 983)
	)
	(segment
		(start 144.667422 84.674)
		(end 144.52112 84.674)
		(width 0.1)
		(layer "In5.Cu")
		(net 983)
	)
	(segment
		(start 65.296019 85.95)
		(end 64.6 86.646019)
		(width 0.1)
		(layer "In5.Cu")
		(net 983)
	)
	(segment
		(start 65.7 70.1)
		(end 66.1 70.5)
		(width 0.1)
		(layer "In5.Cu")
		(net 983)
	)
	(segment
		(start 63.2 59.8)
		(end 63.839 59.161)
		(width 0.1)
		(layer "F.Cu")
		(net 984)
	)
	(segment
		(start 63.839 59.161)
		(end 63.839 58.651)
		(width 0.1)
		(layer "F.Cu")
		(net 984)
	)
	(segment
		(start 63.4 60.8)
		(end 63.2 60.6)
		(width 0.1)
		(layer "F.Cu")
		(net 984)
	)
	(segment
		(start 63.2 60.6)
		(end 63.2 59.8)
		(width 0.1)
		(layer "F.Cu")
		(net 984)
	)
	(segment
		(start 63.67 60.8)
		(end 63.4 60.8)
		(width 0.1)
		(layer "F.Cu")
		(net 984)
	)
	(segment
		(start 64.821 64.779)
		(end 64.821 63.95)
		(width 0.1)
		(layer "F.Cu")
		(net 985)
	)
	(segment
		(start 64.3 67.8)
		(end 64.3 65.3)
		(width 0.1)
		(layer "F.Cu")
		(net 985)
	)
	(segment
		(start 64.3 65.3)
		(end 64.821 64.779)
		(width 0.1)
		(layer "F.Cu")
		(net 985)
	)
	(segment
		(start 63.9 68.9)
		(end 63.9 68.2)
		(width 0.1)
		(layer "F.Cu")
		(net 985)
	)
	(segment
		(start 63.9 68.2)
		(end 64.3 67.8)
		(width 0.1)
		(layer "F.Cu")
		(net 985)
	)
	(via
		(at 63.9 68.9)
		(size 0.45)
		(drill 0.1)
		(layers "F.Cu" "B.Cu")
		(net 985)
	)
	(segment
		(start 62.2 66.98)
		(end 63.9 68.68)
		(width 0.1)
		(layer "B.Cu")
		(net 985)
	)
	(segment
		(start 63.9 69.12)
		(end 63.1 69.92)
		(width 0.1)
		(layer "B.Cu")
		(net 985)
	)
	(segment
		(start 63.9 68.68)
		(end 63.9 68.9)
		(width 0.1)
		(layer "B.Cu")
		(net 985)
	)
	(segment
		(start 63.9 68.9)
		(end 63.9 69.12)
		(width 0.1)
		(layer "B.Cu")
		(net 985)
	)
	(segment
		(start 64.5 68.9)
		(end 64.5 68.2)
		(width 0.1)
		(layer "F.Cu")
		(net 986)
	)
	(segment
		(start 64.7 68)
		(end 64.7 65.5)
		(width 0.1)
		(layer "F.Cu")
		(net 986)
	)
	(segment
		(start 65.321 64.879)
		(end 65.321 63.95)
		(width 0.1)
		(layer "F.Cu")
		(net 986)
	)
	(segment
		(start 64.7 65.5)
		(end 65.321 64.879)
		(width 0.1)
		(layer "F.Cu")
		(net 986)
	)
	(segment
		(start 64.5 68.2)
		(end 64.7 68)
		(width 0.1)
		(layer "F.Cu")
		(net 986)
	)
	(via
		(at 64.5 68.9)
		(size 0.45)
		(drill 0.1)
		(layers "F.Cu" "B.Cu")
		(net 986)
	)
	(segment
		(start 63.2 66.98)
		(end 63.38 66.98)
		(width 0.1)
		(layer "B.Cu")
		(net 986)
	)
	(segment
		(start 64.1 69.5)
		(end 64.1 69.92)
		(width 0.1)
		(layer "B.Cu")
		(net 986)
	)
	(segment
		(start 63.2 66.98)
		(end 64.5 68.28)
		(width 0.1)
		(layer "B.Cu")
		(net 986)
	)
	(segment
		(start 64.5 68.5)
		(end 64.5 68.9)
		(width 0.1)
		(layer "B.Cu")
		(net 986)
	)
	(segment
		(start 64.5 69.1)
		(end 64.1 69.5)
		(width 0.1)
		(layer "B.Cu")
		(net 986)
	)
	(segment
		(start 64.5 68.28)
		(end 64.5 68.5)
		(width 0.1)
		(layer "B.Cu")
		(net 986)
	)
	(segment
		(start 64.5 68.9)
		(end 64.5 69.1)
		(width 0.1)
		(layer "B.Cu")
		(net 986)
	)
	(segment
		(start 63.3 68.9)
		(end 63.3 68.1)
		(width 0.1)
		(layer "F.Cu")
		(net 987)
	)
	(segment
		(start 63.3 68.1)
		(end 63.9 67.5)
		(width 0.1)
		(layer "F.Cu")
		(net 987)
	)
	(segment
		(start 64.321 63.95)
		(end 64.321 64.679)
		(width 0.1)
		(layer "F.Cu")
		(net 987)
	)
	(segment
		(start 63.9 65.1)
		(end 63.9 67.5)
		(width 0.1)
		(layer "F.Cu")
		(net 987)
	)
	(segment
		(start 64.321 64.679)
		(end 63.9 65.1)
		(width 0.1)
		(layer "F.Cu")
		(net 987)
	)
	(via
		(at 63.3 68.9)
		(size 0.45)
		(drill 0.1)
		(layers "F.Cu" "B.Cu")
		(net 987)
	)
	(segment
		(start 61.2 66.98)
		(end 63.12 68.9)
		(width 0.1)
		(layer "B.Cu")
		(net 987)
	)
	(segment
		(start 62.1 69.9)
		(end 63.11 68.89)
		(width 0.1)
		(layer "B.Cu")
		(net 987)
	)
	(segment
		(start 63.11 68.89)
		(end 63.29 68.89)
		(width 0.1)
		(layer "B.Cu")
		(net 987)
	)
	(segment
		(start 62.1 69.92)
		(end 62.1 69.9)
		(width 0.1)
		(layer "B.Cu")
		(net 987)
	)
	(segment
		(start 63.29 68.89)
		(end 63.3 68.9)
		(width 0.1)
		(layer "B.Cu")
		(net 987)
	)
	(segment
		(start 63.3 68.9)
		(end 63.12 68.9)
		(width 0.1)
		(layer "B.Cu")
		(net 987)
	)
	(segment
		(start 65.819 64.881)
		(end 65.819 63.95)
		(width 0.1)
		(layer "F.Cu")
		(net 988)
	)
	(segment
		(start 65.1 65.6)
		(end 65.819 64.881)
		(width 0.1)
		(layer "F.Cu")
		(net 988)
	)
	(segment
		(start 65.1 69)
		(end 65.1 65.6)
		(width 0.1)
		(layer "F.Cu")
		(net 988)
	)
	(via
		(at 65.1 68.9)
		(size 0.45)
		(drill 0.1)
		(layers "F.Cu" "B.Cu")
		(net 988)
	)
	(segment
		(start 65.1 68.9)
		(end 65.1 69.92)
		(width 0.1)
		(layer "B.Cu")
		(net 988)
	)
	(segment
		(start 65.096 68.896)
		(end 65.1 68.9)
		(width 0.1)
		(layer "B.Cu")
		(net 988)
	)
	(segment
		(start 64.2 67)
		(end 65.096 67.896)
		(width 0.1)
		(layer "B.Cu")
		(net 988)
	)
	(segment
		(start 65.096 67.896)
		(end 65.096 68.896)
		(width 0.1)
		(layer "B.Cu")
		(net 988)
	)
	(segment
		(start 65.098 69.002)
		(end 65.1 69)
		(width 0.1)
		(layer "B.Cu")
		(net 988)
	)
	(segment
		(start 62.4 64.2)
		(end 63.299 63.301)
		(width 0.1)
		(layer "F.Cu")
		(net 989)
	)
	(segment
		(start 63.299 63.301)
		(end 63.67 63.301)
		(width 0.1)
		(layer "F.Cu")
		(net 989)
	)
	(segment
		(start 62.08 64.2)
		(end 62.4 64.2)
		(width 0.1)
		(layer "F.Cu")
		(net 989)
	)
	(segment
		(start 67.16 64.06)
		(end 67.16 64.56)
		(width 0.1)
		(layer "B.Cu")
		(net 990)
	)
	(segment
		(start 66.15 64.06)
		(end 66.15 64.45)
		(width 0.1)
		(layer "B.Cu")
		(net 990)
	)
	(segment
		(start 65.4 65.22)
		(end 68.4 65.22)
		(width 0.1)
		(layer "B.Cu")
		(net 990)
	)
	(segment
		(start 67.4 64.8)
		(end 67.4 65.22)
		(width 0.1)
		(layer "B.Cu")
		(net 990)
	)
	(segment
		(start 67.26 64.16)
		(end 67.16 64.06)
		(width 0.1)
		(layer "B.Cu")
		(net 990)
	)
	(segment
		(start 66.062 64.128)
		(end 66.13 64.06)
		(width 0.1)
		(layer "B.Cu")
		(net 990)
	)
	(segment
		(start 66.4 64.7)
		(end 66.4 65.22)
		(width 0.1)
		(layer "B.Cu")
		(net 990)
	)
	(segment
		(start 67.16 64.56)
		(end 67.4 64.8)
		(width 0.1)
		(layer "B.Cu")
		(net 990)
	)
	(segment
		(start 66.15 64.45)
		(end 66.4 64.7)
		(width 0.1)
		(layer "B.Cu")
		(net 990)
	)
	(segment
		(start 66.9 66.1)
		(end 66.9 67.1)
		(width 0.1)
		(layer "F.Cu")
		(net 991)
	)
	(segment
		(start 68 63.4)
		(end 68 65)
		(width 0.1)
		(layer "F.Cu")
		(net 991)
	)
	(segment
		(start 67.469 63.301)
		(end 67.901 63.301)
		(width 0.1)
		(layer "F.Cu")
		(net 991)
	)
	(segment
		(start 68 65)
		(end 66.9 66.1)
		(width 0.1)
		(layer "F.Cu")
		(net 991)
	)
	(segment
		(start 67.901 63.301)
		(end 68 63.4)
		(width 0.1)
		(layer "F.Cu")
		(net 991)
	)
	(via
		(at 66.9 67.1)
		(size 0.45)
		(drill 0.1)
		(layers "F.Cu" "B.Cu")
		(net 991)
	)
	(segment
		(start 67.4 66.18)
		(end 67.4 66.6)
		(width 0.1)
		(layer "B.Cu")
		(net 991)
	)
	(segment
		(start 67.4 66.6)
		(end 66.9 67.1)
		(width 0.1)
		(layer "B.Cu")
		(net 991)
	)
	(segment
		(start 70.3 65.3)
		(end 69.6 66)
		(width 0.1)
		(layer "B.Cu")
		(net 991)
	)
	(segment
		(start 69.6 67.500002)
		(end 69.000002 68.1)
		(width 0.1)
		(layer "B.Cu")
		(net 991)
	)
	(segment
		(start 69.000002 68.1)
		(end 67.3 68.1)
		(width 0.1)
		(layer "B.Cu")
		(net 991)
	)
	(segment
		(start 66.87 67.07)
		(end 66.9 67.1)
		(width 0.1)
		(layer "B.Cu")
		(net 991)
	)
	(segment
		(start 70.62 65.3)
		(end 70.3 65.3)
		(width 0.1)
		(layer "B.Cu")
		(net 991)
	)
	(segment
		(start 66.9 67.7)
		(end 66.9 67.1)
		(width 0.1)
		(layer "B.Cu")
		(net 991)
	)
	(segment
		(start 67.3 68.1)
		(end 66.9 67.7)
		(width 0.1)
		(layer "B.Cu")
		(net 991)
	)
	(segment
		(start 69.6 66)
		(end 69.6 67.500002)
		(width 0.1)
		(layer "B.Cu")
		(net 991)
	)
	(segment
		(start 67.4 66.3)
		(end 67.4 67.5)
		(width 0.1)
		(layer "F.Cu")
		(net 992)
	)
	(segment
		(start 67.9 62.8)
		(end 68.3 63.2)
		(width 0.1)
		(layer "F.Cu")
		(net 992)
	)
	(segment
		(start 67.469 62.8)
		(end 67.9 62.8)
		(width 0.1)
		(layer "F.Cu")
		(net 992)
	)
	(segment
		(start 68.3 63.2)
		(end 68.3 65.4)
		(width 0.1)
		(layer "F.Cu")
		(net 992)
	)
	(segment
		(start 68.3 65.4)
		(end 67.4 66.3)
		(width 0.1)
		(layer "F.Cu")
		(net 992)
	)
	(via
		(at 67.4 67.5)
		(size 0.45)
		(drill 0.1)
		(layers "F.Cu" "B.Cu")
		(net 992)
	)
	(segment
		(start 67.4 67.5)
		(end 68.4 66.5)
		(width 0.1)
		(layer "B.Cu")
		(net 992)
	)
	(segment
		(start 69.2 67.5)
		(end 69.2 65.5)
		(width 0.1)
		(layer "B.Cu")
		(net 992)
	)
	(segment
		(start 67.4 67.5)
		(end 67.7 67.8)
		(width 0.1)
		(layer "B.Cu")
		(net 992)
	)
	(segment
		(start 70.4 64.3)
		(end 70.62 64.3)
		(width 0.1)
		(layer "B.Cu")
		(net 992)
	)
	(segment
		(start 68.9 67.8)
		(end 69.2 67.5)
		(width 0.1)
		(layer "B.Cu")
		(net 992)
	)
	(segment
		(start 67.7 67.8)
		(end 68.9 67.8)
		(width 0.1)
		(layer "B.Cu")
		(net 992)
	)
	(segment
		(start 69.2 65.5)
		(end 70.4 64.3)
		(width 0.1)
		(layer "B.Cu")
		(net 992)
	)
	(segment
		(start 68.4 66.5)
		(end 68.4 66.18)
		(width 0.1)
		(layer "B.Cu")
		(net 992)
	)
	(segment
		(start 66.319 63.95)
		(end 66.319 65.281)
		(width 0.1)
		(layer "F.Cu")
		(net 993)
	)
	(segment
		(start 66.319 65.281)
		(end 66.1 65.5)
		(width 0.1)
		(layer "F.Cu")
		(net 993)
	)
	(segment
		(start 66.1 65.5)
		(end 66.1 67.1)
		(width 0.1)
		(layer "F.Cu")
		(net 993)
	)
	(via
		(at 66.1 67.1)
		(size 0.45)
		(drill 0.1)
		(layers "F.Cu" "B.Cu")
		(net 993)
	)
	(segment
		(start 66.1 68.1)
		(end 66.7 68.7)
		(width 0.1)
		(layer "B.Cu")
		(net 993)
	)
	(segment
		(start 66.7 68.7)
		(end 69.22 68.7)
		(width 0.1)
		(layer "B.Cu")
		(net 993)
	)
	(segment
		(start 69.22 68.7)
		(end 70.62 67.3)
		(width 0.1)
		(layer "B.Cu")
		(net 993)
	)
	(segment
		(start 65.4 66.18)
		(end 65.4 66.4)
		(width 0.1)
		(layer "B.Cu")
		(net 993)
	)
	(segment
		(start 66.1 67.1)
		(end 66.1 68.1)
		(width 0.1)
		(layer "B.Cu")
		(net 993)
	)
	(segment
		(start 65.4 66.4)
		(end 66.1 67.1)
		(width 0.1)
		(layer "B.Cu")
		(net 993)
	)
	(segment
		(start 66.5 65.7)
		(end 66.82 65.38)
		(width 0.1)
		(layer "F.Cu")
		(net 994)
	)
	(segment
		(start 66.5 65.7)
		(end 66.5 67.5)
		(width 0.1)
		(layer "F.Cu")
		(net 994)
	)
	(segment
		(start 66.82 63.95)
		(end 66.82 65.38)
		(width 0.1)
		(layer "F.Cu")
		(net 994)
	)
	(via
		(at 66.5 67.5)
		(size 0.45)
		(drill 0.1)
		(layers "F.Cu" "B.Cu")
		(net 994)
	)
	(segment
		(start 66.5 67.9)
		(end 67 68.4)
		(width 0.1)
		(layer "B.Cu")
		(net 994)
	)
	(segment
		(start 70 66.5)
		(end 70.2 66.3)
		(width 0.1)
		(layer "B.Cu")
		(net 994)
	)
	(segment
		(start 69.1 68.4)
		(end 70 67.5)
		(width 0.1)
		(layer "B.Cu")
		(net 994)
	)
	(segment
		(start 67 68.4)
		(end 69.1 68.4)
		(width 0.1)
		(layer "B.Cu")
		(net 994)
	)
	(segment
		(start 66.5 66.28)
		(end 66.5 67.5)
		(width 0.1)
		(layer "B.Cu")
		(net 994)
	)
	(segment
		(start 70.2 66.3)
		(end 70.62 66.3)
		(width 0.1)
		(layer "B.Cu")
		(net 994)
	)
	(segment
		(start 70 67.5)
		(end 70 66.5)
		(width 0.1)
		(layer "B.Cu")
		(net 994)
	)
	(segment
		(start 66.4 66.18)
		(end 66.5 66.28)
		(width 0.1)
		(layer "B.Cu")
		(net 994)
	)
	(segment
		(start 66.5 67.5)
		(end 66.5 67.9)
		(width 0.1)
		(layer "B.Cu")
		(net 994)
	)
	(segment
		(start 66.754 86.364)
		(end 66.75 86.36)
		(width 0.1)
		(layer "F.Cu")
		(net 995)
	)
	(segment
		(start 66.754 87.701)
		(end 66.754 86.364)
		(width 0.1)
		(layer "F.Cu")
		(net 995)
	)
	(segment
		(start 62.414 87.741)
		(end 62.414 86.704)
		(width 0.1)
		(layer "F.Cu")
		(net 996)
	)
	(segment
		(start 62.414 86.704)
		(end 62.12 86.41)
		(width 0.1)
		(layer "F.Cu")
		(net 996)
	)
	(segment
		(start 207.48 65.98)
		(end 209.177 65.98)
		(width 0.1)
		(layer "B.Cu")
		(net 997)
	)
	(segment
		(start 209.177 65.98)
		(end 209.201 66.004)
		(width 0.1)
		(layer "B.Cu")
		(net 997)
	)
	(segment
		(start 207.501 62.504)
		(end 207.48 62.483)
		(width 0.1)
		(layer "B.Cu")
		(net 998)
	)
	(segment
		(start 209.201 62.504)
		(end 207.501 62.504)
		(width 0.1)
		(layer "B.Cu")
		(net 998)
	)
	(segment
		(start 148.9 118.2)
		(end 148.28 118.2)
		(width 0.1)
		(layer "F.Cu")
		(net 999)
	)
	(segment
		(start 149.6 118.8)
		(end 149.65 118.75)
		(width 0.1)
		(layer "F.Cu")
		(net 999)
	)
	(segment
		(start 149.65 118.75)
		(end 151.231001 118.75)
		(width 0.1)
		(layer "F.Cu")
		(net 999)
	)
	(segment
		(start 149.5 118.8)
		(end 148.9 118.2)
		(width 0.1)
		(layer "F.Cu")
		(net 999)
	)
	(segment
		(start 149.5 118.8)
		(end 149.6 118.8)
		(width 0.1)
		(layer "F.Cu")
		(net 999)
	)
	(via
		(at 149.5 118.8)
		(size 0.45)
		(drill 0.1)
		(layers "F.Cu" "B.Cu")
		(net 999)
	)
	(via
		(at 209.976 146)
		(size 0.45)
		(drill 0.1)
		(layers "F.Cu" "B.Cu")
		(net 999)
	)
	(segment
		(start 209.206 146)
		(end 209.976 146)
		(width 0.1)
		(layer "B.Cu")
		(net 999)
	)
	(segment
		(start 181.24 124.49)
		(end 166.103553 109.353553)
		(width 0.1)
		(layer "In7.Cu")
		(net 999)
	)
	(segment
		(start 149.58 118.72)
		(end 149.5 118.8)
		(width 0.1)
		(layer "In7.Cu")
		(net 999)
	)
	(segment
		(start 202.3 136.7)
		(end 199.9 136.7)
		(width 0.1)
		(layer "In7.Cu")
		(net 999)
	)
	(segment
		(start 155.861953 115.638047)
		(end 154.146447 117.353553)
		(width 0.1)
		(layer "In7.Cu")
		(net 999)
	)
	(segment
		(start 183.25 129.5)
		(end 183.25 125.16)
		(width 0.1)
		(layer "In7.Cu")
		(net 999)
	)
	(segment
		(start 154.146447 117.353553)
		(end 152.896447 117.353553)
		(width 0.1)
		(layer "In7.Cu")
		(net 999)
	)
	(segment
		(start 151.53 118.72)
		(end 149.58 118.72)
		(width 0.1)
		(layer "In7.Cu")
		(net 999)
	)
	(segment
		(start 199.9 136.7)
		(end 198.803553 135.603553)
		(width 0.1)
		(layer "In7.Cu")
		(net 999)
	)
	(segment
		(start 203.6 139.1)
		(end 203.6 138)
		(width 0.1)
		(layer "In7.Cu")
		(net 999)
	)
	(segment
		(start 157.646447 109.353553)
		(end 155.861953 111.138047)
		(width 0.1)
		(layer "In7.Cu")
		(net 999)
	)
	(segment
		(start 209.2 146)
		(end 208.9 145.7)
		(width 0.1)
		(layer "In7.Cu")
		(net 999)
	)
	(segment
		(start 204.9 140.4)
		(end 203.6 139.1)
		(width 0.1)
		(layer "In7.Cu")
		(net 999)
	)
	(segment
		(start 209.976 146)
		(end 209.2 146)
		(width 0.1)
		(layer "In7.Cu")
		(net 999)
	)
	(segment
		(start 152.896447 117.353553)
		(end 151.53 118.72)
		(width 0.1)
		(layer "In7.Cu")
		(net 999)
	)
	(segment
		(start 166.103553 109.353553)
		(end 157.646447 109.353553)
		(width 0.1)
		(layer "In7.Cu")
		(net 999)
	)
	(segment
		(start 182.58 124.49)
		(end 181.24 124.49)
		(width 0.1)
		(layer "In7.Cu")
		(net 999)
	)
	(segment
		(start 208.9 145.7)
		(end 208.9 140.8)
		(width 0.1)
		(layer "In7.Cu")
		(net 999)
	)
	(segment
		(start 208.5 140.4)
		(end 204.9 140.4)
		(width 0.1)
		(layer "In7.Cu")
		(net 999)
	)
	(segment
		(start 198.803553 135.603553)
		(end 189.353553 135.603553)
		(width 0.1)
		(layer "In7.Cu")
		(net 999)
	)
	(segment
		(start 155.861953 111.138047)
		(end 155.861953 115.638047)
		(width 0.1)
		(layer "In7.Cu")
		(net 999)
	)
	(segment
		(start 208.9 140.8)
		(end 208.5 140.4)
		(width 0.1)
		(layer "In7.Cu")
		(net 999)
	)
	(segment
		(start 183.25 125.16)
		(end 182.58 124.49)
		(width 0.1)
		(layer "In7.Cu")
		(net 999)
	)
	(segment
		(start 189.353553 135.603553)
		(end 183.25 129.5)
		(width 0.1)
		(layer "In7.Cu")
		(net 999)
	)
	(segment
		(start 203.6 138)
		(end 202.3 136.7)
		(width 0.1)
		(layer "In7.Cu")
		(net 999)
	)
	(segment
		(start 148.28 117.2)
		(end 149.1 117.2)
		(width 0.1)
		(layer "F.Cu")
		(net 1000)
	)
	(segment
		(start 149.1 117.2)
		(end 150.1 118.2)
		(width 0.1)
		(layer "F.Cu")
		(net 1000)
	)
	(segment
		(start 150.2 118.2)
		(end 150.256 118.256)
		(width 0.1)
		(layer "F.Cu")
		(net 1000)
	)
	(segment
		(start 150.1 118.2)
		(end 150.2 118.2)
		(width 0.1)
		(layer "F.Cu")
		(net 1000)
	)
	(segment
		(start 150.256 118.256)
		(end 151.231 118.256)
		(width 0.1)
		(layer "F.Cu")
		(net 1000)
	)
	(via
		(at 150.1 118.2)
		(size 0.45)
		(drill 0.1)
		(layers "F.Cu" "B.Cu")
		(net 1000)
	)
	(via
		(at 209.976 145)
		(size 0.45)
		(drill 0.1)
		(layers "F.Cu" "B.Cu")
		(net 1000)
	)
	(segment
		(start 209.206 145.01)
		(end 209.966 145.01)
		(width 0.1)
		(layer "B.Cu")
		(net 1000)
	)
	(segment
		(start 209.966 145.01)
		(end 209.976 145)
		(width 0.1)
		(layer "B.Cu")
		(net 1000)
	)
	(segment
		(start 155.5084 110.9916)
		(end 157.5 109)
		(width 0.1)
		(layer "In7.Cu")
		(net 1000)
	)
	(segment
		(start 203.9 137.8)
		(end 203.9 138.9)
		(width 0.1)
		(layer "In7.Cu")
		(net 1000)
	)
	(segment
		(start 205.1 140.1)
		(end 208.8 140.1)
		(width 0.1)
		(layer "In7.Cu")
		(net 1000)
	)
	(segment
		(start 183.603553 124.973553)
		(end 183.603553 129.353553)
		(width 0.1)
		(layer "In7.Cu")
		(net 1000)
	)
	(segment
		(start 157.5 109)
		(end 166.25 109)
		(width 0.1)
		(layer "In7.Cu")
		(net 1000)
	)
	(segment
		(start 150.1 118.2)
		(end 151.55 118.2)
		(width 0.1)
		(layer "In7.Cu")
		(net 1000)
	)
	(segment
		(start 182.79 124.16)
		(end 183.603553 124.973553)
		(width 0.1)
		(layer "In7.Cu")
		(net 1000)
	)
	(segment
		(start 183.603553 129.353553)
		(end 189.5 135.25)
		(width 0.1)
		(layer "In7.Cu")
		(net 1000)
	)
	(segment
		(start 202.5 136.4)
		(end 203.9 137.8)
		(width 0.1)
		(layer "In7.Cu")
		(net 1000)
	)
	(segment
		(start 200.1 136.4)
		(end 202.5 136.4)
		(width 0.1)
		(layer "In7.Cu")
		(net 1000)
	)
	(segment
		(start 198.95 135.25)
		(end 200.1 136.4)
		(width 0.1)
		(layer "In7.Cu")
		(net 1000)
	)
	(segment
		(start 166.25 109)
		(end 181.41 124.16)
		(width 0.1)
		(layer "In7.Cu")
		(net 1000)
	)
	(segment
		(start 189.5 135.25)
		(end 198.95 135.25)
		(width 0.1)
		(layer "In7.Cu")
		(net 1000)
	)
	(segment
		(start 151.55 118.2)
		(end 152.75 117)
		(width 0.1)
		(layer "In7.Cu")
		(net 1000)
	)
	(segment
		(start 152.75 117)
		(end 154 117)
		(width 0.1)
		(layer "In7.Cu")
		(net 1000)
	)
	(segment
		(start 203.9 138.9)
		(end 205.1 140.1)
		(width 0.1)
		(layer "In7.Cu")
		(net 1000)
	)
	(segment
		(start 155.5084 115.4916)
		(end 155.5084 110.9916)
		(width 0.1)
		(layer "In7.Cu")
		(net 1000)
	)
	(segment
		(start 209.3 140.6)
		(end 209.3 144.324)
		(width 0.1)
		(layer "In7.Cu")
		(net 1000)
	)
	(segment
		(start 208.8 140.1)
		(end 209.3 140.6)
		(width 0.1)
		(layer "In7.Cu")
		(net 1000)
	)
	(segment
		(start 209.3 144.324)
		(end 209.976 145)
		(width 0.1)
		(layer "In7.Cu")
		(net 1000)
	)
	(segment
		(start 181.41 124.16)
		(end 182.79 124.16)
		(width 0.1)
		(layer "In7.Cu")
		(net 1000)
	)
	(segment
		(start 154 117)
		(end 155.5084 115.4916)
		(width 0.1)
		(layer "In7.Cu")
		(net 1000)
	)
	(segment
		(start 89.55 148.199999)
		(end 88.280501 148.199999)
		(width 0.22)
		(layer "F.Cu")
		(net 1001)
	)
	(segment
		(start 88.280501 148.199999)
		(end 88.171001 148.090499)
		(width 0.22)
		(layer "F.Cu")
		(net 1001)
	)
	(segment
		(start 91.5 148.23)
		(end 92.475736 148.23)
		(width 0.19)
		(layer "F.Cu")
		(net 1002)
	)
	(segment
		(start 90.51 148.199999)
		(end 91.469999 148.199999)
		(width 0.19)
		(layer "F.Cu")
		(net 1002)
	)
	(segment
		(start 91.469999 148.199999)
		(end 91.5 148.23)
		(width 0.19)
		(layer "F.Cu")
		(net 1002)
	)
	(segment
		(start 92.475736 148.23)
		(end 92.5 148.205736)
		(width 0.19)
		(layer "F.Cu")
		(net 1002)
	)
	(segment
		(start 150.49 105.41)
		(end 151.825 105.41)
		(width 0.1)
		(layer "F.Cu")
		(net 1003)
	)
	(segment
		(start 156.7 108.1)
		(end 150.7 108.1)
		(width 0.1)
		(layer "F.Cu")
		(net 1003)
	)
	(segment
		(start 150 107.4)
		(end 150 105.9)
		(width 0.1)
		(layer "F.Cu")
		(net 1003)
	)
	(segment
		(start 150.7 108.1)
		(end 150 107.4)
		(width 0.1)
		(layer "F.Cu")
		(net 1003)
	)
	(segment
		(start 193.506 149.7)
		(end 194.276 149.7)
		(width 0.1)
		(layer "F.Cu")
		(net 1003)
	)
	(segment
		(start 150 105.9)
		(end 150.49 105.41)
		(width 0.1)
		(layer "F.Cu")
		(net 1003)
	)
	(segment
		(start 158.6 110)
		(end 156.7 108.1)
		(width 0.1)
		(layer "F.Cu")
		(net 1003)
	)
	(via
		(at 158.6 110)
		(size 0.45)
		(drill 0.1)
		(layers "F.Cu" "B.Cu")
		(net 1003)
	)
	(via
		(at 194.276 149.7)
		(size 0.45)
		(drill 0.1)
		(layers "F.Cu" "B.Cu")
		(net 1003)
	)
	(segment
		(start 193.55 136.65)
		(end 196.6 139.7)
		(width 0.1)
		(layer "In7.Cu")
		(net 1003)
	)
	(segment
		(start 202.8 146.3)
		(end 201.3 147.8)
		(width 0.1)
		(layer "In7.Cu")
		(net 1003)
	)
	(segment
		(start 168.23 119.63)
		(end 171.93 119.63)
		(width 0.1)
		(layer "In7.Cu")
		(net 1003)
	)
	(segment
		(start 177 124.7)
		(end 177 130.91)
		(width 0.1)
		(layer "In7.Cu")
		(net 1003)
	)
	(segment
		(start 171.93 119.63)
		(end 177 124.7)
		(width 0.1)
		(layer "In7.Cu")
		(net 1003)
	)
	(segment
		(start 185.7 132.8)
		(end 189.55 136.65)
		(width 0.1)
		(layer "In7.Cu")
		(net 1003)
	)
	(segment
		(start 158.6 110)
		(end 168.23 119.63)
		(width 0.1)
		(layer "In7.Cu")
		(net 1003)
	)
	(segment
		(start 177 130.91)
		(end 178.89 132.8)
		(width 0.1)
		(layer "In7.Cu")
		(net 1003)
	)
	(segment
		(start 189.55 136.65)
		(end 193.55 136.65)
		(width 0.1)
		(layer "In7.Cu")
		(net 1003)
	)
	(segment
		(start 202.6 142.1)
		(end 202.8 142.3)
		(width 0.1)
		(layer "In7.Cu")
		(net 1003)
	)
	(segment
		(start 197.6 142.1)
		(end 202.6 142.1)
		(width 0.1)
		(layer "In7.Cu")
		(net 1003)
	)
	(segment
		(start 202.8 142.3)
		(end 202.8 146.3)
		(width 0.1)
		(layer "In7.Cu")
		(net 1003)
	)
	(segment
		(start 196.176 147.8)
		(end 201.3 147.8)
		(width 0.1)
		(layer "In7.Cu")
		(net 1003)
	)
	(segment
		(start 196.176 147.8)
		(end 194.276 149.7)
		(width 0.1)
		(layer "In7.Cu")
		(net 1003)
	)
	(segment
		(start 196.6 139.7)
		(end 196.6 141.1)
		(width 0.1)
		(layer "In7.Cu")
		(net 1003)
	)
	(segment
		(start 196.6 141.1)
		(end 197.6 142.1)
		(width 0.1)
		(layer "In7.Cu")
		(net 1003)
	)
	(segment
		(start 178.89 132.8)
		(end 185.7 132.8)
		(width 0.1)
		(layer "In7.Cu")
		(net 1003)
	)
	(segment
		(start 149.7 107.524264)
		(end 149.7 105.7)
		(width 0.1)
		(layer "F.Cu")
		(net 1004)
	)
	(segment
		(start 149.7 105.7)
		(end 150.39 105.01)
		(width 0.1)
		(layer "F.Cu")
		(net 1004)
	)
	(segment
		(start 193.506 140.1)
		(end 194.226 140.1)
		(width 0.1)
		(layer "F.Cu")
		(net 1004)
	)
	(segment
		(start 158.2 110.4)
		(end 156.199999 108.399999)
		(width 0.1)
		(layer "F.Cu")
		(net 1004)
	)
	(segment
		(start 150.575735 108.399999)
		(end 149.7 107.524264)
		(width 0.1)
		(layer "F.Cu")
		(net 1004)
	)
	(segment
		(start 156.199999 108.399999)
		(end 150.575735 108.399999)
		(width 0.1)
		(layer "F.Cu")
		(net 1004)
	)
	(segment
		(start 194.226 140.1)
		(end 194.526 139.8)
		(width 0.1)
		(layer "F.Cu")
		(net 1004)
	)
	(segment
		(start 150.39 105.01)
		(end 151.825 105.01)
		(width 0.1)
		(layer "F.Cu")
		(net 1004)
	)
	(via
		(at 194.526 139.8)
		(size 0.45)
		(drill 0.1)
		(layers "F.Cu" "B.Cu")
		(net 1004)
	)
	(via
		(at 158.2 110.4)
		(size 0.45)
		(drill 0.1)
		(layers "F.Cu" "B.Cu")
		(net 1004)
	)
	(segment
		(start 189.4 137)
		(end 185.5 133.1)
		(width 0.1)
		(layer "In7.Cu")
		(net 1004)
	)
	(segment
		(start 178.5 133.1)
		(end 175.7 130.3)
		(width 0.1)
		(layer "In7.Cu")
		(net 1004)
	)
	(segment
		(start 193.3 137)
		(end 189.4 137)
		(width 0.1)
		(layer "In7.Cu")
		(net 1004)
	)
	(segment
		(start 175.7 130.3)
		(end 175.7 124.7)
		(width 0.1)
		(layer "In7.Cu")
		(net 1004)
	)
	(segment
		(start 175.7 124.7)
		(end 171.05 120.05)
		(width 0.1)
		(layer "In7.Cu")
		(net 1004)
	)
	(segment
		(start 185.5 133.1)
		(end 178.5 133.1)
		(width 0.1)
		(layer "In7.Cu")
		(net 1004)
	)
	(segment
		(start 194.526 138.226)
		(end 193.3 137)
		(width 0.1)
		(layer "In7.Cu")
		(net 1004)
	)
	(segment
		(start 171.05 120.05)
		(end 167.85 120.05)
		(width 0.1)
		(layer "In7.Cu")
		(net 1004)
	)
	(segment
		(start 167.85 120.05)
		(end 158.2 110.4)
		(width 0.1)
		(layer "In7.Cu")
		(net 1004)
	)
	(segment
		(start 194.526 139.8)
		(end 194.526 138.226)
		(width 0.1)
		(layer "In7.Cu")
		(net 1004)
	)
	(segment
		(start 126.9 120.7)
		(end 126.9 121.9)
		(width 0.1)
		(layer "B.Cu")
		(net 1005)
	)
	(segment
		(start 127 129.6)
		(end 126.9 129.5)
		(width 0.1)
		(layer "B.Cu")
		(net 1005)
	)
	(segment
		(start 126.9 129.7)
		(end 127 129.6)
		(width 0.1)
		(layer "B.Cu")
		(net 1005)
	)
	(segment
		(start 127.875 130.175)
		(end 127.3 129.6)
		(width 0.1)
		(layer "B.Cu")
		(net 1005)
	)
	(segment
		(start 126.9 129.5)
		(end 126.9 121.9)
		(width 0.1)
		(layer "B.Cu")
		(net 1005)
	)
	(segment
		(start 126.9 130.6)
		(end 126.7 130.8)
		(width 0.1)
		(layer "B.Cu")
		(net 1005)
	)
	(segment
		(start 125.08 110.8)
		(end 126.4 110.8)
		(width 0.1)
		(layer "B.Cu")
		(net 1005)
	)
	(segment
		(start 126.9 129.6)
		(end 126.9 129.5)
		(width 0.1)
		(layer "B.Cu")
		(net 1005)
	)
	(segment
		(start 126.7 130.8)
		(end 125.8 130.8)
		(width 0.1)
		(layer "B.Cu")
		(net 1005)
	)
	(segment
		(start 126.9 129.7)
		(end 126.9 129.6)
		(width 0.1)
		(layer "B.Cu")
		(net 1005)
	)
	(segment
		(start 127 129.6)
		(end 126.9 129.6)
		(width 0.1)
		(layer "B.Cu")
		(net 1005)
	)
	(segment
		(start 126.9 111.3)
		(end 126.4 110.8)
		(width 0.1)
		(layer "B.Cu")
		(net 1005)
	)
	(segment
		(start 125.08 130.8)
		(end 125.8 130.8)
		(width 0.1)
		(layer "B.Cu")
		(net 1005)
	)
	(segment
		(start 126.9 120.7)
		(end 126.9 111.3)
		(width 0.1)
		(layer "B.Cu")
		(net 1005)
	)
	(segment
		(start 127.3 129.6)
		(end 127 129.6)
		(width 0.1)
		(layer "B.Cu")
		(net 1005)
	)
	(segment
		(start 126.9 129.7)
		(end 126.9 130.6)
		(width 0.1)
		(layer "B.Cu")
		(net 1005)
	)
	(segment
		(start 127.875 131.277)
		(end 127.875 130.175)
		(width 0.1)
		(layer "B.Cu")
		(net 1005)
	)
	(segment
		(start 161.74 56)
		(end 161.75 56)
		(width 0.1)
		(layer "F.Cu")
		(net 1008)
	)
	(via
		(at 161.75 56)
		(size 0.45)
		(drill 0.1)
		(layers "F.Cu" "B.Cu")
		(net 1008)
	)
	(segment
		(start 161.8 57.02)
		(end 161.8 56.05)
		(width 0.1)
		(layer "B.Cu")
		(net 1008)
	)
	(segment
		(start 161.8 56.05)
		(end 161.75 56)
		(width 0.1)
		(layer "B.Cu")
		(net 1008)
	)
	(segment
		(start 135.8 63.575)
		(end 135.604 63.379)
		(width 0.1)
		(layer "B.Cu")
		(net 1009)
	)
	(segment
		(start 135.8 64.72)
		(end 135.8 63.575)
		(width 0.1)
		(layer "B.Cu")
		(net 1009)
	)
	(segment
		(start 143.6 64.72)
		(end 143.6 63.383)
		(width 0.1)
		(layer "B.Cu")
		(net 1010)
	)
	(segment
		(start 143.6 63.383)
		(end 143.604 63.379)
		(width 0.1)
		(layer "B.Cu")
		(net 1010)
	)
	(segment
		(start 216.874 101.726)
		(end 217.2 101.4)
		(width 0.1)
		(layer "F.Cu")
		(net 1011)
	)
	(segment
		(start 216.445 101.726)
		(end 216.874 101.726)
		(width 0.1)
		(layer "F.Cu")
		(net 1011)
	)
	(via
		(at 204.4 101.8)
		(size 0.45)
		(drill 0.1)
		(layers "F.Cu" "B.Cu")
		(net 1011)
	)
	(via
		(at 217.2 101.4)
		(size 0.45)
		(drill 0.1)
		(layers "F.Cu" "B.Cu")
		(net 1011)
	)
	(segment
		(start 204.92 101.8)
		(end 204.4 101.8)
		(width 0.3)
		(layer "B.Cu")
		(net 1011)
	)
	(segment
		(start 203.88 101.800001)
		(end 204.4 101.8)
		(width 0.3)
		(layer "B.Cu")
		(net 1011)
	)
	(segment
		(start 204.3 101.9)
		(end 204.3 103)
		(width 0.1)
		(layer "In5.Cu")
		(net 1011)
	)
	(segment
		(start 204.4 101.8)
		(end 204.3 101.9)
		(width 0.1)
		(layer "In5.Cu")
		(net 1011)
	)
	(segment
		(start 210.2 102.6)
		(end 216 102.6)
		(width 0.1)
		(layer "In5.Cu")
		(net 1011)
	)
	(segment
		(start 209.6 103.2)
		(end 210.2 102.6)
		(width 0.1)
		(layer "In5.Cu")
		(net 1011)
	)
	(segment
		(start 204.3 103)
		(end 204.5 103.2)
		(width 0.1)
		(layer "In5.Cu")
		(net 1011)
	)
	(segment
		(start 204.5 103.2)
		(end 209.6 103.2)
		(width 0.1)
		(layer "In5.Cu")
		(net 1011)
	)
	(segment
		(start 216 102.6)
		(end 217.2 101.4)
		(width 0.1)
		(layer "In5.Cu")
		(net 1011)
	)
	(segment
		(start 214.046 101.726)
		(end 213.426 101.726)
		(width 0.1)
		(layer "F.Cu")
		(net 1012)
	)
	(segment
		(start 213.426 101.726)
		(end 213.2 101.5)
		(width 0.1)
		(layer "F.Cu")
		(net 1012)
	)
	(via
		(at 213.2 101.5)
		(size 0.45)
		(drill 0.1)
		(layers "F.Cu" "B.Cu")
		(net 1012)
	)
	(via
		(at 204.7 102.8)
		(size 0.45)
		(drill 0.1)
		(layers "F.Cu" "B.Cu")
		(net 1012)
	)
	(segment
		(start 203.88 102.8)
		(end 204.7 102.8)
		(width 0.1)
		(layer "B.Cu")
		(net 1012)
	)
	(segment
		(start 204.7 102.8)
		(end 206.725 100.775)
		(width 0.1)
		(layer "In5.Cu")
		(net 1012)
	)
	(segment
		(start 209.975 100.775)
		(end 210.7 101.5)
		(width 0.1)
		(layer "In5.Cu")
		(net 1012)
	)
	(segment
		(start 210.7 101.5)
		(end 213.2 101.5)
		(width 0.1)
		(layer "In5.Cu")
		(net 1012)
	)
	(segment
		(start 206.725 100.775)
		(end 209.975 100.775)
		(width 0.1)
		(layer "In5.Cu")
		(net 1012)
	)
	(segment
		(start 213.8 105.6)
		(end 213.8 106.52)
		(width 0.1)
		(layer "F.Cu")
		(net 1013)
	)
	(segment
		(start 214.445 104.526)
		(end 214.445 104.955)
		(width 0.1)
		(layer "F.Cu")
		(net 1013)
	)
	(segment
		(start 214.445 104.955)
		(end 213.8 105.6)
		(width 0.1)
		(layer "F.Cu")
		(net 1013)
	)
	(segment
		(start 216.85 100.7)
		(end 216.85 100.65)
		(width 0.1)
		(layer "F.Cu")
		(net 1014)
	)
	(segment
		(start 216.625 100.925)
		(end 216.85 100.7)
		(width 0.1)
		(layer "F.Cu")
		(net 1014)
	)
	(segment
		(start 216.85 100.65)
		(end 217.2 100.3)
		(width 0.1)
		(layer "F.Cu")
		(net 1014)
	)
	(segment
		(start 216.445 100.925)
		(end 216.625 100.925)
		(width 0.1)
		(layer "F.Cu")
		(net 1014)
	)
	(via
		(at 217.2 100.3)
		(size 0.45)
		(drill 0.1)
		(layers "F.Cu" "B.Cu")
		(net 1014)
	)
	(segment
		(start 217.2 100.3)
		(end 216.38 100.3)
		(width 0.1)
		(layer "B.Cu")
		(net 1014)
	)
	(segment
		(start 216.38 100.3)
		(end 216.28 100.4)
		(width 0.1)
		(layer "B.Cu")
		(net 1014)
	)
	(segment
		(start 217.2 100.3)
		(end 218.2 100.3)
		(width 0.1)
		(layer "B.Cu")
		(net 1014)
	)
	(segment
		(start 234.404 133.996)
		(end 235.4 133)
		(width 0.1)
		(layer "B.Cu")
		(net 1015)
	)
	(segment
		(start 235.42 133)
		(end 235.4 133)
		(width 0.1)
		(layer "B.Cu")
		(net 1015)
	)
	(segment
		(start 233.699 133.996)
		(end 234.404 133.996)
		(width 0.1)
		(layer "B.Cu")
		(net 1015)
	)
	(segment
		(start 206.15 119.15)
		(end 206.15 119.24)
		(width 0.1)
		(layer "F.Cu")
		(net 1016)
	)
	(segment
		(start 206.15 119.24)
		(end 206.155 119.245)
		(width 0.1)
		(layer "F.Cu")
		(net 1016)
	)
	(segment
		(start 206.155 119.245)
		(end 206.155 119.911)
		(width 0.1)
		(layer "F.Cu")
		(net 1016)
	)
	(via
		(at 206.15 119.15)
		(size 0.45)
		(drill 0.1)
		(layers "F.Cu" "B.Cu")
		(net 1016)
	)
	(segment
		(start 206.15 119.93)
		(end 206.22 120)
		(width 0.1)
		(layer "B.Cu")
		(net 1016)
	)
	(segment
		(start 206.22 120)
		(end 206.22 121)
		(width 0.1)
		(layer "B.Cu")
		(net 1016)
	)
	(segment
		(start 206.15 119.15)
		(end 206.15 119.93)
		(width 0.1)
		(layer "B.Cu")
		(net 1016)
	)
	(segment
		(start 197.9 108)
		(end 189.1 108)
		(width 0.1)
		(layer "F.Cu")
		(net 1017)
	)
	(segment
		(start 149.2 104.6)
		(end 149.2 107.4)
		(width 0.1)
		(layer "F.Cu")
		(net 1017)
	)
	(segment
		(start 160.4 117)
		(end 165 112.4)
		(width 0.1)
		(layer "F.Cu")
		(net 1017)
	)
	(segment
		(start 149.2 107.4)
		(end 150.4 108.6)
		(width 0.1)
		(layer "F.Cu")
		(net 1017)
	)
	(segment
		(start 165 108.1)
		(end 168.8 104.3)
		(width 0.1)
		(layer "F.Cu")
		(net 1017)
	)
	(segment
		(start 203.9 107.9)
		(end 203.7 107.7)
		(width 0.1)
		(layer "F.Cu")
		(net 1017)
	)
	(segment
		(start 150.4 108.6)
		(end 155.8 108.6)
		(width 0.1)
		(layer "F.Cu")
		(net 1017)
	)
	(segment
		(start 203.7 107.7)
		(end 198.2 107.7)
		(width 0.1)
		(layer "F.Cu")
		(net 1017)
	)
	(segment
		(start 155.8 108.6)
		(end 158.1 110.9)
		(width 0.1)
		(layer "F.Cu")
		(net 1017)
	)
	(segment
		(start 151.675 104.21)
		(end 149.59 104.21)
		(width 0.1)
		(layer "F.Cu")
		(net 1017)
	)
	(segment
		(start 204.5 107.9)
		(end 203.9 107.9)
		(width 0.1)
		(layer "F.Cu")
		(net 1017)
	)
	(segment
		(start 158.1 110.9)
		(end 158.1 114.8)
		(width 0.1)
		(layer "F.Cu")
		(net 1017)
	)
	(segment
		(start 198.2 107.7)
		(end 197.9 108)
		(width 0.1)
		(layer "F.Cu")
		(net 1017)
	)
	(segment
		(start 165 112.4)
		(end 165 108.1)
		(width 0.1)
		(layer "F.Cu")
		(net 1017)
	)
	(segment
		(start 149.59 104.21)
		(end 149.2 104.6)
		(width 0.1)
		(layer "F.Cu")
		(net 1017)
	)
	(via
		(at 158.1 114.8)
		(size 0.45)
		(drill 0.1)
		(layers "F.Cu" "B.Cu")
		(net 1017)
	)
	(via
		(at 160.4 117)
		(size 0.45)
		(drill 0.1)
		(layers "F.Cu" "B.Cu")
		(net 1017)
	)
	(via
		(at 204.5 107.9)
		(size 0.45)
		(drill 0.1)
		(layers "F.Cu" "B.Cu")
		(net 1017)
	)
	(via
		(at 189.1 108)
		(size 0.45)
		(drill 0.1)
		(layers "F.Cu" "B.Cu")
		(net 1017)
	)
	(via
		(at 168.8 104.3)
		(size 0.45)
		(drill 0.1)
		(layers "F.Cu" "B.Cu")
		(net 1017)
	)
	(via
		(at 238.7 108.5)
		(size 0.45)
		(drill 0.1)
		(layers "F.Cu" "B.Cu")
		(net 1017)
	)
	(segment
		(start 238.7 108.5)
		(end 238.7 107.844468)
		(width 0.1)
		(layer "B.Cu")
		(net 1017)
	)
	(segment
		(start 189.1 108)
		(end 188.4 108)
		(width 0.1)
		(layer "B.Cu")
		(net 1017)
	)
	(segment
		(start 184.7 104.3)
		(end 168.8 104.3)
		(width 0.1)
		(layer "B.Cu")
		(net 1017)
	)
	(segment
		(start 158.2 114.8)
		(end 158.1 114.8)
		(width 0.1)
		(layer "B.Cu")
		(net 1017)
	)
	(segment
		(start 238.7 107.844468)
		(end 238.68 107.824468)
		(width 0.1)
		(layer "B.Cu")
		(net 1017)
	)
	(segment
		(start 188.4 108)
		(end 184.7 104.3)
		(width 0.1)
		(layer "B.Cu")
		(net 1017)
	)
	(segment
		(start 160.4 117)
		(end 158.2 114.8)
		(width 0.1)
		(layer "B.Cu")
		(net 1017)
	)
	(segment
		(start 204.5 107.9)
		(end 204.5 109)
		(width 0.1)
		(layer "In5.Cu")
		(net 1017)
	)
	(segment
		(start 238.25 108.5)
		(end 238.7 108.5)
		(width 0.1)
		(layer "In5.Cu")
		(net 1017)
	)
	(segment
		(start 225.1 110.6)
		(end 226.4 109.3)
		(width 0.1)
		(layer "In5.Cu")
		(net 1017)
	)
	(segment
		(start 204.5 109)
		(end 206.1 110.6)
		(width 0.1)
		(layer "In5.Cu")
		(net 1017)
	)
	(segment
		(start 237.45 109.3)
		(end 238.25 108.5)
		(width 0.1)
		(layer "In5.Cu")
		(net 1017)
	)
	(segment
		(start 206.1 110.6)
		(end 225.1 110.6)
		(width 0.1)
		(layer "In5.Cu")
		(net 1017)
	)
	(segment
		(start 226.4 109.3)
		(end 237.45 109.3)
		(width 0.1)
		(layer "In5.Cu")
		(net 1017)
	)
	(segment
		(start 151.675 103.01)
		(end 150.29 103.01)
		(width 0.1)
		(layer "F.Cu")
		(net 1018)
	)
	(segment
		(start 150.29 103.01)
		(end 150.05 103.25)
		(width 0.1)
		(layer "F.Cu")
		(net 1018)
	)
	(via
		(at 216.8 107.5)
		(size 0.45)
		(drill 0.1)
		(layers "F.Cu" "B.Cu")
		(net 1018)
	)
	(via
		(at 150.05 103.25)
		(size 0.45)
		(drill 0.1)
		(layers "F.Cu" "B.Cu")
		(net 1018)
	)
	(segment
		(start 220.8 107.5)
		(end 221.848 108.548)
		(width 0.1)
		(layer "B.Cu")
		(net 1018)
	)
	(segment
		(start 221.848 108.548)
		(end 223.2 108.548)
		(width 0.1)
		(layer "B.Cu")
		(net 1018)
	)
	(segment
		(start 216.8 107.5)
		(end 220.8 107.5)
		(width 0.1)
		(layer "B.Cu")
		(net 1018)
	)
	(segment
		(start 223.48 107.4)
		(end 223.48 108.268)
		(width 0.1)
		(layer "B.Cu")
		(net 1018)
	)
	(segment
		(start 223.48 108.268)
		(end 223.2 108.548)
		(width 0.1)
		(layer "B.Cu")
		(net 1018)
	)
	(segment
		(start 156.8 106.8)
		(end 158.6 105)
		(width 0.1)
		(layer "In7.Cu")
		(net 1018)
	)
	(segment
		(start 151.2 106.8)
		(end 156.8 106.8)
		(width 0.1)
		(layer "In7.Cu")
		(net 1018)
	)
	(segment
		(start 149.2 103.75)
		(end 149.2 104.8)
		(width 0.1)
		(layer "In7.Cu")
		(net 1018)
	)
	(segment
		(start 150.05 103.25)
		(end 149.7 103.25)
		(width 0.1)
		(layer "In7.Cu")
		(net 1018)
	)
	(segment
		(start 198 109)
		(end 199.5 107.5)
		(width 0.1)
		(layer "In7.Cu")
		(net 1018)
	)
	(segment
		(start 186.2 109)
		(end 198 109)
		(width 0.1)
		(layer "In7.Cu")
		(net 1018)
	)
	(segment
		(start 158.6 105)
		(end 182.2 105)
		(width 0.1)
		(layer "In7.Cu")
		(net 1018)
	)
	(segment
		(start 149.2 104.8)
		(end 151.2 106.8)
		(width 0.1)
		(layer "In7.Cu")
		(net 1018)
	)
	(segment
		(start 199.5 107.5)
		(end 216.8 107.5)
		(width 0.1)
		(layer "In7.Cu")
		(net 1018)
	)
	(segment
		(start 149.7 103.25)
		(end 149.2 103.75)
		(width 0.1)
		(layer "In7.Cu")
		(net 1018)
	)
	(segment
		(start 182.2 105)
		(end 186.2 109)
		(width 0.1)
		(layer "In7.Cu")
		(net 1018)
	)
	(segment
		(start 219.683 112.308)
		(end 219.13 112.861)
		(width 0.1)
		(layer "B.Cu")
		(net 1019)
	)
	(segment
		(start 219.683 112.019)
		(end 219.683 112.308)
		(width 0.1)
		(layer "B.Cu")
		(net 1019)
	)
	(segment
		(start 234.45 108.65)
		(end 234.625 108.825)
		(width 0.1)
		(layer "B.Cu")
		(net 1020)
	)
	(segment
		(start 234.625 108.825)
		(end 235.214 108.825)
		(width 0.1)
		(layer "B.Cu")
		(net 1020)
	)
	(segment
		(start 233.7 108.65)
		(end 234.45 108.65)
		(width 0.1)
		(layer "B.Cu")
		(net 1020)
	)
	(segment
		(start 214.8 104.572)
		(end 214.846 104.526)
		(width 0.1)
		(layer "F.Cu")
		(net 1021)
	)
	(segment
		(start 214.8 106.52)
		(end 214.8 104.572)
		(width 0.1)
		(layer "F.Cu")
		(net 1021)
	)
	(segment
		(start 214.9 98.68)
		(end 214.9 100.071)
		(width 0.1)
		(layer "F.Cu")
		(net 1022)
	)
	(segment
		(start 214.9 100.071)
		(end 214.846 100.125)
		(width 0.1)
		(layer "F.Cu")
		(net 1022)
	)
	(segment
		(start 212.4 101.1)
		(end 213.5 101.1)
		(width 0.1)
		(layer "F.Cu")
		(net 1023)
	)
	(segment
		(start 213.5 101.1)
		(end 213.725 101.325)
		(width 0.1)
		(layer "F.Cu")
		(net 1023)
	)
	(segment
		(start 213.725 101.325)
		(end 214.046 101.325)
		(width 0.1)
		(layer "F.Cu")
		(net 1023)
	)
	(via
		(at 204.7 103.8)
		(size 0.45)
		(drill 0.1)
		(layers "F.Cu" "B.Cu")
		(net 1023)
	)
	(via
		(at 212.4 101.1)
		(size 0.45)
		(drill 0.1)
		(layers "F.Cu" "B.Cu")
		(net 1023)
	)
	(segment
		(start 203.88 103.8)
		(end 204.7 103.8)
		(width 0.1)
		(layer "B.Cu")
		(net 1023)
	)
	(segment
		(start 203.8 103.6)
		(end 204 103.8)
		(width 0.1)
		(layer "In5.Cu")
		(net 1023)
	)
	(segment
		(start 211.2 101.1)
		(end 210.4 100.3)
		(width 0.1)
		(layer "In5.Cu")
		(net 1023)
	)
	(segment
		(start 210.4 100.3)
		(end 205 100.3)
		(width 0.1)
		(layer "In5.Cu")
		(net 1023)
	)
	(segment
		(start 203.8 101.5)
		(end 203.8 103.6)
		(width 0.1)
		(layer "In5.Cu")
		(net 1023)
	)
	(segment
		(start 212.4 101.1)
		(end 211.2 101.1)
		(width 0.1)
		(layer "In5.Cu")
		(net 1023)
	)
	(segment
		(start 204 103.8)
		(end 204.7 103.8)
		(width 0.1)
		(layer "In5.Cu")
		(net 1023)
	)
	(segment
		(start 205 100.3)
		(end 203.8 101.5)
		(width 0.1)
		(layer "In5.Cu")
		(net 1023)
	)
	(segment
		(start 216.624 100.526)
		(end 216.8 100.35)
		(width 0.1)
		(layer "F.Cu")
		(net 1024)
	)
	(segment
		(start 216.8 100.35)
		(end 216.8 99.95)
		(width 0.1)
		(layer "F.Cu")
		(net 1024)
	)
	(segment
		(start 217.05 99.7)
		(end 217.15 99.7)
		(width 0.1)
		(layer "F.Cu")
		(net 1024)
	)
	(segment
		(start 216.8 99.95)
		(end 217.05 99.7)
		(width 0.1)
		(layer "F.Cu")
		(net 1024)
	)
	(segment
		(start 216.471 100.526)
		(end 216.624 100.526)
		(width 0.1)
		(layer "F.Cu")
		(net 1024)
	)
	(via
		(at 204.4 105.8)
		(size 0.45)
		(drill 0.1)
		(layers "F.Cu" "B.Cu")
		(net 1024)
	)
	(via
		(at 217.15 99.7)
		(size 0.45)
		(drill 0.1)
		(layers "F.Cu" "B.Cu")
		(net 1024)
	)
	(segment
		(start 203.88 105.800001)
		(end 204.399999 105.800001)
		(width 0.3)
		(layer "B.Cu")
		(net 1024)
	)
	(segment
		(start 204.4 105.8)
		(end 204.399999 105.800001)
		(width 0.3)
		(layer "B.Cu")
		(net 1024)
	)
	(segment
		(start 204.4 105.8)
		(end 204.92 105.800001)
		(width 0.3)
		(layer "B.Cu")
		(net 1024)
	)
	(segment
		(start 203.3 105.6)
		(end 203.3 101.2)
		(width 0.1)
		(layer "In5.Cu")
		(net 1024)
	)
	(segment
		(start 203.3 101.2)
		(end 204.6 99.9)
		(width 0.1)
		(layer "In5.Cu")
		(net 1024)
	)
	(segment
		(start 212 100.6)
		(end 212.430331 100.6)
		(width 0.1)
		(layer "In5.Cu")
		(net 1024)
	)
	(segment
		(start 212.430331 100.6)
		(end 212.930331 101.1)
		(width 0.1)
		(layer "In5.Cu")
		(net 1024)
	)
	(segment
		(start 204.4 105.8)
		(end 203.5 105.8)
		(width 0.1)
		(layer "In5.Cu")
		(net 1024)
	)
	(segment
		(start 212.930331 101.1)
		(end 215.75 101.1)
		(width 0.1)
		(layer "In5.Cu")
		(net 1024)
	)
	(segment
		(start 215.75 101.1)
		(end 217.15 99.7)
		(width 0.1)
		(layer "In5.Cu")
		(net 1024)
	)
	(segment
		(start 203.5 105.8)
		(end 203.3 105.6)
		(width 0.1)
		(layer "In5.Cu")
		(net 1024)
	)
	(segment
		(start 211.3 99.9)
		(end 212 100.6)
		(width 0.1)
		(layer "In5.Cu")
		(net 1024)
	)
	(segment
		(start 204.6 99.9)
		(end 211.3 99.9)
		(width 0.1)
		(layer "In5.Cu")
		(net 1024)
	)
	(segment
		(start 216.046 99.704)
		(end 216.35 99.4)
		(width 0.1)
		(layer "F.Cu")
		(net 1025)
	)
	(segment
		(start 216.046 100.125)
		(end 216.046 99.704)
		(width 0.1)
		(layer "F.Cu")
		(net 1025)
	)
	(segment
		(start 216.35 99.4)
		(end 216.4 99.4)
		(width 0.1)
		(layer "F.Cu")
		(net 1025)
	)
	(via
		(at 204.4 104.8)
		(size 0.45)
		(drill 0.1)
		(layers "F.Cu" "B.Cu")
		(net 1025)
	)
	(via
		(at 216.4 99.4)
		(size 0.45)
		(drill 0.1)
		(layers "F.Cu" "B.Cu")
		(net 1025)
	)
	(segment
		(start 204.915 104.79)
		(end 204.41 104.79)
		(width 0.1)
		(layer "B.Cu")
		(net 1025)
	)
	(segment
		(start 203.88 104.8)
		(end 204.905 104.8)
		(width 0.3)
		(layer "B.Cu")
		(net 1025)
	)
	(segment
		(start 204.905 104.8)
		(end 204.915 104.79)
		(width 0.3)
		(layer "B.Cu")
		(net 1025)
	)
	(segment
		(start 204.41 104.79)
		(end 204.4 104.8)
		(width 0.1)
		(layer "B.Cu")
		(net 1025)
	)
	(segment
		(start 203.88 104.8)
		(end 204.4 104.8)
		(width 0.1)
		(layer "B.Cu")
		(net 1025)
	)
	(segment
		(start 216.8 99)
		(end 216.4 99.4)
		(width 0.1)
		(layer "In5.Cu")
		(net 1025)
	)
	(segment
		(start 207.7 106)
		(end 214 106)
		(width 0.1)
		(layer "In5.Cu")
		(net 1025)
	)
	(segment
		(start 206.5 104.8)
		(end 207.7 106)
		(width 0.1)
		(layer "In5.Cu")
		(net 1025)
	)
	(segment
		(start 214 106)
		(end 218.2 101.8)
		(width 0.1)
		(layer "In5.Cu")
		(net 1025)
	)
	(segment
		(start 217.5 99)
		(end 216.8 99)
		(width 0.1)
		(layer "In5.Cu")
		(net 1025)
	)
	(segment
		(start 204.4 104.8)
		(end 206.5 104.8)
		(width 0.1)
		(layer "In5.Cu")
		(net 1025)
	)
	(segment
		(start 218.2 101.8)
		(end 218.2 99.7)
		(width 0.1)
		(layer "In5.Cu")
		(net 1025)
	)
	(segment
		(start 218.2 99.7)
		(end 217.5 99)
		(width 0.1)
		(layer "In5.Cu")
		(net 1025)
	)
	(segment
		(start 151.675 103.41)
		(end 150.875 103.41)
		(width 0.1)
		(layer "F.Cu")
		(net 1026)
	)
	(via
		(at 150.875 103.41)
		(size 0.45)
		(drill 0.1)
		(layers "F.Cu" "B.Cu")
		(net 1026)
	)
	(via
		(at 203.6 108.2)
		(size 0.45)
		(drill 0.1)
		(layers "F.Cu" "B.Cu")
		(net 1026)
	)
	(via
		(at 189.6 109.4)
		(size 0.45)
		(drill 0.1)
		(layers "F.Cu" "B.Cu")
		(net 1026)
	)
	(segment
		(start 176.7 120.1)
		(end 187.4 109.4)
		(width 0.1)
		(layer "B.Cu")
		(net 1026)
	)
	(segment
		(start 202.92 106.800001)
		(end 202.92 107.52)
		(width 0.1)
		(layer "B.Cu")
		(net 1026)
	)
	(segment
		(start 151.31 103.41)
		(end 152.3 104.4)
		(width 0.1)
		(layer "B.Cu")
		(net 1026)
	)
	(segment
		(start 154.4 109.4)
		(end 161.5 109.4)
		(width 0.1)
		(layer "B.Cu")
		(net 1026)
	)
	(segment
		(start 150.875 103.41)
		(end 151.31 103.41)
		(width 0.1)
		(layer "B.Cu")
		(net 1026)
	)
	(segment
		(start 167.1 120.1)
		(end 176.7 120.1)
		(width 0.1)
		(layer "B.Cu")
		(net 1026)
	)
	(segment
		(start 202.92 107.52)
		(end 203.6 108.2)
		(width 0.1)
		(layer "B.Cu")
		(net 1026)
	)
	(segment
		(start 161.5 109.4)
		(end 164 111.9)
		(width 0.1)
		(layer "B.Cu")
		(net 1026)
	)
	(segment
		(start 187.4 109.4)
		(end 189.6 109.4)
		(width 0.1)
		(layer "B.Cu")
		(net 1026)
	)
	(segment
		(start 164 111.9)
		(end 164 117)
		(width 0.1)
		(layer "B.Cu")
		(net 1026)
	)
	(segment
		(start 152.3 104.4)
		(end 152.3 107.3)
		(width 0.1)
		(layer "B.Cu")
		(net 1026)
	)
	(segment
		(start 164 117)
		(end 167.1 120.1)
		(width 0.1)
		(layer "B.Cu")
		(net 1026)
	)
	(segment
		(start 152.3 107.3)
		(end 154.4 109.4)
		(width 0.1)
		(layer "B.Cu")
		(net 1026)
	)
	(segment
		(start 203.6 108.2)
		(end 199.7 108.2)
		(width 0.1)
		(layer "In7.Cu")
		(net 1026)
	)
	(segment
		(start 189.6 109.4)
		(end 198.5 109.4)
		(width 0.1)
		(layer "In7.Cu")
		(net 1026)
	)
	(segment
		(start 199.7 108.2)
		(end 198.5 109.4)
		(width 0.1)
		(layer "In7.Cu")
		(net 1026)
	)
	(segment
		(start 88.48 60.5)
		(end 88.48 61.5)
		(width 0.1)
		(layer "F.Cu")
		(net 1027)
	)
	(segment
		(start 88.48 61.5)
		(end 89.15 61.5)
		(width 0.1)
		(layer "F.Cu")
		(net 1027)
	)
	(segment
		(start 88.48 60.5)
		(end 89.74 60.5)
		(width 0.1)
		(layer "F.Cu")
		(net 1027)
	)
	(segment
		(start 89.74 60.5)
		(end 89.786 60.454)
		(width 0.1)
		(layer "F.Cu")
		(net 1027)
	)
	(via
		(at 89.15 61.5)
		(size 0.45)
		(drill 0.1)
		(layers "F.Cu" "B.Cu")
		(net 1027)
	)
	(segment
		(start 158.26 67.24)
		(end 159.081 67.24)
		(width 0.1)
		(layer "B.Cu")
		(net 1028)
	)
	(segment
		(start 157.63 67.53)
		(end 157.97 67.53)
		(width 0.1)
		(layer "B.Cu")
		(net 1028)
	)
	(segment
		(start 157.97 67.53)
		(end 158.26 67.24)
		(width 0.1)
		(layer "B.Cu")
		(net 1028)
	)
	(segment
		(start 158.26 66.74)
		(end 159.081 66.74)
		(width 0.1)
		(layer "B.Cu")
		(net 1029)
	)
	(segment
		(start 157.63 66.51)
		(end 158.01 66.51)
		(width 0.1)
		(layer "B.Cu")
		(net 1029)
	)
	(segment
		(start 158.01 66.51)
		(end 158.25 66.75)
		(width 0.1)
		(layer "B.Cu")
		(net 1029)
	)
	(segment
		(start 158.25 66.75)
		(end 158.26 66.74)
		(width 0.1)
		(layer "B.Cu")
		(net 1029)
	)
	(segment
		(start 158.36 66.24)
		(end 159.081 66.24)
		(width 0.1)
		(layer "B.Cu")
		(net 1030)
	)
	(segment
		(start 157.62 65.5)
		(end 158.36 66.24)
		(width 0.1)
		(layer "B.Cu")
		(net 1030)
	)
	(segment
		(start 158.25 68)
		(end 158.516 67.734)
		(width 0.1)
		(layer "B.Cu")
		(net 1031)
	)
	(segment
		(start 158.05 68.55)
		(end 158.25 68.35)
		(width 0.1)
		(layer "B.Cu")
		(net 1031)
	)
	(segment
		(start 158.25 68.35)
		(end 158.25 68)
		(width 0.1)
		(layer "B.Cu")
		(net 1031)
	)
	(segment
		(start 158.516 67.734)
		(end 159.081 67.734)
		(width 0.1)
		(layer "B.Cu")
		(net 1031)
	)
	(segment
		(start 157.63 68.55)
		(end 158.05 68.55)
		(width 0.1)
		(layer "B.Cu")
		(net 1031)
	)
	(segment
		(start 96.62 61.9)
		(end 96.62 61.52)
		(width 0.1)
		(layer "F.Cu")
		(net 1032)
	)
	(segment
		(start 91.1 63.8)
		(end 91.1 61.68)
		(width 0.1)
		(layer "F.Cu")
		(net 1032)
	)
	(segment
		(start 90.75 64.15)
		(end 91.1 63.8)
		(width 0.1)
		(layer "F.Cu")
		(net 1032)
	)
	(segment
		(start 89.9 64.5)
		(end 90.48 65.08)
		(width 0.1)
		(layer "F.Cu")
		(net 1032)
	)
	(segment
		(start 96.62 61.52)
		(end 96.1 61)
		(width 0.1)
		(layer "F.Cu")
		(net 1032)
	)
	(segment
		(start 91.1 61.68)
		(end 91.59 61.19)
		(width 0.1)
		(layer "F.Cu")
		(net 1032)
	)
	(segment
		(start 90.48 65.08)
		(end 90.48 65.45)
		(width 0.1)
		(layer "F.Cu")
		(net 1032)
	)
	(segment
		(start 92.23 61.19)
		(end 91.59 61.19)
		(width 0.1)
		(layer "F.Cu")
		(net 1032)
	)
	(segment
		(start 88.48 64.5)
		(end 89 64.5)
		(width 0.1)
		(layer "F.Cu")
		(net 1032)
	)
	(segment
		(start 89.9 64.15)
		(end 90.75 64.15)
		(width 0.1)
		(layer "F.Cu")
		(net 1032)
	)
	(segment
		(start 96.1 61)
		(end 92.42 61)
		(width 0.1)
		(layer "F.Cu")
		(net 1032)
	)
	(segment
		(start 92.42 61)
		(end 92.23 61.19)
		(width 0.1)
		(layer "F.Cu")
		(net 1032)
	)
	(segment
		(start 89.9 64.15)
		(end 89.9 64.5)
		(width 0.1)
		(layer "F.Cu")
		(net 1032)
	)
	(segment
		(start 88.48 65.5)
		(end 88.48 64.5)
		(width 0.1)
		(layer "F.Cu")
		(net 1032)
	)
	(segment
		(start 89.35 64.15)
		(end 89.9 64.15)
		(width 0.1)
		(layer "F.Cu")
		(net 1032)
	)
	(segment
		(start 89 64.5)
		(end 89.35 64.15)
		(width 0.1)
		(layer "F.Cu")
		(net 1032)
	)
	(segment
		(start 91.59 61.19)
		(end 91.15 60.75)
		(width 0.1)
		(layer "F.Cu")
		(net 1032)
	)
	(via
		(at 91.15 60.75)
		(size 0.45)
		(drill 0.1)
		(layers "F.Cu" "B.Cu")
		(net 1032)
	)
	(segment
		(start 91.17 60.77)
		(end 91.17 62.68)
		(width 0.1)
		(layer "B.Cu")
		(net 1032)
	)
	(segment
		(start 91.15 60.75)
		(end 91.17 60.77)
		(width 0.1)
		(layer "B.Cu")
		(net 1032)
	)
	(segment
		(start 89.786 57.786)
		(end 89.786 58.553)
		(width 0.1)
		(layer "F.Cu")
		(net 1033)
	)
	(segment
		(start 89.5 57.5)
		(end 89.786 57.786)
		(width 0.1)
		(layer "F.Cu")
		(net 1033)
	)
	(segment
		(start 88.48 57.5)
		(end 89.5 57.5)
		(width 0.1)
		(layer "F.Cu")
		(net 1033)
	)
	(segment
		(start 88.48 59.5)
		(end 89.783 59.5)
		(width 0.1)
		(layer "F.Cu")
		(net 1035)
	)
	(segment
		(start 89.783 59.5)
		(end 89.786 59.503)
		(width 0.1)
		(layer "F.Cu")
		(net 1035)
	)
	(segment
		(start 91.753 57.59)
		(end 91.753 58.553)
		(width 0.1)
		(layer "B.Cu")
		(net 1036)
	)
	(segment
		(start 91.8 58.6)
		(end 93.4 58.6)
		(width 0.1)
		(layer "B.Cu")
		(net 1036)
	)
	(segment
		(start 91.753 58.553)
		(end 91.8 58.6)
		(width 0.1)
		(layer "B.Cu")
		(net 1036)
	)
	(segment
		(start 93.4 58.6)
		(end 95 57)
		(width 0.1)
		(layer "B.Cu")
		(net 1036)
	)
	(segment
		(start 95 57)
		(end 95 55.98)
		(width 0.1)
		(layer "B.Cu")
		(net 1036)
	)
	(segment
		(start 90.6 59)
		(end 90.254 58.654)
		(width 0.1)
		(layer "B.Cu")
		(net 1037)
	)
	(segment
		(start 90.254 60.45)
		(end 90.254 59.346)
		(width 0.1)
		(layer "B.Cu")
		(net 1037)
	)
	(segment
		(start 90.254 58.654)
		(end 90.254 57.59)
		(width 0.1)
		(layer "B.Cu")
		(net 1037)
	)
	(segment
		(start 94.851 57.949)
		(end 93.8 59)
		(width 0.1)
		(layer "B.Cu")
		(net 1037)
	)
	(segment
		(start 90.254 59.346)
		(end 90.6 59)
		(width 0.1)
		(layer "B.Cu")
		(net 1037)
	)
	(segment
		(start 96.4 57.949)
		(end 94.851 57.949)
		(width 0.1)
		(layer "B.Cu")
		(net 1037)
	)
	(segment
		(start 93.8 59)
		(end 90.6 59)
		(width 0.1)
		(layer "B.Cu")
		(net 1037)
	)
	(segment
		(start 200.801 74.099)
		(end 200.9 74)
		(width 0.1)
		(layer "F.Cu")
		(net 1039)
	)
	(segment
		(start 201.450058 74)
		(end 202.000058 73.45)
		(width 0.1)
		(layer "F.Cu")
		(net 1039)
	)
	(segment
		(start 200.801 75.13)
		(end 200.801 74.099)
		(width 0.1)
		(layer "F.Cu")
		(net 1039)
	)
	(segment
		(start 202.000058 73.45)
		(end 202.1 73.45)
		(width 0.1)
		(layer "F.Cu")
		(net 1039)
	)
	(segment
		(start 200.9 74)
		(end 201.450058 74)
		(width 0.1)
		(layer "F.Cu")
		(net 1039)
	)
	(segment
		(start 200.399 75.13)
		(end 200.399 74.201)
		(width 0.1)
		(layer "F.Cu")
		(net 1040)
	)
	(segment
		(start 200.399 74.201)
		(end 201.15 73.45)
		(width 0.1)
		(layer "F.Cu")
		(net 1040)
	)
	(segment
		(start 200.05 75.081)
		(end 200.001 75.13)
		(width 0.1)
		(layer "F.Cu")
		(net 1041)
	)
	(segment
		(start 200.05 74.05)
		(end 200.05 75.081)
		(width 0.1)
		(layer "F.Cu")
		(net 1041)
	)
	(segment
		(start 200.2 73.45)
		(end 200.2 73.9)
		(width 0.1)
		(layer "F.Cu")
		(net 1041)
	)
	(segment
		(start 200.2 73.9)
		(end 200.05 74.05)
		(width 0.1)
		(layer "F.Cu")
		(net 1041)
	)
	(segment
		(start 193.8 79)
		(end 193.8 79.8815)
		(width 0.1)
		(layer "F.Cu")
		(net 1042)
	)
	(segment
		(start 197.249 77.882)
		(end 194.918 77.882)
		(width 0.1)
		(layer "F.Cu")
		(net 1042)
	)
	(segment
		(start 193.8 79.8815)
		(end 194.6 80.6815)
		(width 0.1)
		(layer "F.Cu")
		(net 1042)
	)
	(segment
		(start 194.918 77.882)
		(end 193.8 79)
		(width 0.1)
		(layer "F.Cu")
		(net 1042)
	)
	(via
		(at 194.6 80.6815)
		(size 0.45)
		(drill 0.1)
		(layers "F.Cu" "B.Cu")
		(net 1042)
	)
	(segment
		(start 166.675 144.275)
		(end 167 144.6)
		(width 0.3)
		(layer "F.Cu")
		(net 1043)
	)
	(segment
		(start 167.28 144.32)
		(end 167.95 144.32)
		(width 0.3)
		(layer "F.Cu")
		(net 1043)
	)
	(segment
		(start 165.580532 144.275)
		(end 166.675 144.275)
		(width 0.3)
		(layer "F.Cu")
		(net 1043)
	)
	(segment
		(start 165.580532 144.275)
		(end 165.693532 144.388)
		(width 0.3)
		(layer "F.Cu")
		(net 1043)
	)
	(segment
		(start 167 144.6)
		(end 167 145.12)
		(width 0.3)
		(layer "F.Cu")
		(net 1043)
	)
	(segment
		(start 167.15 145.12)
		(end 167 145.12)
		(width 0.3)
		(layer "F.Cu")
		(net 1043)
	)
	(segment
		(start 167 144.6)
		(end 167.28 144.32)
		(width 0.3)
		(layer "F.Cu")
		(net 1043)
	)
	(segment
		(start 216.8 92.2)
		(end 216.6 92.4)
		(width 0.1)
		(layer "F.Cu")
		(net 1044)
	)
	(segment
		(start 216.364632 91.972856)
		(end 216.772856 91.972856)
		(width 0.1)
		(layer "F.Cu")
		(net 1044)
	)
	(segment
		(start 216.8 92)
		(end 216.8 92.2)
		(width 0.1)
		(layer "F.Cu")
		(net 1044)
	)
	(segment
		(start 216.772856 91.972856)
		(end 216.8 92)
		(width 0.1)
		(layer "F.Cu")
		(net 1044)
	)
	(via
		(at 216.6 92.4)
		(size 0.45)
		(drill 0.1)
		(layers "F.Cu" "B.Cu")
		(net 1044)
	)
	(segment
		(start 216.6 92.4)
		(end 217.322 92.4)
		(width 0.1)
		(layer "B.Cu")
		(net 1044)
	)
	(segment
		(start 217.322 92.4)
		(end 217.4 92.322)
		(width 0.1)
		(layer "B.Cu")
		(net 1044)
	)
	(segment
		(start 68.6 62.552)
		(end 69.279 63.231)
		(width 0.1)
		(layer "F.Cu")
		(net 1045)
	)
	(segment
		(start 68.401 61.801)
		(end 68.6 62)
		(width 0.1)
		(layer "F.Cu")
		(net 1045)
	)
	(segment
		(start 68.6 62)
		(end 68.6 62.552)
		(width 0.1)
		(layer "F.Cu")
		(net 1045)
	)
	(segment
		(start 67.469 61.801)
		(end 68.401 61.801)
		(width 0.1)
		(layer "F.Cu")
		(net 1045)
	)
	(segment
		(start 68.599 61.301)
		(end 69.279 61.981)
		(width 0.1)
		(layer "F.Cu")
		(net 1046)
	)
	(segment
		(start 67.469 61.301)
		(end 68.599 61.301)
		(width 0.1)
		(layer "F.Cu")
		(net 1046)
	)
	(segment
		(start 69.15 60.8)
		(end 69.279 60.671)
		(width 0.1)
		(layer "F.Cu")
		(net 1047)
	)
	(segment
		(start 67.469 60.8)
		(end 69.15 60.8)
		(width 0.1)
		(layer "F.Cu")
		(net 1047)
	)
	(segment
		(start 66.82 59.78)
		(end 67 59.6)
		(width 0.1)
		(layer "F.Cu")
		(net 1048)
	)
	(segment
		(start 67 59.6)
		(end 69.02 59.6)
		(width 0.1)
		(layer "F.Cu")
		(net 1048)
	)
	(segment
		(start 66.82 60.151)
		(end 66.82 59.78)
		(width 0.1)
		(layer "F.Cu")
		(net 1048)
	)
	(segment
		(start 69.02 59.6)
		(end 69.289 59.331)
		(width 0.1)
		(layer "F.Cu")
		(net 1048)
	)
	(segment
		(start 66.319 59.481)
		(end 66.6 59.2)
		(width 0.1)
		(layer "F.Cu")
		(net 1049)
	)
	(segment
		(start 68.04 59.2)
		(end 68.85 58.39)
		(width 0.1)
		(layer "F.Cu")
		(net 1049)
	)
	(segment
		(start 66.6 59.2)
		(end 68.04 59.2)
		(width 0.1)
		(layer "F.Cu")
		(net 1049)
	)
	(segment
		(start 66.319 60.151)
		(end 66.319 59.481)
		(width 0.1)
		(layer "F.Cu")
		(net 1049)
	)
	(segment
		(start 68.85 58.39)
		(end 68.85 58.25)
		(width 0.1)
		(layer "F.Cu")
		(net 1049)
	)
	(segment
		(start 66.4 58.8)
		(end 67.14 58.8)
		(width 0.1)
		(layer "F.Cu")
		(net 1050)
	)
	(segment
		(start 67.51 58.43)
		(end 67.51 58.29)
		(width 0.1)
		(layer "F.Cu")
		(net 1050)
	)
	(segment
		(start 67.14 58.8)
		(end 67.51 58.43)
		(width 0.1)
		(layer "F.Cu")
		(net 1050)
	)
	(segment
		(start 65.819 59.381)
		(end 66.4 58.8)
		(width 0.1)
		(layer "F.Cu")
		(net 1050)
	)
	(segment
		(start 65.819 60.151)
		(end 65.819 59.381)
		(width 0.1)
		(layer "F.Cu")
		(net 1050)
	)
	(segment
		(start 66.16 58.4)
		(end 66.16 58.26)
		(width 0.1)
		(layer "F.Cu")
		(net 1051)
	)
	(segment
		(start 65.321 60.151)
		(end 65.321 59.239)
		(width 0.1)
		(layer "F.Cu")
		(net 1051)
	)
	(segment
		(start 65.321 59.239)
		(end 66.16 58.4)
		(width 0.1)
		(layer "F.Cu")
		(net 1051)
	)
	(segment
		(start 64.91 58.38)
		(end 64.91 58.24)
		(width 0.1)
		(layer "F.Cu")
		(net 1052)
	)
	(segment
		(start 64.821 58.469)
		(end 64.91 58.38)
		(width 0.1)
		(layer "F.Cu")
		(net 1052)
	)
	(segment
		(start 64.821 60.151)
		(end 64.821 58.469)
		(width 0.1)
		(layer "F.Cu")
		(net 1052)
	)
	(segment
		(start 209.3 131.541)
		(end 209.3 133.551)
		(width 0.1)
		(layer "F.Cu")
		(net 1078)
	)
	(segment
		(start 209.3 133.551)
		(end 210.313 134.564)
		(width 0.1)
		(layer "F.Cu")
		(net 1078)
	)
	(segment
		(start 209.353 131.488)
		(end 209.3 131.541)
		(width 0.1)
		(layer "F.Cu")
		(net 1078)
	)
	(segment
		(start 181.64 71.425)
		(end 182.144468 71.425)
		(width 0.2)
		(layer "F.Cu")
		(net 1081)
	)
	(segment
		(start 182.144468 71.425)
		(end 182.764468 72.045)
		(width 0.2)
		(layer "F.Cu")
		(net 1081)
	)
	(segment
		(start 202.3 118.4)
		(end 202.3 117.3)
		(width 0.1)
		(layer "F.Cu")
		(net 1084)
	)
	(segment
		(start 202.3 118.4)
		(end 203.354 119.454)
		(width 0.1)
		(layer "F.Cu")
		(net 1084)
	)
	(segment
		(start 203.354 119.911)
		(end 203.354 119.454)
		(width 0.1)
		(layer "F.Cu")
		(net 1084)
	)
	(via
		(at 202.3 117.3)
		(size 0.45)
		(drill 0.1)
		(layers "F.Cu" "B.Cu")
		(net 1084)
	)
	(segment
		(start 214.5 121.6)
		(end 222.8 121.6)
		(width 0.1)
		(layer "B.Cu")
		(net 1084)
	)
	(segment
		(start 210.1 121.6)
		(end 211 120.7)
		(width 0.1)
		(layer "B.Cu")
		(net 1084)
	)
	(segment
		(start 223.079 121.879)
		(end 223.079 122.419)
		(width 0.1)
		(layer "B.Cu")
		(net 1084)
	)
	(segment
		(start 222.8 121.6)
		(end 223.079 121.879)
		(width 0.1)
		(layer "B.Cu")
		(net 1084)
	)
	(segment
		(start 213.6 120.7)
		(end 214.5 121.6)
		(width 0.1)
		(layer "B.Cu")
		(net 1084)
	)
	(segment
		(start 211 120.7)
		(end 213.6 120.7)
		(width 0.1)
		(layer "B.Cu")
		(net 1084)
	)
	(segment
		(start 202.3 119.1)
		(end 204.8 121.6)
		(width 0.1)
		(layer "B.Cu")
		(net 1084)
	)
	(segment
		(start 204.8 121.6)
		(end 210.1 121.6)
		(width 0.1)
		(layer "B.Cu")
		(net 1084)
	)
	(segment
		(start 223.079 123.399)
		(end 223.08 123.4)
		(width 0.1)
		(layer "B.Cu")
		(net 1084)
	)
	(segment
		(start 202.3 117.3)
		(end 202.3 116.9)
		(width 0.1)
		(layer "B.Cu")
		(net 1084)
	)
	(segment
		(start 223.079 122.419)
		(end 223.079 123.399)
		(width 0.1)
		(layer "B.Cu")
		(net 1084)
	)
	(segment
		(start 202.3 117.3)
		(end 202.3 119.1)
		(width 0.1)
		(layer "B.Cu")
		(net 1084)
	)
	(segment
		(start 202.3 116.9)
		(end 202.8 116.4)
		(width 0.1)
		(layer "B.Cu")
		(net 1084)
	)
	(segment
		(start 202.555 119.911)
		(end 202.555 119.455)
		(width 0.1)
		(layer "F.Cu")
		(net 1085)
	)
	(segment
		(start 200.7 117.8)
		(end 200.2 117.3)
		(width 0.1)
		(layer "F.Cu")
		(net 1085)
	)
	(segment
		(start 200.9 117.8)
		(end 202.555 119.455)
		(width 0.1)
		(layer "F.Cu")
		(net 1085)
	)
	(segment
		(start 200.7 117.8)
		(end 200.9 117.8)
		(width 0.1)
		(layer "F.Cu")
		(net 1085)
	)
	(via
		(at 200.2 117.3)
		(size 0.45)
		(drill 0.1)
		(layers "F.Cu" "B.Cu")
		(net 1085)
	)
	(segment
		(start 200.2 116.4)
		(end 200.2 117.3)
		(width 0.1)
		(layer "B.Cu")
		(net 1085)
	)
	(segment
		(start 178.675 68.51)
		(end 178.675 67.425)
		(width 0.15)
		(layer "F.Cu")
		(net 1086)
	)
	(segment
		(start 178.675 67.425)
		(end 178.68 67.42)
		(width 0.15)
		(layer "F.Cu")
		(net 1086)
	)
	(segment
		(start 135.930532 76.65)
		(end 135.925 76.65)
		(width 0.19)
		(layer "F.Cu")
		(net 1088)
	)
	(via
		(at 135.925 76.65)
		(size 0.45)
		(drill 0.1)
		(layers "F.Cu" "B.Cu")
		(net 1088)
	)
	(via
		(at 211.225 97.675)
		(size 0.45)
		(drill 0.1)
		(layers "F.Cu" "B.Cu")
		(net 1088)
	)
	(segment
		(start 212.8 95.889002)
		(end 213.110499 96.199501)
		(width 0.19)
		(layer "B.Cu")
		(net 1088)
	)
	(segment
		(start 211.34 97.79)
		(end 211.225 97.675)
		(width 0.19)
		(layer "B.Cu")
		(net 1088)
	)
	(segment
		(start 213.110499 96.199501)
		(end 213.110499 96.752871)
		(width 0.19)
		(layer "B.Cu")
		(net 1088)
	)
	(segment
		(start 213.110499 96.752871)
		(end 212.07337 97.79)
		(width 0.19)
		(layer "B.Cu")
		(net 1088)
	)
	(segment
		(start 212.07337 97.79)
		(end 211.34 97.79)
		(width 0.19)
		(layer "B.Cu")
		(net 1088)
	)
	(segment
		(start 211.5555 96.957928)
		(end 211.5555 97.022928)
		(width 0.15)
		(layer "In7.Cu")
		(net 1088)
	)
	(segment
		(start 145.243044 79.7875)
		(end 146.543044 79.7875)
		(width 0.15)
		(layer "In7.Cu")
		(net 1088)
	)
	(segment
		(start 150.693044 86.0375)
		(end 202.843044 86.0375)
		(width 0.15)
		(layer "In7.Cu")
		(net 1088)
	)
	(segment
		(start 207.2125 91.031956)
		(end 212.0875 95.906956)
		(width 0.15)
		(layer "In7.Cu")
		(net 1088)
	)
	(segment
		(start 149.4125 82.656956)
		(end 149.4125 84.756956)
		(width 0.15)
		(layer "In7.Cu")
		(net 1088)
	)
	(segment
		(start 211.3875 97.8375)
		(end 211.225 97.675)
		(width 0.15)
		(layer "In7.Cu")
		(net 1088)
	)
	(segment
		(start 136.9625 78.156956)
		(end 136.9625 78.656956)
		(width 0.15)
		(layer "In7.Cu")
		(net 1088)
	)
	(segment
		(start 202.843044 86.0375)
		(end 207.2125 90.406956)
		(width 0.15)
		(layer "In7.Cu")
		(net 1088)
	)
	(segment
		(start 211.6855 97.152928)
		(end 211.9575 97.152928)
		(width 0.15)
		(layer "In7.Cu")
		(net 1088)
	)
	(segment
		(start 212.0875 95.906956)
		(end 212.0875 96.047928)
		(width 0.15)
		(layer "In7.Cu")
		(net 1088)
	)
	(segment
		(start 146.543044 79.7875)
		(end 149.4125 82.656956)
		(width 0.15)
		(layer "In7.Cu")
		(net 1088)
	)
	(segment
		(start 211.693044 97.8375)
		(end 212.0875 97.443044)
		(width 0.15)
		(layer "In7.Cu")
		(net 1088)
	)
	(segment
		(start 212.0875 97.282928)
		(end 212.0875 97.443044)
		(width 0.15)
		(layer "In7.Cu")
		(net 1088)
	)
	(segment
		(start 136.2375 77.431956)
		(end 136.9625 78.156956)
		(width 0.15)
		(layer "In7.Cu")
		(net 1088)
	)
	(segment
		(start 144.593044 79.1375)
		(end 145.243044 79.7875)
		(width 0.15)
		(layer "In7.Cu")
		(net 1088)
	)
	(segment
		(start 136.9625 78.656956)
		(end 137.443044 79.1375)
		(width 0.15)
		(layer "In7.Cu")
		(net 1088)
	)
	(segment
		(start 207.2125 90.406956)
		(end 207.2125 91.031956)
		(width 0.15)
		(layer "In7.Cu")
		(net 1088)
	)
	(segment
		(start 136.2375 76.9625)
		(end 136.2375 77.431956)
		(width 0.15)
		(layer "In7.Cu")
		(net 1088)
	)
	(segment
		(start 211.9575 96.827928)
		(end 211.6855 96.827928)
		(width 0.15)
		(layer "In7.Cu")
		(net 1088)
	)
	(segment
		(start 137.443044 79.1375)
		(end 144.593044 79.1375)
		(width 0.15)
		(layer "In7.Cu")
		(net 1088)
	)
	(segment
		(start 212.0875 96.583848)
		(end 212.0875 96.697928)
		(width 0.15)
		(layer "In7.Cu")
		(net 1088)
	)
	(segment
		(start 211.693044 97.8375)
		(end 211.3875 97.8375)
		(width 0.15)
		(layer "In7.Cu")
		(net 1088)
	)
	(segment
		(start 135.925 76.65)
		(end 136.2375 76.9625)
		(width 0.15)
		(layer "In7.Cu")
		(net 1088)
	)
	(segment
		(start 211.87658 96.258848)
		(end 211.87658 96.372928)
		(width 0.15)
		(layer "In7.Cu")
		(net 1088)
	)
	(segment
		(start 149.4125 84.756956)
		(end 150.693044 86.0375)
		(width 0.15)
		(layer "In7.Cu")
		(net 1088)
	)
	(arc
		(start 211.5555 97.022928)
		(mid 211.593576 97.114852)
		(end 211.6855 97.152928)
		(width 0.15)
		(layer "In7.Cu")
		(net 1088)
	)
	(arc
		(start 212.0875 96.697928)
		(mid 212.049424 96.789852)
		(end 211.9575 96.827928)
		(width 0.15)
		(layer "In7.Cu")
		(net 1088)
	)
	(arc
		(start 211.98204 96.153388)
		(mid 211.907469 96.184277)
		(end 211.87658 96.258848)
		(width 0.15)
		(layer "In7.Cu")
		(net 1088)
	)
	(arc
		(start 211.87658 96.372928)
		(mid 211.907469 96.447499)
		(end 211.98204 96.478388)
		(width 0.15)
		(layer "In7.Cu")
		(net 1088)
	)
	(arc
		(start 211.98204 96.478388)
		(mid 212.056611 96.509277)
		(end 212.0875 96.583848)
		(width 0.15)
		(layer "In7.Cu")
		(net 1088)
	)
	(arc
		(start 211.6855 96.827928)
		(mid 211.593576 96.866004)
		(end 211.5555 96.957928)
		(width 0.15)
		(layer "In7.Cu")
		(net 1088)
	)
	(arc
		(start 212.0875 96.047928)
		(mid 212.056611 96.122499)
		(end 211.98204 96.153388)
		(width 0.15)
		(layer "In7.Cu")
		(net 1088)
	)
	(arc
		(start 211.9575 97.152928)
		(mid 212.049424 97.191004)
		(end 212.0875 97.282928)
		(width 0.15)
		(layer "In7.Cu")
		(net 1088)
	)
	(segment
		(start 130.11 150.72)
		(end 130.11 150.01)
		(width 0.1)
		(layer "B.Cu")
		(net 1089)
	)
	(segment
		(start 129.8345 149.7345)
		(end 130.11 150.01)
		(width 0.1)
		(layer "B.Cu")
		(net 1089)
	)
	(segment
		(start 130.11 150.72)
		(end 130.12 150.73)
		(width 0.1)
		(layer "B.Cu")
		(net 1089)
	)
	(segment
		(start 131.418 150.73)
		(end 131.548 150.6)
		(width 0.1)
		(layer "B.Cu")
		(net 1089)
	)
	(segment
		(start 130.12 150.73)
		(end 131.418 150.73)
		(width 0.1)
		(layer "B.Cu")
		(net 1089)
	)
	(segment
		(start 129.8345 149.027)
		(end 129.8345 149.7345)
		(width 0.1)
		(layer "B.Cu")
		(net 1089)
	)
	(segment
		(start 201.4 117.9)
		(end 202.955 119.455)
		(width 0.1)
		(layer "F.Cu")
		(net 1095)
	)
	(segment
		(start 201.4 117.9)
		(end 201.4 117.3)
		(width 0.1)
		(layer "F.Cu")
		(net 1095)
	)
	(segment
		(start 202.955 119.911)
		(end 202.955 119.455)
		(width 0.1)
		(layer "F.Cu")
		(net 1095)
	)
	(via
		(at 201.4 117.3)
		(size 0.45)
		(drill 0.1)
		(layers "F.Cu" "B.Cu")
		(net 1095)
	)
	(segment
		(start 201.4 119)
		(end 204.5 122.1)
		(width 0.1)
		(layer "B.Cu")
		(net 1095)
	)
	(segment
		(start 201.4 117.3)
		(end 201.4 119)
		(width 0.1)
		(layer "B.Cu")
		(net 1095)
	)
	(segment
		(start 204.5 122.1)
		(end 218.4 122.1)
		(width 0.1)
		(layer "B.Cu")
		(net 1095)
	)
	(segment
		(start 218.6 121.9)
		(end 219.8 121.9)
		(width 0.1)
		(layer "B.Cu")
		(net 1095)
	)
	(segment
		(start 219.92 122.431698)
		(end 219.889 122.400698)
		(width 0.1)
		(layer "B.Cu")
		(net 1095)
	)
	(segment
		(start 201.4 116.4)
		(end 201.4 117.3)
		(width 0.1)
		(layer "B.Cu")
		(net 1095)
	)
	(segment
		(start 219.8 121.9)
		(end 219.889 121.989)
		(width 0.1)
		(layer "B.Cu")
		(net 1095)
	)
	(segment
		(start 219.92 123.391698)
		(end 219.92 122.431698)
		(width 0.1)
		(layer "B.Cu")
		(net 1095)
	)
	(segment
		(start 218.4 122.1)
		(end 218.6 121.9)
		(width 0.1)
		(layer "B.Cu")
		(net 1095)
	)
	(segment
		(start 219.889 121.989)
		(end 219.889 122.400698)
		(width 0.1)
		(layer "B.Cu")
		(net 1095)
	)
	(segment
		(start 197.6 120)
		(end 198.5 120.9)
		(width 0.1)
		(layer "F.Cu")
		(net 1099)
	)
	(segment
		(start 197.6 119.4)
		(end 197.6 120)
		(width 0.1)
		(layer "F.Cu")
		(net 1099)
	)
	(segment
		(start 198.5 120.9)
		(end 199.565 120.9)
		(width 0.1)
		(layer "F.Cu")
		(net 1099)
	)
	(via
		(at 197.6 119.4)
		(size 0.45)
		(drill 0.1)
		(layers "F.Cu" "B.Cu")
		(net 1099)
	)
	(segment
		(start 197.9 119.4)
		(end 197.6 119.4)
		(width 0.1)
		(layer "B.Cu")
		(net 1099)
	)
	(segment
		(start 220.18 113.03)
		(end 220.18 112.02)
		(width 0.1)
		(layer "B.Cu")
		(net 1099)
	)
	(segment
		(start 198.4 118.9)
		(end 197.9 119.4)
		(width 0.1)
		(layer "B.Cu")
		(net 1099)
	)
	(segment
		(start 198.4 118)
		(end 198.4 118.9)
		(width 0.1)
		(layer "B.Cu")
		(net 1099)
	)
	(segment
		(start 197.7 117.3)
		(end 198.4 118)
		(width 0.1)
		(layer "B.Cu")
		(net 1099)
	)
	(segment
		(start 220.179 112.019)
		(end 220.179 111.179)
		(width 0.1)
		(layer "B.Cu")
		(net 1099)
	)
	(segment
		(start 199.4 113.6)
		(end 197.7 115.3)
		(width 0.1)
		(layer "B.Cu")
		(net 1099)
	)
	(segment
		(start 197.6 119.4)
		(end 197.6 118.4)
		(width 0.1)
		(layer "B.Cu")
		(net 1099)
	)
	(segment
		(start 220.179 111.179)
		(end 220 111)
		(width 0.1)
		(layer "B.Cu")
		(net 1099)
	)
	(segment
		(start 197.7 115.3)
		(end 197.7 117.3)
		(width 0.1)
		(layer "B.Cu")
		(net 1099)
	)
	(segment
		(start 208.5 113.6)
		(end 199.4 113.6)
		(width 0.1)
		(layer "B.Cu")
		(net 1099)
	)
	(segment
		(start 220 111)
		(end 211.1 111)
		(width 0.1)
		(layer "B.Cu")
		(net 1099)
	)
	(segment
		(start 220.18 112.02)
		(end 220.179 112.019)
		(width 0.1)
		(layer "B.Cu")
		(net 1099)
	)
	(segment
		(start 211.1 111)
		(end 208.5 113.6)
		(width 0.1)
		(layer "B.Cu")
		(net 1099)
	)
	(segment
		(start 138.6 143.6)
		(end 138.6 138.6)
		(width 0.1)
		(layer "F.Cu")
		(net 1100)
	)
	(segment
		(start 136.35 130.65)
		(end 136.35 114.95)
		(width 0.1)
		(layer "F.Cu")
		(net 1100)
	)
	(segment
		(start 135.25 135.25)
		(end 135.25 131.75)
		(width 0.1)
		(layer "F.Cu")
		(net 1100)
	)
	(segment
		(start 138.6 138.6)
		(end 135.25 135.25)
		(width 0.1)
		(layer "F.Cu")
		(net 1100)
	)
	(segment
		(start 133.3 148.9)
		(end 138.6 143.6)
		(width 0.1)
		(layer "F.Cu")
		(net 1100)
	)
	(segment
		(start 136.35 114.95)
		(end 138.7 112.6)
		(width 0.1)
		(layer "F.Cu")
		(net 1100)
	)
	(segment
		(start 138.7 112.6)
		(end 138.7 112.2)
		(width 0.1)
		(layer "F.Cu")
		(net 1100)
	)
	(segment
		(start 135.25 131.75)
		(end 136.35 130.65)
		(width 0.1)
		(layer "F.Cu")
		(net 1100)
	)
	(via
		(at 133.3 148.9)
		(size 0.45)
		(drill 0.1)
		(layers "F.Cu" "B.Cu")
		(net 1100)
	)
	(segment
		(start 134 150.1)
		(end 132.85 150.1)
		(width 0.1)
		(layer "B.Cu")
		(net 1100)
	)
	(segment
		(start 132.85 150.1)
		(end 132.85 149.35)
		(width 0.1)
		(layer "B.Cu")
		(net 1100)
	)
	(segment
		(start 132.85 149.35)
		(end 133.3 148.9)
		(width 0.1)
		(layer "B.Cu")
		(net 1100)
	)
	(segment
		(start 101.24 58.76)
		(end 101.675 58.325)
		(width 0.1)
		(layer "B.Cu")
		(net 1101)
	)
	(segment
		(start 101.675 58.325)
		(end 102.51 58.325)
		(width 0.1)
		(layer "B.Cu")
		(net 1101)
	)
	(segment
		(start 101.24 59.52)
		(end 101.24 58.76)
		(width 0.1)
		(layer "B.Cu")
		(net 1101)
	)
	(segment
		(start 200 118.5)
		(end 201.2 118.5)
		(width 0.1)
		(layer "F.Cu")
		(net 1103)
	)
	(segment
		(start 200 118.5)
		(end 198.8 117.3)
		(width 0.1)
		(layer "F.Cu")
		(net 1103)
	)
	(segment
		(start 202.154 119.911)
		(end 202.154 119.454)
		(width 0.1)
		(layer "F.Cu")
		(net 1103)
	)
	(segment
		(start 201.2 118.5)
		(end 202.154 119.454)
		(width 0.1)
		(layer "F.Cu")
		(net 1103)
	)
	(via
		(at 198.8 117.3)
		(size 0.45)
		(drill 0.1)
		(layers "F.Cu" "B.Cu")
		(net 1103)
	)
	(segment
		(start 198.8 117.3)
		(end 198.8 116.4)
		(width 0.1)
		(layer "B.Cu")
		(net 1103)
	)
	(segment
		(start 178.225 67.925)
		(end 177.72 67.42)
		(width 0.15)
		(layer "F.Cu")
		(net 1104)
	)
	(segment
		(start 178.225 68.51)
		(end 178.225 67.925)
		(width 0.15)
		(layer "F.Cu")
		(net 1104)
	)
	(segment
		(start 162.709468 77.090532)
		(end 162.709468 77.62)
		(width 0.1)
		(layer "F.Cu")
		(net 1105)
	)
	(segment
		(start 181.175 68.51)
		(end 181.59 68.51)
		(width 0.15)
		(layer "F.Cu")
		(net 1105)
	)
	(segment
		(start 162.9 76.4)
		(end 162.9 76.9)
		(width 0.1)
		(layer "F.Cu")
		(net 1105)
	)
	(segment
		(start 182.829468 67.270532)
		(end 182.8 67.3)
		(width 0.2)
		(layer "F.Cu")
		(net 1105)
	)
	(segment
		(start 163.09 76.21)
		(end 162.9 76.4)
		(width 0.1)
		(layer "F.Cu")
		(net 1105)
	)
	(segment
		(start 162.9 76.9)
		(end 162.709468 77.090532)
		(width 0.1)
		(layer "F.Cu")
		(net 1105)
	)
	(segment
		(start 182.829468 67.24)
		(end 182.829468 67.270532)
		(width 0.2)
		(layer "F.Cu")
		(net 1105)
	)
	(segment
		(start 181.59 68.51)
		(end 182.8 67.3)
		(width 0.15)
		(layer "F.Cu")
		(net 1105)
	)
	(segment
		(start 163.929468 76.21)
		(end 163.09 76.21)
		(width 0.1)
		(layer "F.Cu")
		(net 1105)
	)
	(via
		(at 182.8 67.3)
		(size 0.45)
		(drill 0.1)
		(layers "F.Cu" "B.Cu")
		(remove_unused_layers yes)
		(keep_end_layers yes)
		(zone_layer_connections)
		(net 1105)
	)
	(via
		(at 175.35 74.95)
		(size 0.45)
		(drill 0.1)
		(layers "F.Cu" "B.Cu")
		(remove_unused_layers yes)
		(keep_end_layers yes)
		(zone_layer_connections)
		(net 1105)
	)
	(segment
		(start 175.35 74.95)
		(end 176.375 73.925)
		(width 0.2)
		(layer "In5.Cu")
		(net 1105)
	)
	(segment
		(start 181.6325 68.4675)
		(end 182.8 67.3)
		(width 0.2)
		(layer "In5.Cu")
		(net 1105)
	)
	(segment
		(start 177.425 73.925)
		(end 181.6325 69.7175)
		(width 0.2)
		(layer "In5.Cu")
		(net 1105)
	)
	(segment
		(start 176.375 73.925)
		(end 177.425 73.925)
		(width 0.2)
		(layer "In5.Cu")
		(net 1105)
	)
	(segment
		(start 181.6325 69.7175)
		(end 181.6325 68.4675)
		(width 0.2)
		(layer "In5.Cu")
		(net 1105)
	)
	(segment
		(start 197.901 121.301)
		(end 196.4 119.8)
		(width 0.1)
		(layer "F.Cu")
		(net 1106)
	)
	(segment
		(start 196.4 119.4)
		(end 196.4 119.8)
		(width 0.1)
		(layer "F.Cu")
		(net 1106)
	)
	(segment
		(start 199.565 121.301)
		(end 197.901 121.301)
		(width 0.1)
		(layer "F.Cu")
		(net 1106)
	)
	(via
		(at 196.4 119.4)
		(size 0.45)
		(drill 0.1)
		(layers "F.Cu" "B.Cu")
		(net 1106)
	)
	(segment
		(start 211.9 111.3)
		(end 216.9 111.3)
		(width 0.1)
		(layer "B.Cu")
		(net 1106)
	)
	(segment
		(start 198.1 117.2)
		(end 198.1 115.8)
		(width 0.1)
		(layer "B.Cu")
		(net 1106)
	)
	(segment
		(start 217.039 111.439)
		(end 217.039 111.989)
		(width 0.1)
		(layer "B.Cu")
		(net 1106)
	)
	(segment
		(start 198 120)
		(end 198.8 119.2)
		(width 0.1)
		(layer "B.Cu")
		(net 1106)
	)
	(segment
		(start 198.8 117.9)
		(end 198.1 117.2)
		(width 0.1)
		(layer "B.Cu")
		(net 1106)
	)
	(segment
		(start 196.4 118.4)
		(end 196.4 119.4)
		(width 0.1)
		(layer "B.Cu")
		(net 1106)
	)
	(segment
		(start 217.07 113.03)
		(end 217.07 112.02)
		(width 0.1)
		(layer "B.Cu")
		(net 1106)
	)
	(segment
		(start 216.9 111.3)
		(end 217.039 111.439)
		(width 0.1)
		(layer "B.Cu")
		(net 1106)
	)
	(segment
		(start 209 114.2)
		(end 211.9 111.3)
		(width 0.1)
		(layer "B.Cu")
		(net 1106)
	)
	(segment
		(start 217.07 112.02)
		(end 217.039 111.989)
		(width 0.1)
		(layer "B.Cu")
		(net 1106)
	)
	(segment
		(start 196.4 119.4)
		(end 197 120)
		(width 0.1)
		(layer "B.Cu")
		(net 1106)
	)
	(segment
		(start 198.8 119.2)
		(end 198.8 117.9)
		(width 0.1)
		(layer "B.Cu")
		(net 1106)
	)
	(segment
		(start 198.1 115.8)
		(end 199.7 114.2)
		(width 0.1)
		(layer "B.Cu")
		(net 1106)
	)
	(segment
		(start 197 120)
		(end 198 120)
		(width 0.1)
		(layer "B.Cu")
		(net 1106)
	)
	(segment
		(start 199.7 114.2)
		(end 209 114.2)
		(width 0.1)
		(layer "B.Cu")
		(net 1106)
	)
	(via
		(at 182 56)
		(size 0.45)
		(drill 0.1)
		(layers "F.Cu" "B.Cu")
		(net 1108)
	)
	(segment
		(start 182 56)
		(end 182 57.02)
		(width 0.1)
		(layer "B.Cu")
		(net 1108)
	)
	(segment
		(start 202.6 131.533)
		(end 202.555 131.488)
		(width 0.1)
		(layer "F.Cu")
		(net 1111)
	)
	(segment
		(start 202.6 132.66)
		(end 202.6 131.533)
		(width 0.1)
		(layer "F.Cu")
		(net 1111)
	)
	(via
		(at 202.6 132.66)
		(size 0.45)
		(drill 0.1)
		(layers "F.Cu" "B.Cu")
		(net 1111)
	)
	(segment
		(start 202.46 132.66)
		(end 202.3 132.5)
		(width 0.1)
		(layer "B.Cu")
		(net 1111)
	)
	(segment
		(start 202.3 132.5)
		(end 202.3 130.98)
		(width 0.1)
		(layer "B.Cu")
		(net 1111)
	)
	(segment
		(start 202.6 132.66)
		(end 202.46 132.66)
		(width 0.1)
		(layer "B.Cu")
		(net 1111)
	)
	(segment
		(start 136.830532 76.65)
		(end 136.825 76.65)
		(width 0.19)
		(layer "F.Cu")
		(net 1112)
	)
	(via
		(at 211.225 98.275)
		(size 0.45)
		(drill 0.1)
		(layers "F.Cu" "B.Cu")
		(net 1112)
	)
	(via
		(at 136.825 76.65)
		(size 0.45)
		(drill 0.1)
		(layers "F.Cu" "B.Cu")
		(net 1112)
	)
	(segment
		(start 213.480499 96.199501)
		(end 213.480499 96.906131)
		(width 0.19)
		(layer "B.Cu")
		(net 1112)
	)
	(segment
		(start 213.8 95.88)
		(end 213.480499 96.199501)
		(width 0.19)
		(layer "B.Cu")
		(net 1112)
	)
	(segment
		(start 213.480499 96.906131)
		(end 212.22663 98.16)
		(width 0.19)
		(layer "B.Cu")
		(net 1112)
	)
	(segment
		(start 212.22663 98.16)
		(end 211.34 98.16)
		(width 0.19)
		(layer "B.Cu")
		(net 1112)
	)
	(segment
		(start 211.34 98.16)
		(end 211.225 98.275)
		(width 0.19)
		(layer "B.Cu")
		(net 1112)
	)
	(segment
		(start 211.3875 98.1125)
		(end 211.225 98.275)
		(width 0.15)
		(layer "In7.Cu")
		(net 1112)
	)
	(segment
		(start 149.6875 82.543044)
		(end 149.6875 84.643044)
		(width 0.15)
		(layer "In7.Cu")
		(net 1112)
	)
	(segment
		(start 212.3625 95.793044)
		(end 212.3625 97.556956)
		(width 0.15)
		(layer "In7.Cu")
		(net 1112)
	)
	(segment
		(start 137.556956 78.8625)
		(end 144.706956 78.8625)
		(width 0.15)
		(layer "In7.Cu")
		(net 1112)
	)
	(segment
		(start 136.825 76.65)
		(end 136.5125 76.9625)
		(width 0.15)
		(layer "In7.Cu")
		(net 1112)
	)
	(segment
		(start 136.5125 77.318044)
		(end 137.2375 78.043044)
		(width 0.15)
		(layer "In7.Cu")
		(net 1112)
	)
	(segment
		(start 137.2375 78.543044)
		(end 137.556956 78.8625)
		(width 0.15)
		(layer "In7.Cu")
		(net 1112)
	)
	(segment
		(start 145.356956 79.5125)
		(end 146.656956 79.5125)
		(width 0.15)
		(layer "In7.Cu")
		(net 1112)
	)
	(segment
		(start 211.806956 98.1125)
		(end 211.3875 98.1125)
		(width 0.15)
		(layer "In7.Cu")
		(net 1112)
	)
	(segment
		(start 137.2375 78.043044)
		(end 137.2375 78.543044)
		(width 0.15)
		(layer "In7.Cu")
		(net 1112)
	)
	(segment
		(start 149.6875 84.643044)
		(end 150.806956 85.7625)
		(width 0.15)
		(layer "In7.Cu")
		(net 1112)
	)
	(segment
		(start 146.656956 79.5125)
		(end 149.6875 82.543044)
		(width 0.15)
		(layer "In7.Cu")
		(net 1112)
	)
	(segment
		(start 212.3625 97.556956)
		(end 211.806956 98.1125)
		(width 0.15)
		(layer "In7.Cu")
		(net 1112)
	)
	(segment
		(start 202.956956 85.7625)
		(end 207.4875 90.293044)
		(width 0.15)
		(layer "In7.Cu")
		(net 1112)
	)
	(segment
		(start 144.706956 78.8625)
		(end 145.356956 79.5125)
		(width 0.15)
		(layer "In7.Cu")
		(net 1112)
	)
	(segment
		(start 136.5125 76.9625)
		(end 136.5125 77.318044)
		(width 0.15)
		(layer "In7.Cu")
		(net 1112)
	)
	(segment
		(start 207.4875 90.293044)
		(end 207.4875 90.918044)
		(width 0.15)
		(layer "In7.Cu")
		(net 1112)
	)
	(segment
		(start 150.806956 85.7625)
		(end 202.956956 85.7625)
		(width 0.15)
		(layer "In7.Cu")
		(net 1112)
	)
	(segment
		(start 207.4875 90.918044)
		(end 212.3625 95.793044)
		(width 0.15)
		(layer "In7.Cu")
		(net 1112)
	)
	(segment
		(start 153.2 98.4)
		(end 154.8 98.4)
		(width 0.1)
		(layer "F.Cu")
		(net 1113)
	)
	(via
		(at 126.9 135)
		(size 0.45)
		(drill 0.1)
		(layers "F.Cu" "B.Cu")
		(net 1113)
	)
	(via
		(at 154.8 98.4)
		(size 0.45)
		(drill 0.1)
		(layers "F.Cu" "B.Cu")
		(net 1113)
	)
	(via
		(at 149.3 109.6)
		(size 0.45)
		(drill 0.1)
		(layers "F.Cu" "B.Cu")
		(net 1113)
	)
	(segment
		(start 126.85 134.95)
		(end 126.9 135)
		(width 0.1)
		(layer "B.Cu")
		(net 1113)
	)
	(segment
		(start 125.08 134.95)
		(end 126.85 134.95)
		(width 0.1)
		(layer "B.Cu")
		(net 1113)
	)
	(segment
		(start 154.55 93.8)
		(end 155.3 94.55)
		(width 0.1)
		(layer "In5.Cu")
		(net 1113)
	)
	(segment
		(start 149.699 109.201)
		(end 149.699 103.498)
		(width 0.1)
		(layer "In5.Cu")
		(net 1113)
	)
	(segment
		(start 149.3 101.7)
		(end 149.7 101.3)
		(width 0.1)
		(layer "In5.Cu")
		(net 1113)
	)
	(segment
		(start 155.3 97.9)
		(end 154.8 98.4)
		(width 0.1)
		(layer "In5.Cu")
		(net 1113)
	)
	(segment
		(start 149.501 103.3)
		(end 149.501 102.801)
		(width 0.1)
		(layer "In5.Cu")
		(net 1113)
	)
	(segment
		(start 149.7 94.2)
		(end 150.1 93.8)
		(width 0.1)
		(layer "In5.Cu")
		(net 1113)
	)
	(segment
		(start 150.1 93.8)
		(end 154.55 93.8)
		(width 0.1)
		(layer "In5.Cu")
		(net 1113)
	)
	(segment
		(start 149.3 109.6)
		(end 149.699 109.201)
		(width 0.1)
		(layer "In5.Cu")
		(net 1113)
	)
	(segment
		(start 149.699 103.498)
		(end 149.501 103.3)
		(width 0.1)
		(layer "In5.Cu")
		(net 1113)
	)
	(segment
		(start 149.501 102.801)
		(end 149.3 102.6)
		(width 0.1)
		(layer "In5.Cu")
		(net 1113)
	)
	(segment
		(start 149.3 102.6)
		(end 149.3 101.7)
		(width 0.1)
		(layer "In5.Cu")
		(net 1113)
	)
	(segment
		(start 155.3 94.55)
		(end 155.3 97.9)
		(width 0.1)
		(layer "In5.Cu")
		(net 1113)
	)
	(segment
		(start 149.7 101.3)
		(end 149.7 94.2)
		(width 0.1)
		(layer "In5.Cu")
		(net 1113)
	)
	(segment
		(start 134.7 116.1)
		(end 135.9 114.9)
		(width 0.1)
		(layer "In7.Cu")
		(net 1113)
	)
	(segment
		(start 134.7 122.1)
		(end 134.7 116.1)
		(width 0.1)
		(layer "In7.Cu")
		(net 1113)
	)
	(segment
		(start 135.9 113.1)
		(end 138.05 110.95)
		(width 0.1)
		(layer "In7.Cu")
		(net 1113)
	)
	(segment
		(start 130.2 126.6)
		(end 134.7 122.1)
		(width 0.1)
		(layer "In7.Cu")
		(net 1113)
	)
	(segment
		(start 141.5 109.3)
		(end 149 109.3)
		(width 0.1)
		(layer "In7.Cu")
		(net 1113)
	)
	(segment
		(start 135.9 114.9)
		(end 135.9 113.1)
		(width 0.1)
		(layer "In7.Cu")
		(net 1113)
	)
	(segment
		(start 129.1 135)
		(end 130.2 133.9)
		(width 0.1)
		(layer "In7.Cu")
		(net 1113)
	)
	(segment
		(start 139.85 110.95)
		(end 141.5 109.3)
		(width 0.1)
		(layer "In7.Cu")
		(net 1113)
	)
	(segment
		(start 138.05 110.95)
		(end 139.85 110.95)
		(width 0.1)
		(layer "In7.Cu")
		(net 1113)
	)
	(segment
		(start 149 109.3)
		(end 149.3 109.6)
		(width 0.1)
		(layer "In7.Cu")
		(net 1113)
	)
	(segment
		(start 130.2 133.9)
		(end 130.2 126.6)
		(width 0.1)
		(layer "In7.Cu")
		(net 1113)
	)
	(segment
		(start 126.9 135)
		(end 129.1 135)
		(width 0.1)
		(layer "In7.Cu")
		(net 1113)
	)
	(segment
		(start 202.955 131.488)
		(end 202.955 132.305)
		(width 0.1)
		(layer "F.Cu")
		(net 1126)
	)
	(segment
		(start 202.955 132.305)
		(end 203.15 132.5)
		(width 0.1)
		(layer "F.Cu")
		(net 1126)
	)
	(via
		(at 203.15 132.5)
		(size 0.45)
		(drill 0.1)
		(layers "F.Cu" "B.Cu")
		(net 1126)
	)
	(segment
		(start 203.3 132.35)
		(end 203.15 132.5)
		(width 0.1)
		(layer "B.Cu")
		(net 1126)
	)
	(segment
		(start 203.3 130.98)
		(end 203.3 132.35)
		(width 0.1)
		(layer "B.Cu")
		(net 1126)
	)
	(via
		(at 173 56.01)
		(size 0.45)
		(drill 0.1)
		(layers "F.Cu" "B.Cu")
		(net 1127)
	)
	(segment
		(start 173 56)
		(end 173 57.02)
		(width 0.1)
		(layer "B.Cu")
		(net 1127)
	)
	(segment
		(start 211.8075 104.9725)
		(end 212.28913 104.9725)
		(width 0.19)
		(layer "F.Cu")
		(net 1128)
	)
	(segment
		(start 211.48 105.275)
		(end 211.505 105.275)
		(width 0.19)
		(layer "F.Cu")
		(net 1128)
	)
	(segment
		(start 213.13663 104.125)
		(end 214.017 104.125)
		(width 0.19)
		(layer "F.Cu")
		(net 1128)
	)
	(segment
		(start 211.505 105.275)
		(end 211.8075 104.9725)
		(width 0.19)
		(layer "F.Cu")
		(net 1128)
	)
	(segment
		(start 212.28913 104.9725)
		(end 213.13663 104.125)
		(width 0.19)
		(layer "F.Cu")
		(net 1128)
	)
	(segment
		(start 213.656499 102.9105)
		(end 213.670999 102.925)
		(width 0.19)
		(layer "F.Cu")
		(net 1129)
	)
	(segment
		(start 211.505 102.355)
		(end 211.8075 102.0525)
		(width 0.19)
		(layer "F.Cu")
		(net 1129)
	)
	(segment
		(start 211.99087 102.0525)
		(end 212.84887 102.9105)
		(width 0.19)
		(layer "F.Cu")
		(net 1129)
	)
	(segment
		(start 212.84887 102.9105)
		(end 213.656499 102.9105)
		(width 0.19)
		(layer "F.Cu")
		(net 1129)
	)
	(segment
		(start 211.48 102.355)
		(end 211.505 102.355)
		(width 0.19)
		(layer "F.Cu")
		(net 1129)
	)
	(segment
		(start 213.670999 102.925)
		(end 214.046 102.925)
		(width 0.19)
		(layer "F.Cu")
		(net 1129)
	)
	(segment
		(start 211.8075 102.0525)
		(end 211.99087 102.0525)
		(width 0.19)
		(layer "F.Cu")
		(net 1129)
	)
	(segment
		(start 211.48 104.3)
		(end 211.505 104.3)
		(width 0.19)
		(layer "F.Cu")
		(net 1130)
	)
	(segment
		(start 212.13587 104.6025)
		(end 212.98337 103.755)
		(width 0.19)
		(layer "F.Cu")
		(net 1130)
	)
	(segment
		(start 214.017 103.755)
		(end 214.046 103.726)
		(width 0.19)
		(layer "F.Cu")
		(net 1130)
	)
	(segment
		(start 211.505 104.3)
		(end 211.8075 104.6025)
		(width 0.19)
		(layer "F.Cu")
		(net 1130)
	)
	(segment
		(start 212.98337 103.755)
		(end 214.017 103.755)
		(width 0.19)
		(layer "F.Cu")
		(net 1130)
	)
	(segment
		(start 211.8075 104.6025)
		(end 212.13587 104.6025)
		(width 0.19)
		(layer "F.Cu")
		(net 1130)
	)
	(segment
		(start 212.14413 101.6825)
		(end 213.00213 102.5405)
		(width 0.19)
		(layer "F.Cu")
		(net 1131)
	)
	(segment
		(start 211.505 101.38)
		(end 211.8075 101.6825)
		(width 0.19)
		(layer "F.Cu")
		(net 1131)
	)
	(segment
		(start 213.656499 102.5405)
		(end 213.670999 102.526)
		(width 0.19)
		(layer "F.Cu")
		(net 1131)
	)
	(segment
		(start 213.00213 102.5405)
		(end 213.656499 102.5405)
		(width 0.19)
		(layer "F.Cu")
		(net 1131)
	)
	(segment
		(start 211.8075 101.6825)
		(end 212.14413 101.6825)
		(width 0.19)
		(layer "F.Cu")
		(net 1131)
	)
	(segment
		(start 213.670999 102.526)
		(end 214.046 102.526)
		(width 0.19)
		(layer "F.Cu")
		(net 1131)
	)
	(segment
		(start 211.48 101.38)
		(end 211.505 101.38)
		(width 0.19)
		(layer "F.Cu")
		(net 1131)
	)
	(segment
		(start 206.5685 132.261901)
		(end 206.5685 132.61987)
		(width 0.19)
		(layer "F.Cu")
		(net 1132)
	)
	(segment
		(start 206.553 132.246401)
		(end 206.5685 132.261901)
		(width 0.19)
		(layer "F.Cu")
		(net 1132)
	)
	(segment
		(start 206.205 133.99)
		(end 205.9 134.295)
		(width 0.19)
		(layer "F.Cu")
		(net 1132)
	)
	(segment
		(start 206.5685 132.61987)
		(end 206.205 132.98337)
		(width 0.19)
		(layer "F.Cu")
		(net 1132)
	)
	(segment
		(start 205.9 134.295)
		(end 205.9 134.32)
		(width 0.19)
		(layer "F.Cu")
		(net 1132)
	)
	(segment
		(start 206.205 132.98337)
		(end 206.205 133.99)
		(width 0.19)
		(layer "F.Cu")
		(net 1132)
	)
	(segment
		(start 206.553 131.488)
		(end 206.553 132.246401)
		(width 0.19)
		(layer "F.Cu")
		(net 1132)
	)
	(segment
		(start 207.7685 132.63013)
		(end 207.7685 132.261901)
		(width 0.19)
		(layer "F.Cu")
		(net 1133)
	)
	(segment
		(start 208.185 133.99)
		(end 208.185 133.04663)
		(width 0.19)
		(layer "F.Cu")
		(net 1133)
	)
	(segment
		(start 208.185 133.04663)
		(end 207.7685 132.63013)
		(width 0.19)
		(layer "F.Cu")
		(net 1133)
	)
	(segment
		(start 207.753 132.246401)
		(end 207.753 131.488)
		(width 0.19)
		(layer "F.Cu")
		(net 1133)
	)
	(segment
		(start 207.7685 132.261901)
		(end 207.753 132.246401)
		(width 0.19)
		(layer "F.Cu")
		(net 1133)
	)
	(segment
		(start 207.88 134.32)
		(end 207.88 134.295)
		(width 0.19)
		(layer "F.Cu")
		(net 1133)
	)
	(segment
		(start 207.88 134.295)
		(end 208.185 133.99)
		(width 0.19)
		(layer "F.Cu")
		(net 1133)
	)
	(segment
		(start 206.575 133.99)
		(end 206.88 134.295)
		(width 0.19)
		(layer "F.Cu")
		(net 1134)
	)
	(segment
		(start 206.575 133.13663)
		(end 206.575 133.99)
		(width 0.19)
		(layer "F.Cu")
		(net 1134)
	)
	(segment
		(start 206.9385 132.261901)
		(end 206.9385 132.77313)
		(width 0.19)
		(layer "F.Cu")
		(net 1134)
	)
	(segment
		(start 206.954 132.246401)
		(end 206.9385 132.261901)
		(width 0.19)
		(layer "F.Cu")
		(net 1134)
	)
	(segment
		(start 206.9385 132.77313)
		(end 206.575 133.13663)
		(width 0.19)
		(layer "F.Cu")
		(net 1134)
	)
	(segment
		(start 206.88 134.295)
		(end 206.88 134.32)
		(width 0.19)
		(layer "F.Cu")
		(net 1134)
	)
	(segment
		(start 206.954 131.488)
		(end 206.954 132.246401)
		(width 0.19)
		(layer "F.Cu")
		(net 1134)
	)
	(segment
		(start 208.86 134.295)
		(end 208.555 133.99)
		(width 0.19)
		(layer "F.Cu")
		(net 1135)
	)
	(segment
		(start 208.1385 132.261901)
		(end 208.154 132.246401)
		(width 0.19)
		(layer "F.Cu")
		(net 1135)
	)
	(segment
		(start 208.86 134.32)
		(end 208.86 134.295)
		(width 0.19)
		(layer "F.Cu")
		(net 1135)
	)
	(segment
		(start 208.1385 132.47687)
		(end 208.1385 132.261901)
		(width 0.19)
		(layer "F.Cu")
		(net 1135)
	)
	(segment
		(start 208.154 132.246401)
		(end 208.154 131.488)
		(width 0.19)
		(layer "F.Cu")
		(net 1135)
	)
	(segment
		(start 208.555 133.99)
		(end 208.555 132.89337)
		(width 0.19)
		(layer "F.Cu")
		(net 1135)
	)
	(segment
		(start 208.555 132.89337)
		(end 208.1385 132.47687)
		(width 0.19)
		(layer "F.Cu")
		(net 1135)
	)
	(segment
		(start 212.2 125.3)
		(end 212.3 125.2)
		(width 0.1)
		(layer "F.Cu")
		(net 1138)
	)
	(segment
		(start 212.3 125.2)
		(end 213.8 125.2)
		(width 0.1)
		(layer "F.Cu")
		(net 1138)
	)
	(segment
		(start 213.8 125.2)
		(end 214.2 125.6)
		(width 0.1)
		(layer "F.Cu")
		(net 1138)
	)
	(segment
		(start 211.142 125.3)
		(end 212.2 125.3)
		(width 0.1)
		(layer "F.Cu")
		(net 1138)
	)
	(via
		(at 214.2 125.6)
		(size 0.45)
		(drill 0.1)
		(layers "F.Cu" "B.Cu")
		(net 1138)
	)
	(segment
		(start 215.1 126.5)
		(end 215.62 126.5)
		(width 0.1)
		(layer "B.Cu")
		(net 1138)
	)
	(segment
		(start 214.2 125.6)
		(end 215.1 126.5)
		(width 0.1)
		(layer "B.Cu")
		(net 1138)
	)
	(segment
		(start 214.199 124.899)
		(end 214.8 125.5)
		(width 0.1)
		(layer "F.Cu")
		(net 1141)
	)
	(segment
		(start 211.142 124.899)
		(end 214.199 124.899)
		(width 0.1)
		(layer "F.Cu")
		(net 1141)
	)
	(via
		(at 214.8 125.5)
		(size 0.45)
		(drill 0.1)
		(layers "F.Cu" "B.Cu")
		(net 1141)
	)
	(segment
		(start 214.8 125.5)
		(end 215.62 125.5)
		(width 0.1)
		(layer "B.Cu")
		(net 1141)
	)
	(segment
		(start 204.553 131.488)
		(end 204.553 132.447)
		(width 0.1)
		(layer "F.Cu")
		(net 1142)
	)
	(segment
		(start 204.553 132.447)
		(end 204.25 132.75)
		(width 0.1)
		(layer "F.Cu")
		(net 1142)
	)
	(via
		(at 204.25 132.75)
		(size 0.45)
		(drill 0.1)
		(layers "F.Cu" "B.Cu")
		(net 1142)
	)
	(segment
		(start 202.1 132.4)
		(end 202.1 132.9)
		(width 0.1)
		(layer "B.Cu")
		(net 1142)
	)
	(segment
		(start 203.55 132.75)
		(end 204.25 132.75)
		(width 0.1)
		(layer "B.Cu")
		(net 1142)
	)
	(segment
		(start 201.3 130.98)
		(end 201.3 131.6)
		(width 0.1)
		(layer "B.Cu")
		(net 1142)
	)
	(segment
		(start 202.4 133.2)
		(end 203.1 133.2)
		(width 0.1)
		(layer "B.Cu")
		(net 1142)
	)
	(segment
		(start 201.3 131.6)
		(end 202.1 132.4)
		(width 0.1)
		(layer "B.Cu")
		(net 1142)
	)
	(segment
		(start 203.1 133.2)
		(end 203.55 132.75)
		(width 0.1)
		(layer "B.Cu")
		(net 1142)
	)
	(segment
		(start 202.1 132.9)
		(end 202.4 133.2)
		(width 0.1)
		(layer "B.Cu")
		(net 1142)
	)
	(segment
		(start 171.919468 119.226)
		(end 171.815 119.330468)
		(width 0.1)
		(layer "F.Cu")
		(net 1161)
	)
	(segment
		(start 171.815 119.330468)
		(end 171.815 120.401)
		(width 0.1)
		(layer "F.Cu")
		(net 1161)
	)
	(segment
		(start 171.919468 118.286)
		(end 171.919468 119.226)
		(width 0.1)
		(layer "F.Cu")
		(net 1161)
	)
	(segment
		(start 170.229468 135.92)
		(end 170.229468 134.645)
		(width 0.1)
		(layer "F.Cu")
		(net 1162)
	)
	(segment
		(start 170.304468 133.6)
		(end 170.304468 134.57)
		(width 0.1)
		(layer "F.Cu")
		(net 1162)
	)
	(segment
		(start 170.229468 134.645)
		(end 170.304468 134.57)
		(width 0.1)
		(layer "F.Cu")
		(net 1162)
	)
	(segment
		(start 204.8 132.2)
		(end 204.954 132.046)
		(width 0.1)
		(layer "F.Cu")
		(net 1163)
	)
	(segment
		(start 204.8 132.2)
		(end 204.8 132.85)
		(width 0.1)
		(layer "F.Cu")
		(net 1163)
	)
	(segment
		(start 204.8 132.85)
		(end 204.25 133.4)
		(width 0.1)
		(layer "F.Cu")
		(net 1163)
	)
	(segment
		(start 204.954 131.488)
		(end 204.954 132.046)
		(width 0.1)
		(layer "F.Cu")
		(net 1163)
	)
	(via
		(at 204.25 133.4)
		(size 0.45)
		(drill 0.1)
		(layers "F.Cu" "B.Cu")
		(net 1163)
	)
	(segment
		(start 201.2 132.3)
		(end 201.2 132.9)
		(width 0.1)
		(layer "B.Cu")
		(net 1163)
	)
	(segment
		(start 203.95 133.7)
		(end 204.25 133.4)
		(width 0.1)
		(layer "B.Cu")
		(net 1163)
	)
	(segment
		(start 200.3 131.4)
		(end 201.2 132.3)
		(width 0.1)
		(layer "B.Cu")
		(net 1163)
	)
	(segment
		(start 200.3 130.98)
		(end 200.3 131.4)
		(width 0.1)
		(layer "B.Cu")
		(net 1163)
	)
	(segment
		(start 202 133.7)
		(end 203.95 133.7)
		(width 0.1)
		(layer "B.Cu")
		(net 1163)
	)
	(segment
		(start 201.2 132.9)
		(end 202 133.7)
		(width 0.1)
		(layer "B.Cu")
		(net 1163)
	)
	(segment
		(start 202.5 134.9)
		(end 202.5 133.16)
		(width 0.19)
		(layer "F.Cu")
		(net 1164)
	)
	(segment
		(start 202.18 135.7)
		(end 202.18 135.22)
		(width 0.19)
		(layer "F.Cu")
		(net 1164)
	)
	(segment
		(start 202.18 135.22)
		(end 202.5 134.9)
		(width 0.19)
		(layer "F.Cu")
		(net 1164)
	)
	(segment
		(start 202.154 132.814)
		(end 202.154 131.488)
		(width 0.19)
		(layer "F.Cu")
		(net 1164)
	)
	(segment
		(start 202.5 133.16)
		(end 202.154 132.814)
		(width 0.19)
		(layer "F.Cu")
		(net 1164)
	)
	(segment
		(start 203.12 135.7)
		(end 202.18 135.7)
		(width 0.19)
		(layer "F.Cu")
		(net 1164)
	)
	(segment
		(start 188.202 119.202)
		(end 188.202 121.498)
		(width 0.1)
		(layer "F.Cu")
		(net 1165)
	)
	(segment
		(start 188.135 119.135)
		(end 187.1 119.135)
		(width 0.1)
		(layer "F.Cu")
		(net 1165)
	)
	(segment
		(start 188.202 121.498)
		(end 188.3 121.596)
		(width 0.1)
		(layer "F.Cu")
		(net 1165)
	)
	(segment
		(start 188.202 119.202)
		(end 188.135 119.135)
		(width 0.1)
		(layer "F.Cu")
		(net 1165)
	)
	(segment
		(start 188.3 121.596)
		(end 188.3 122.12)
		(width 0.1)
		(layer "F.Cu")
		(net 1165)
	)
	(segment
		(start 188.6 121)
		(end 189.3 121.7)
		(width 0.1)
		(layer "F.Cu")
		(net 1166)
	)
	(segment
		(start 188.6 119.6)
		(end 188.6 121)
		(width 0.1)
		(layer "F.Cu")
		(net 1166)
	)
	(segment
		(start 191.235 117.965)
		(end 191.2 118)
		(width 0.1)
		(layer "F.Cu")
		(net 1166)
	)
	(segment
		(start 189.3 121.7)
		(end 189.3 122.12)
		(width 0.1)
		(layer "F.Cu")
		(net 1166)
	)
	(segment
		(start 194.4 117.865)
		(end 194.3 117.965)
		(width 0.1)
		(layer "F.Cu")
		(net 1166)
	)
	(segment
		(start 194.3 117.965)
		(end 191.235 117.965)
		(width 0.1)
		(layer "F.Cu")
		(net 1166)
	)
	(via
		(at 188.6 119.6)
		(size 0.45)
		(drill 0.1)
		(layers "F.Cu" "B.Cu")
		(net 1166)
	)
	(via
		(at 191.2 118)
		(size 0.45)
		(drill 0.1)
		(layers "F.Cu" "B.Cu")
		(net 1166)
	)
	(segment
		(start 191.2 118)
		(end 189.6 118)
		(width 0.1)
		(layer "B.Cu")
		(net 1166)
	)
	(segment
		(start 188.6 119)
		(end 188.6 119.6)
		(width 0.1)
		(layer "B.Cu")
		(net 1166)
	)
	(segment
		(start 189.6 118)
		(end 188.6 119)
		(width 0.1)
		(layer "B.Cu")
		(net 1166)
	)
	(segment
		(start 153.2 98.8)
		(end 155.6 98.8)
		(width 0.1)
		(layer "F.Cu")
		(net 1167)
	)
	(via
		(at 126.9 134.3)
		(size 0.45)
		(drill 0.1)
		(layers "F.Cu" "B.Cu")
		(net 1167)
	)
	(via
		(at 155.6 98.8)
		(size 0.45)
		(drill 0.1)
		(layers "F.Cu" "B.Cu")
		(net 1167)
	)
	(via
		(at 149.3 108.8)
		(size 0.45)
		(drill 0.1)
		(layers "F.Cu" "B.Cu")
		(net 1167)
	)
	(segment
		(start 126.525 133.925)
		(end 126.9 134.3)
		(width 0.1)
		(layer "B.Cu")
		(net 1167)
	)
	(segment
		(start 125.08 133.925)
		(end 126.525 133.925)
		(width 0.1)
		(layer "B.Cu")
		(net 1167)
	)
	(segment
		(start 154.7 93.35)
		(end 155.6 94.25)
		(width 0.1)
		(layer "In5.Cu")
		(net 1167)
	)
	(segment
		(start 149.05 102.75)
		(end 149.05 100.7)
		(width 0.1)
		(layer "In5.Cu")
		(net 1167)
	)
	(segment
		(start 155.6 94.25)
		(end 155.6 98.8)
		(width 0.1)
		(layer "In5.Cu")
		(net 1167)
	)
	(segment
		(start 149.3 108.8)
		(end 149.3 103)
		(width 0.1)
		(layer "In5.Cu")
		(net 1167)
	)
	(segment
		(start 149.3 103)
		(end 149.05 102.75)
		(width 0.1)
		(layer "In5.Cu")
		(net 1167)
	)
	(segment
		(start 148.65 94.7)
		(end 150 93.35)
		(width 0.1)
		(layer "In5.Cu")
		(net 1167)
	)
	(segment
		(start 150 93.35)
		(end 154.7 93.35)
		(width 0.1)
		(layer "In5.Cu")
		(net 1167)
	)
	(segment
		(start 148.65 100.3)
		(end 148.65 94.7)
		(width 0.1)
		(layer "In5.Cu")
		(net 1167)
	)
	(segment
		(start 149.05 100.7)
		(end 148.65 100.3)
		(width 0.1)
		(layer "In5.Cu")
		(net 1167)
	)
	(segment
		(start 149.099998 109.000002)
		(end 149.3 108.8)
		(width 0.1)
		(layer "In7.Cu")
		(net 1167)
	)
	(segment
		(start 134.45 115.925738)
		(end 135.487869 114.887869)
		(width 0.1)
		(layer "In7.Cu")
		(net 1167)
	)
	(segment
		(start 141.375736 109.000002)
		(end 149.099998 109.000002)
		(width 0.1)
		(layer "In7.Cu")
		(net 1167)
	)
	(segment
		(start 129.9 133.5)
		(end 129.9 126.546148)
		(width 0.1)
		(layer "In7.Cu")
		(net 1167)
	)
	(segment
		(start 134.45 121.996148)
		(end 134.45 115.925738)
		(width 0.1)
		(layer "In7.Cu")
		(net 1167)
	)
	(segment
		(start 129.1 134.3)
		(end 129.9 133.5)
		(width 0.1)
		(layer "In7.Cu")
		(net 1167)
	)
	(segment
		(start 135.487869 114.887869)
		(end 135.487869 113.112131)
		(width 0.1)
		(layer "In7.Cu")
		(net 1167)
	)
	(segment
		(start 139.887869 110.487869)
		(end 141.375736 109.000002)
		(width 0.1)
		(layer "In7.Cu")
		(net 1167)
	)
	(segment
		(start 129.9 126.546148)
		(end 134.45 121.996148)
		(width 0.1)
		(layer "In7.Cu")
		(net 1167)
	)
	(segment
		(start 126.9 134.3)
		(end 129.1 134.3)
		(width 0.1)
		(layer "In7.Cu")
		(net 1167)
	)
	(segment
		(start 135.487869 113.112131)
		(end 138.112131 110.487869)
		(width 0.1)
		(layer "In7.Cu")
		(net 1167)
	)
	(segment
		(start 138.112131 110.487869)
		(end 139.887869 110.487869)
		(width 0.1)
		(layer "In7.Cu")
		(net 1167)
	)
	(segment
		(start 193.4 78)
		(end 192.6 78.8)
		(width 0.1)
		(layer "F.Cu")
		(net 1168)
	)
	(segment
		(start 196 76)
		(end 194.6 76)
		(width 0.1)
		(layer "F.Cu")
		(net 1168)
	)
	(segment
		(start 197.249 76.28)
		(end 196.28 76.28)
		(width 0.1)
		(layer "F.Cu")
		(net 1168)
	)
	(segment
		(start 193.4 77.2)
		(end 193.4 78)
		(width 0.1)
		(layer "F.Cu")
		(net 1168)
	)
	(segment
		(start 192.6 79.2)
		(end 191.1185 80.6815)
		(width 0.1)
		(layer "F.Cu")
		(net 1168)
	)
	(segment
		(start 191.1185 80.6815)
		(end 190.4 80.6815)
		(width 0.1)
		(layer "F.Cu")
		(net 1168)
	)
	(segment
		(start 196.28 76.28)
		(end 196 76)
		(width 0.1)
		(layer "F.Cu")
		(net 1168)
	)
	(segment
		(start 192.6 78.8)
		(end 192.6 79.2)
		(width 0.1)
		(layer "F.Cu")
		(net 1168)
	)
	(segment
		(start 194.6 76)
		(end 193.4 77.2)
		(width 0.1)
		(layer "F.Cu")
		(net 1168)
	)
	(via
		(at 190.4 80.6815)
		(size 0.45)
		(drill 0.1)
		(layers "F.Cu" "B.Cu")
		(net 1168)
	)
	(segment
		(start 161.748936 99.57)
		(end 161.748936 100.755532)
		(width 0.2)
		(layer "F.Cu")
		(net 1187)
	)
	(segment
		(start 161.734468 98.625)
		(end 161.734468 99.555532)
		(width 0.1)
		(layer "F.Cu")
		(net 1187)
	)
	(segment
		(start 161.734468 99.555532)
		(end 161.748936 99.57)
		(width 0.1)
		(layer "F.Cu")
		(net 1187)
	)
	(segment
		(start 161.748936 100.755532)
		(end 161.729468 100.775)
		(width 0.2)
		(layer "F.Cu")
		(net 1187)
	)
	(segment
		(start 132.530532 75.15)
		(end 132.525 75.15)
		(width 0.19)
		(layer "F.Cu")
		(net 1191)
	)
	(via
		(at 132.525 75.15)
		(size 0.45)
		(drill 0.1)
		(layers "F.Cu" "B.Cu")
		(net 1191)
	)
	(via
		(at 93.495002 107.6)
		(size 0.45)
		(drill 0.1)
		(layers "F.Cu" "B.Cu")
		(net 1191)
	)
	(segment
		(start 93.680001 105.98)
		(end 93.680001 106.005)
		(width 0.19)
		(layer "B.Cu")
		(net 1191)
	)
	(segment
		(start 93.365002 106.319999)
		(end 93.365002 107.47)
		(width 0.19)
		(layer "B.Cu")
		(net 1191)
	)
	(segment
		(start 93.680001 106.005)
		(end 93.365002 106.319999)
		(width 0.19)
		(layer "B.Cu")
		(net 1191)
	)
	(segment
		(start 93.365002 107.47)
		(end 93.495002 107.6)
		(width 0.19)
		(layer "B.Cu")
		(net 1191)
	)
	(segment
		(start 93.556956 106.9375)
		(end 93.743044 106.9375)
		(width 0.15)
		(layer "In7.Cu")
		(net 1191)
	)
	(segment
		(start 132.2125 75.4625)
		(end 132.525 75.15)
		(width 0.15)
		(layer "In7.Cu")
		(net 1191)
	)
	(segment
		(start 104.243044 116.7375)
		(end 104.643044 117.1375)
		(width 0.15)
		(layer "In7.Cu")
		(net 1191)
	)
	(segment
		(start 93.495002 107.6)
		(end 93.317502 107.4225)
		(width 0.15)
		(layer "In7.Cu")
		(net 1191)
	)
	(segment
		(start 98.786091 119.574999)
		(end 100.713909 119.574999)
		(width 0.15)
		(layer "In7.Cu")
		(net 1191)
	)
	(segment
		(start 131.870765 69.022686)
		(end 131.940765 69.022686)
		(width 0.15)
		(layer "In7.Cu")
		(net 1191)
	)
	(segment
		(start 132.406956 75.7625)
		(end 132.2125 75.568044)
		(width 0.15)
		(layer "In7.Cu")
		(net 1191)
	)
	(segment
		(start 133.9375 75.7625)
		(end 132.406956 75.7625)
		(width 0.15)
		(layer "In7.Cu")
		(net 1191)
	)
	(segment
		(start 134.3 72.7)
		(end 134.3 74)
		(width 0.15)
		(layer "In7.Cu")
		(net 1191)
	)
	(segment
		(start 95.3625 111.256956)
		(end 96.725001 112.619457)
		(width 0.15)
		(layer "In7.Cu")
		(net 1191)
	)
	(segment
		(start 123.1375 86.693044)
		(end 123.1375 82.506956)
		(width 0.15)
		(layer "In7.Cu")
		(net 1191)
	)
	(segment
		(start 95.111888 108.306344)
		(end 95.3625 108.556956)
		(width 0.15)
		(layer "In7.Cu")
		(net 1191)
	)
	(segment
		(start 123.1375 82.506956)
		(end 124.2375 81.406956)
		(width 0.15)
		(layer "In7.Cu")
		(net 1191)
	)
	(segment
		(start 100.713909 119.574999)
		(end 103.551408 116.7375)
		(width 0.15)
		(layer "In7.Cu")
		(net 1191)
	)
	(segment
		(start 121.5375 71.756956)
		(end 122.2375 71.056956)
		(width 0.15)
		(layer "In7.Cu")
		(net 1191)
	)
	(segment
		(start 132.220765 68.5375)
		(end 134.143044 68.5375)
		(width 0.15)
		(layer "In7.Cu")
		(net 1191)
	)
	(segment
		(start 123.1375 74.893044)
		(end 122.3375 74.093044)
		(width 0.15)
		(layer "In7.Cu")
		(net 1191)
	)
	(segment
		(start 134.3 74)
		(end 134.5 74.2)
		(width 0.15)
		(layer "In7.Cu")
		(net 1191)
	)
	(segment
		(start 123.1375 79.243044)
		(end 123.1375 74.893044)
		(width 0.15)
		(layer "In7.Cu")
		(net 1191)
	)
	(segment
		(start 122.2375 70.156956)
		(end 123.856956 68.5375)
		(width 0.15)
		(layer "In7.Cu")
		(net 1191)
	)
	(segment
		(start 134.143044 68.5375)
		(end 135.1 69.494456)
		(width 0.15)
		(layer "In7.Cu")
		(net 1191)
	)
	(segment
		(start 121.5375 72.343044)
		(end 121.5375 71.756956)
		(width 0.15)
		(layer "In7.Cu")
		(net 1191)
	)
	(segment
		(start 93.317502 107.176954)
		(end 93.556956 106.9375)
		(width 0.15)
		(layer "In7.Cu")
		(net 1191)
	)
	(segment
		(start 114.3875 116.101408)
		(end 114.3875 110.356956)
		(width 0.15)
		(layer "In7.Cu")
		(net 1191)
	)
	(segment
		(start 122.411353 102.333101)
		(end 122.411355 102.333101)
		(width 0.15)
		(layer "In7.Cu")
		(net 1191)
	)
	(segment
		(start 135.1 71.9)
		(end 134.3 72.7)
		(width 0.15)
		(layer "In7.Cu")
		(net 1191)
	)
	(segment
		(start 124.2375 80.343044)
		(end 123.1375 79.243044)
		(width 0.15)
		(layer "In7.Cu")
		(net 1191)
	)
	(segment
		(start 122.411355 102.333101)
		(end 124.925003 99.819453)
		(width 0.15)
		(layer "In7.Cu")
		(net 1191)
	)
	(segment
		(start 96.725001 112.619457)
		(end 96.725001 117.513909)
		(width 0.15)
		(layer "In7.Cu")
		(net 1191)
	)
	(segment
		(start 123.856956 68.5375)
		(end 131.590765 68.5375)
		(width 0.15)
		(layer "In7.Cu")
		(net 1191)
	)
	(segment
		(start 134.5 75.2)
		(end 133.9375 75.7625)
		(width 0.15)
		(layer "In7.Cu")
		(net 1191)
	)
	(segment
		(start 124.925003 99.819453)
		(end 124.925003 88.480547)
		(width 0.15)
		(layer "In7.Cu")
		(net 1191)
	)
	(segment
		(start 132.080765 68.882686)
		(end 132.080765 68.6775)
		(width 0.15)
		(layer "In7.Cu")
		(net 1191)
	)
	(segment
		(start 95.3625 108.556956)
		(end 95.3625 109.054096)
		(width 0.15)
		(layer "In7.Cu")
		(net 1191)
	)
	(segment
		(start 94.602772 108.000874)
		(end 94.330827 108.272818)
		(width 0.15)
		(layer "In7.Cu")
		(net 1191)
	)
	(segment
		(start 124.925003 88.480547)
		(end 123.1375 86.693044)
		(width 0.15)
		(layer "In7.Cu")
		(net 1191)
	)
	(segment
		(start 134.5 74.2)
		(end 134.5 75.2)
		(width 0.15)
		(layer "In7.Cu")
		(net 1191)
	)
	(segment
		(start 132.2125 75.568044)
		(end 132.2125 75.4625)
		(width 0.15)
		(layer "In7.Cu")
		(net 1191)
	)
	(segment
		(start 93.743044 106.9375)
		(end 94.602772 107.797228)
		(width 0.15)
		(layer "In7.Cu")
		(net 1191)
	)
	(segment
		(start 93.317502 107.4225)
		(end 93.317502 107.176954)
		(width 0.15)
		(layer "In7.Cu")
		(net 1191)
	)
	(segment
		(start 94.330827 108.476465)
		(end 94.381738 108.527376)
		(width 0.15)
		(layer "In7.Cu")
		(net 1191)
	)
	(segment
		(start 135.1 69.494456)
		(end 135.1 71.9)
		(width 0.15)
		(layer "In7.Cu")
		(net 1191)
	)
	(segment
		(start 124.2375 81.406956)
		(end 124.2375 80.343044)
		(width 0.15)
		(layer "In7.Cu")
		(net 1191)
	)
	(segment
		(start 94.585385 108.527376)
		(end 94.857329 108.255431)
		(width 0.15)
		(layer "In7.Cu")
		(net 1191)
	)
	(segment
		(start 96.725001 117.513909)
		(end 98.786091 119.574999)
		(width 0.15)
		(layer "In7.Cu")
		(net 1191)
	)
	(segment
		(start 122.2375 71.056956)
		(end 122.2375 70.156956)
		(width 0.15)
		(layer "In7.Cu")
		(net 1191)
	)
	(segment
		(start 103.551408 116.7375)
		(end 104.243044 116.7375)
		(width 0.15)
		(layer "In7.Cu")
		(net 1191)
	)
	(segment
		(start 114.3875 110.356956)
		(end 122.411353 102.333101)
		(width 0.15)
		(layer "In7.Cu")
		(net 1191)
	)
	(segment
		(start 95.3625 109.054096)
		(end 95.3625 111.256956)
		(width 0.15)
		(layer "In7.Cu")
		(net 1191)
	)
	(segment
		(start 104.643044 117.1375)
		(end 113.351408 117.1375)
		(width 0.15)
		(layer "In7.Cu")
		(net 1191)
	)
	(segment
		(start 113.351408 117.1375)
		(end 114.3875 116.101408)
		(width 0.15)
		(layer "In7.Cu")
		(net 1191)
	)
	(segment
		(start 122.3375 74.093044)
		(end 122.3375 73.143044)
		(width 0.15)
		(layer "In7.Cu")
		(net 1191)
	)
	(segment
		(start 131.730765 68.6775)
		(end 131.730765 68.882686)
		(width 0.15)
		(layer "In7.Cu")
		(net 1191)
	)
	(segment
		(start 95.060976 108.255431)
		(end 95.111888 108.306344)
		(width 0.15)
		(layer "In7.Cu")
		(net 1191)
	)
	(segment
		(start 122.3375 73.143044)
		(end 121.5375 72.343044)
		(width 0.15)
		(layer "In7.Cu")
		(net 1191)
	)
	(arc
		(start 94.857329 108.255431)
		(mid 94.959152 108.213255)
		(end 95.060976 108.255431)
		(width 0.15)
		(layer "In7.Cu")
		(net 1191)
	)
	(arc
		(start 131.730765 68.882686)
		(mid 131.77177 68.981681)
		(end 131.870765 69.022686)
		(width 0.15)
		(layer "In7.Cu")
		(net 1191)
	)
	(arc
		(start 131.940765 69.022686)
		(mid 132.03976 68.981681)
		(end 132.080765 68.882686)
		(width 0.15)
		(layer "In7.Cu")
		(net 1191)
	)
	(arc
		(start 94.602772 107.797228)
		(mid 94.644948 107.899051)
		(end 94.602772 108.000874)
		(width 0.15)
		(layer "In7.Cu")
		(net 1191)
	)
	(arc
		(start 132.080765 68.6775)
		(mid 132.12177 68.578505)
		(end 132.220765 68.5375)
		(width 0.15)
		(layer "In7.Cu")
		(net 1191)
	)
	(arc
		(start 94.381738 108.527376)
		(mid 94.483562 108.569552)
		(end 94.585385 108.527376)
		(width 0.15)
		(layer "In7.Cu")
		(net 1191)
	)
	(arc
		(start 94.330827 108.272818)
		(mid 94.288651 108.374641)
		(end 94.330827 108.476465)
		(width 0.15)
		(layer "In7.Cu")
		(net 1191)
	)
	(arc
		(start 131.590765 68.5375)
		(mid 131.68976 68.578505)
		(end 131.730765 68.6775)
		(width 0.15)
		(layer "In7.Cu")
		(net 1191)
	)
	(segment
		(start 182.092 90.708)
		(end 182.092 89.973)
		(width 0.2)
		(layer "B.Cu")
		(net 1200)
	)
	(segment
		(start 181.797 91.003)
		(end 182.092 90.708)
		(width 0.2)
		(layer "B.Cu")
		(net 1200)
	)
	(segment
		(start 180.464 91.003)
		(end 181.797 91.003)
		(width 0.2)
		(layer "B.Cu")
		(net 1200)
	)
	(segment
		(start 182.092 80.892)
		(end 182.092 81.23)
		(width 0.2)
		(layer "B.Cu")
		(net 1201)
	)
	(segment
		(start 180.459 80.383)
		(end 181.583 80.383)
		(width 0.2)
		(layer "B.Cu")
		(net 1201)
	)
	(segment
		(start 181.583 80.383)
		(end 182.092 80.892)
		(width 0.2)
		(layer "B.Cu")
		(net 1201)
	)
	(segment
		(start 181.657 85.743)
		(end 182.092 85.743)
		(width 0.2)
		(layer "B.Cu")
		(net 1202)
	)
	(segment
		(start 180.464 86.753)
		(end 180.647 86.753)
		(width 0.2)
		(layer "B.Cu")
		(net 1202)
	)
	(segment
		(start 180.647 86.753)
		(end 181.657 85.743)
		(width 0.2)
		(layer "B.Cu")
		(net 1202)
	)
	(segment
		(start 180.5 76.049)
		(end 181.549 76.049)
		(width 0.2)
		(layer "B.Cu")
		(net 1203)
	)
	(segment
		(start 181.549 76.049)
		(end 182.092 76.592)
		(width 0.2)
		(layer "B.Cu")
		(net 1203)
	)
	(segment
		(start 182.092 76.592)
		(end 182.092 77)
		(width 0.2)
		(layer "B.Cu")
		(net 1203)
	)
	(segment
		(start 179.999468 138.95)
		(end 180.859468 139.81)
		(width 0.2)
		(layer "F.Cu")
		(net 1204)
	)
	(segment
		(start 180.859468 139.81)
		(end 181.125 140.075532)
		(width 0.2)
		(layer "F.Cu")
		(net 1204)
	)
	(segment
		(start 179.93 138.95)
		(end 179.999468 138.95)
		(width 0.2)
		(layer "F.Cu")
		(net 1204)
	)
	(segment
		(start 181.125 140.075532)
		(end 181.125 141.06)
		(width 0.2)
		(layer "F.Cu")
		(net 1204)
	)
	(segment
		(start 181.575 140.085)
		(end 181.575 141.06)
		(width 0.2)
		(layer "F.Cu")
		(net 1205)
	)
	(segment
		(start 181.85 139.81)
		(end 181.575 140.085)
		(width 0.2)
		(layer "F.Cu")
		(net 1205)
	)
	(segment
		(start 183.73 139.95)
		(end 183.73 140.95)
		(width 0.2)
		(layer "F.Cu")
		(net 1206)
	)
	(segment
		(start 183.73 139)
		(end 183.73 139.95)
		(width 0.2)
		(layer "F.Cu")
		(net 1206)
	)
	(segment
		(start 182.94 141.725)
		(end 183.302499 141.725)
		(width 0.2)
		(layer "F.Cu")
		(net 1206)
	)
	(segment
		(start 183.5 141.165)
		(end 183.73 140.95)
		(width 0.2)
		(layer "F.Cu")
		(net 1206)
	)
	(segment
		(start 183.5 141.527499)
		(end 183.5 141.165)
		(width 0.2)
		(layer "F.Cu")
		(net 1206)
	)
	(segment
		(start 183.302499 141.725)
		(end 183.5 141.527499)
		(width 0.2)
		(layer "F.Cu")
		(net 1206)
	)
	(segment
		(start 179.604468 87.205)
		(end 179.604468 87.679468)
		(width 0.15)
		(layer "F.Cu")
		(net 1207)
	)
	(segment
		(start 179.174734 86.775266)
		(end 178.994734 86.775266)
		(width 0.15)
		(layer "F.Cu")
		(net 1207)
	)
	(segment
		(start 179.825 88.51)
		(end 179.825 87.9)
		(width 0.15)
		(layer "F.Cu")
		(net 1207)
	)
	(segment
		(start 179.174734 86.775266)
		(end 179.604468 87.205)
		(width 0.15)
		(layer "F.Cu")
		(net 1207)
	)
	(segment
		(start 179.604468 87.679468)
		(end 179.825 87.9)
		(width 0.15)
		(layer "F.Cu")
		(net 1207)
	)
	(segment
		(start 178.994734 86.775266)
		(end 178.674468 86.455)
		(width 0.15)
		(layer "F.Cu")
		(net 1207)
	)
	(segment
		(start 179.009468 66.51)
		(end 179.449468 66.95)
		(width 0.15)
		(layer "F.Cu")
		(net 1208)
	)
	(segment
		(start 179.949468 66.95)
		(end 179.949468 67.525532)
		(width 0.15)
		(layer "F.Cu")
		(net 1208)
	)
	(segment
		(start 179.949468 67.525532)
		(end 179.825 67.65)
		(width 0.15)
		(layer "F.Cu")
		(net 1208)
	)
	(segment
		(start 179.449468 66.95)
		(end 179.949468 66.95)
		(width 0.15)
		(layer "F.Cu")
		(net 1208)
	)
	(segment
		(start 179.825 68.51)
		(end 179.825 67.65)
		(width 0.15)
		(layer "F.Cu")
		(net 1208)
	)
	(segment
		(start 134.130532 76.65)
		(end 134.125 76.65)
		(width 0.19)
		(layer "F.Cu")
		(net 1209)
	)
	(via
		(at 134.125 76.65)
		(size 0.45)
		(drill 0.1)
		(layers "F.Cu" "B.Cu")
		(net 1209)
	)
	(via
		(at 93.3 109.0875)
		(size 0.45)
		(drill 0.1)
		(layers "F.Cu" "B.Cu")
		(net 1209)
	)
	(segment
		(start 93.815 109.52337)
		(end 93.62337 109.715)
		(width 0.19)
		(layer "B.Cu")
		(net 1209)
	)
	(segment
		(start 90.475 106.285001)
		(end 90.780001 105.98)
		(width 0.19)
		(layer "B.Cu")
		(net 1209)
	)
	(segment
		(start 93.4025 108.985)
		(end 93.62337 108.985)
		(width 0.19)
		(layer "B.Cu")
		(net 1209)
	)
	(segment
		(start 93.62337 108.985)
		(end 93.815 109.17663)
		(width 0.19)
		(layer "B.Cu")
		(net 1209)
	)
	(segment
		(start 93.62337 109.715)
		(end 91.77663 109.715)
		(width 0.19)
		(layer "B.Cu")
		(net 1209)
	)
	(segment
		(start 90.475 108.41337)
		(end 90.475 106.285001)
		(width 0.19)
		(layer "B.Cu")
		(net 1209)
	)
	(segment
		(start 91.77663 109.715)
		(end 90.475 108.41337)
		(width 0.19)
		(layer "B.Cu")
		(net 1209)
	)
	(segment
		(start 93.3 109.0875)
		(end 93.4025 108.985)
		(width 0.19)
		(layer "B.Cu")
		(net 1209)
	)
	(segment
		(start 93.815 109.17663)
		(end 93.815 109.52337)
		(width 0.19)
		(layer "B.Cu")
		(net 1209)
	)
	(segment
		(start 94.299388 109.593844)
		(end 94.310114 109.60457)
		(width 0.15)
		(layer "In7.Cu")
		(net 1209)
	)
	(segment
		(start 93.45 108.9375)
		(end 93.643044 108.9375)
		(width 0.15)
		(layer "In7.Cu")
		(net 1209)
	)
	(segment
		(start 94.310114 109.60457)
		(end 94.4625 109.756956)
		(width 0.15)
		(layer "In7.Cu")
		(net 1209)
	)
	(segment
		(start 128.178338 69.9375)
		(end 130.581089 69.9375)
		(width 0.15)
		(layer "In7.Cu")
		(net 1209)
	)
	(segment
		(start 94.248476 109.542931)
		(end 94.299388 109.593844)
		(width 0.15)
		(layer "In7.Cu")
		(net 1209)
	)
	(segment
		(start 130.368044 74.2625)
		(end 129.8375 74.793044)
		(width 0.15)
		(layer "In7.Cu")
		(net 1209)
	)
	(segment
		(start 103.331135 118.074999)
		(end 113.531135 118.074999)
		(width 0.15)
		(layer "In7.Cu")
		(net 1209)
	)
	(segment
		(start 125.0375 82.856956)
		(end 125.0375 81.543044)
		(width 0.15)
		(layer "In7.Cu")
		(net 1209)
	)
	(segment
		(start 124.8875 87.143044)
		(end 124.8875 85.956956)
		(width 0.15)
		(layer "In7.Cu")
		(net 1209)
	)
	(segment
		(start 125.0375 81.543044)
		(end 124.7875 81.293044)
		(width 0.15)
		(layer "In7.Cu")
		(net 1209)
	)
	(segment
		(start 125.0875 85.756956)
		(end 125.0875 84.993044)
		(width 0.15)
		(layer "In7.Cu")
		(net 1209)
	)
	(segment
		(start 124.6875 84.593044)
		(end 124.6875 83.206956)
		(width 0.15)
		(layer "In7.Cu")
		(net 1209)
	)
	(segment
		(start 133.8125 76.9625)
		(end 134.125 76.65)
		(width 0.15)
		(layer "In7.Cu")
		(net 1209)
	)
	(segment
		(start 123.8375 76.893044)
		(end 123.8375 76.256956)
		(width 0.15)
		(layer "In7.Cu")
		(net 1209)
	)
	(segment
		(start 115.3875 116.218634)
		(end 115.3875 111.656956)
		(width 0.15)
		(layer "In7.Cu")
		(net 1209)
	)
	(segment
		(start 127.618338 70.0775)
		(end 127.618338 70.416445)
		(width 0.15)
		(layer "In7.Cu")
		(net 1209)
	)
	(segment
		(start 94.0625 111.343044)
		(end 94.0625 112.556956)
		(width 0.15)
		(layer "In7.Cu")
		(net 1209)
	)
	(segment
		(start 93.643044 108.9375)
		(end 93.790272 109.084728)
		(width 0.15)
		(layer "In7.Cu")
		(net 1209)
	)
	(segment
		(start 123.0875 70.931956)
		(end 124.081956 69.9375)
		(width 0.15)
		(layer "In7.Cu")
		(net 1209)
	)
	(segment
		(start 94.0625 112.556956)
		(end 95.935003 114.429459)
		(width 0.15)
		(layer "In7.Cu")
		(net 1209)
	)
	(segment
		(start 124.7875 81.293044)
		(end 124.7875 80.256956)
		(width 0.15)
		(layer "In7.Cu")
		(net 1209)
	)
	(segment
		(start 129.8375 74.793044)
		(end 129.8375 75.368044)
		(width 0.15)
		(layer "In7.Cu")
		(net 1209)
	)
	(segment
		(start 94.4625 110.943044)
		(end 94.0625 111.343044)
		(width 0.15)
		(layer "In7.Cu")
		(net 1209)
	)
	(segment
		(start 124.2375 74.343044)
		(end 123.0875 73.193044)
		(width 0.15)
		(layer "In7.Cu")
		(net 1209)
	)
	(segment
		(start 132.768044 74.2625)
		(end 130.368044 74.2625)
		(width 0.15)
		(layer "In7.Cu")
		(net 1209)
	)
	(segment
		(start 128.8875 77.206956)
		(end 129.368044 77.6875)
		(width 0.15)
		(layer "In7.Cu")
		(net 1209)
	)
	(segment
		(start 124.8875 85.956956)
		(end 125.0875 85.756956)
		(width 0.15)
		(layer "In7.Cu")
		(net 1209)
	)
	(segment
		(start 124.9375 80.106956)
		(end 124.9375 79.343044)
		(width 0.15)
		(layer "In7.Cu")
		(net 1209)
	)
	(segment
		(start 129.368044 77.6875)
		(end 133.331956 77.6875)
		(width 0.15)
		(layer "In7.Cu")
		(net 1209)
	)
	(segment
		(start 124.2375 78.643044)
		(end 124.2375 77.293044)
		(width 0.15)
		(layer "In7.Cu")
		(net 1209)
	)
	(segment
		(start 130.581089 69.9375)
		(end 133.243044 69.9375)
		(width 0.15)
		(layer "In7.Cu")
		(net 1209)
	)
	(segment
		(start 125.715001 87.970545)
		(end 124.8875 87.143044)
		(width 0.15)
		(layer "In7.Cu")
		(net 1209)
	)
	(segment
		(start 123.8375 76.256956)
		(end 124.2375 75.856956)
		(width 0.15)
		(layer "In7.Cu")
		(net 1209)
	)
	(segment
		(start 113.531135 118.074999)
		(end 115.3875 116.218634)
		(width 0.15)
		(layer "In7.Cu")
		(net 1209)
	)
	(segment
		(start 133.243044 69.9375)
		(end 133.6125 70.306956)
		(width 0.15)
		(layer "In7.Cu")
		(net 1209)
	)
	(segment
		(start 98.458863 120.364997)
		(end 101.041137 120.364997)
		(width 0.15)
		(layer "In7.Cu")
		(net 1209)
	)
	(segment
		(start 95.935003 114.429459)
		(end 95.935003 117.841137)
		(width 0.15)
		(layer "In7.Cu")
		(net 1209)
	)
	(segment
		(start 127.758338 70.556445)
		(end 127.828338 70.556445)
		(width 0.15)
		(layer "In7.Cu")
		(net 1209)
	)
	(segment
		(start 124.9375 79.343044)
		(end 124.2375 78.643044)
		(width 0.15)
		(layer "In7.Cu")
		(net 1209)
	)
	(segment
		(start 93.3 109.0875)
		(end 93.45 108.9375)
		(width 0.15)
		(layer "In7.Cu")
		(net 1209)
	)
	(segment
		(start 133.8125 77.206956)
		(end 133.8125 76.9625)
		(width 0.15)
		(layer "In7.Cu")
		(net 1209)
	)
	(segment
		(start 123.0875 73.193044)
		(end 123.0875 70.931956)
		(width 0.15)
		(layer "In7.Cu")
		(net 1209)
	)
	(segment
		(start 124.6875 83.206956)
		(end 125.0375 82.856956)
		(width 0.15)
		(layer "In7.Cu")
		(net 1209)
	)
	(segment
		(start 124.2375 77.293044)
		(end 123.8375 76.893044)
		(width 0.15)
		(layer "In7.Cu")
		(net 1209)
	)
	(segment
		(start 115.3875 111.656956)
		(end 125.715001 101.329455)
		(width 0.15)
		(layer "In7.Cu")
		(net 1209)
	)
	(segment
		(start 128.8875 76.318044)
		(end 128.8875 77.206956)
		(width 0.15)
		(layer "In7.Cu")
		(net 1209)
	)
	(segment
		(start 129.8375 75.368044)
		(end 128.8875 76.318044)
		(width 0.15)
		(layer "In7.Cu")
		(net 1209)
	)
	(segment
		(start 124.7875 80.256956)
		(end 124.9375 80.106956)
		(width 0.15)
		(layer "In7.Cu")
		(net 1209)
	)
	(segment
		(start 128.108338 69.9375)
		(end 128.178338 69.9375)
		(width 0.15)
		(layer "In7.Cu")
		(net 1209)
	)
	(segment
		(start 93.60501 109.677282)
		(end 93.655921 109.728193)
		(width 0.15)
		(layer "In7.Cu")
		(net 1209)
	)
	(segment
		(start 127.968338 70.416445)
		(end 127.968338 70.0775)
		(width 0.15)
		(layer "In7.Cu")
		(net 1209)
	)
	(segment
		(start 125.715001 101.329455)
		(end 125.715001 87.970545)
		(width 0.15)
		(layer "In7.Cu")
		(net 1209)
	)
	(segment
		(start 93.859568 109.728193)
		(end 94.044829 109.542931)
		(width 0.15)
		(layer "In7.Cu")
		(net 1209)
	)
	(segment
		(start 133.331956 77.6875)
		(end 133.8125 77.206956)
		(width 0.15)
		(layer "In7.Cu")
		(net 1209)
	)
	(segment
		(start 94.4625 109.756956)
		(end 94.4625 110.943044)
		(width 0.15)
		(layer "In7.Cu")
		(net 1209)
	)
	(segment
		(start 125.0875 84.993044)
		(end 124.6875 84.593044)
		(width 0.15)
		(layer "In7.Cu")
		(net 1209)
	)
	(segment
		(start 124.081956 69.9375)
		(end 127.478338 69.9375)
		(width 0.15)
		(layer "In7.Cu")
		(net 1209)
	)
	(segment
		(start 101.041137 120.364997)
		(end 103.331135 118.074999)
		(width 0.15)
		(layer "In7.Cu")
		(net 1209)
	)
	(segment
		(start 95.935003 117.841137)
		(end 98.458863 120.364997)
		(width 0.15)
		(layer "In7.Cu")
		(net 1209)
	)
	(segment
		(start 133.6125 70.306956)
		(end 133.6125 73.418044)
		(width 0.15)
		(layer "In7.Cu")
		(net 1209)
	)
	(segment
		(start 93.790272 109.288374)
		(end 93.60501 109.473635)
		(width 0.15)
		(layer "In7.Cu")
		(net 1209)
	)
	(segment
		(start 133.6125 73.418044)
		(end 132.768044 74.2625)
		(width 0.15)
		(layer "In7.Cu")
		(net 1209)
	)
	(segment
		(start 124.2375 75.856956)
		(end 124.2375 74.343044)
		(width 0.15)
		(layer "In7.Cu")
		(net 1209)
	)
	(arc
		(start 127.968338 70.0775)
		(mid 128.009343 69.978505)
		(end 128.108338 69.9375)
		(width 0.15)
		(layer "In7.Cu")
		(net 1209)
	)
	(arc
		(start 127.618338 70.416445)
		(mid 127.659343 70.51544)
		(end 127.758338 70.556445)
		(width 0.15)
		(layer "In7.Cu")
		(net 1209)
	)
	(arc
		(start 93.60501 109.473635)
		(mid 93.562834 109.575458)
		(end 93.60501 109.677282)
		(width 0.15)
		(layer "In7.Cu")
		(net 1209)
	)
	(arc
		(start 94.044829 109.542931)
		(mid 94.146652 109.500755)
		(end 94.248476 109.542931)
		(width 0.15)
		(layer "In7.Cu")
		(net 1209)
	)
	(arc
		(start 93.655921 109.728193)
		(mid 93.757745 109.770369)
		(end 93.859568 109.728193)
		(width 0.15)
		(layer "In7.Cu")
		(net 1209)
	)
	(arc
		(start 93.790272 109.084728)
		(mid 93.832448 109.186551)
		(end 93.790272 109.288374)
		(width 0.15)
		(layer "In7.Cu")
		(net 1209)
	)
	(arc
		(start 127.478338 69.9375)
		(mid 127.577333 69.978505)
		(end 127.618338 70.0775)
		(width 0.15)
		(layer "In7.Cu")
		(net 1209)
	)
	(arc
		(start 127.828338 70.556445)
		(mid 127.927333 70.51544)
		(end 127.968338 70.416445)
		(width 0.15)
		(layer "In7.Cu")
		(net 1209)
	)
	(segment
		(start 180.889468 66.95)
		(end 180.275 67.564468)
		(width 0.15)
		(layer "F.Cu")
		(net 1210)
	)
	(segment
		(start 180.275 67.564468)
		(end 180.275 68.51)
		(width 0.15)
		(layer "F.Cu")
		(net 1210)
	)
	(segment
		(start 181.28 67.42)
		(end 180.725 67.975)
		(width 0.15)
		(layer "F.Cu")
		(net 1211)
	)
	(segment
		(start 180.725 67.975)
		(end 180.725 68.51)
		(width 0.15)
		(layer "F.Cu")
		(net 1211)
	)
	(via
		(at 181.5 67.4)
		(size 0.45)
		(drill 0.1)
		(layers "F.Cu" "B.Cu")
		(net 1211)
	)
	(segment
		(start 181.5 67.4)
		(end 178.78 67.4)
		(width 0.1)
		(layer "B.Cu")
		(net 1211)
	)
	(segment
		(start 178.78 66.3)
		(end 178.78 67.4)
		(width 0.1)
		(layer "B.Cu")
		(net 1211)
	)
	(segment
		(start 180.41 107.24)
		(end 180.17 107.24)
		(width 0.2)
		(layer "F.Cu")
		(net 1212)
	)
	(segment
		(start 181.125 109.06)
		(end 181.125 107.955)
		(width 0.2)
		(layer "F.Cu")
		(net 1212)
	)
	(segment
		(start 180.41 107.24)
		(end 180.8 107.63)
		(width 0.2)
		(layer "F.Cu")
		(net 1212)
	)
	(segment
		(start 181.125 107.955)
		(end 180.8 107.63)
		(width 0.2)
		(layer "F.Cu")
		(net 1212)
	)
	(segment
		(start 180.17 107.24)
		(end 179.88 106.95)
		(width 0.2)
		(layer "F.Cu")
		(net 1212)
	)
	(segment
		(start 180.551652 124.631652)
		(end 179.87 123.95)
		(width 0.2)
		(layer "F.Cu")
		(net 1213)
	)
	(segment
		(start 180.551652 124.677356)
		(end 180.551652 124.631652)
		(width 0.2)
		(layer "F.Cu")
		(net 1213)
	)
	(segment
		(start 181.115 125.240704)
		(end 180.551652 124.677356)
		(width 0.2)
		(layer "F.Cu")
		(net 1213)
	)
	(segment
		(start 181.115 126.06)
		(end 181.115 125.240704)
		(width 0.2)
		(layer "F.Cu")
		(net 1213)
	)
	(segment
		(start 180.554468 87.205)
		(end 180.554468 87.620532)
		(width 0.15)
		(layer "F.Cu")
		(net 1214)
	)
	(segment
		(start 180.554468 87.620532)
		(end 180.275 87.9)
		(width 0.15)
		(layer "F.Cu")
		(net 1214)
	)
	(segment
		(start 180.275 88.51)
		(end 180.275 87.9)
		(width 0.15)
		(layer "F.Cu")
		(net 1214)
	)
	(segment
		(start 181.575 109.06)
		(end 181.575 107.805)
		(width 0.2)
		(layer "F.Cu")
		(net 1215)
	)
	(segment
		(start 181.575 107.805)
		(end 181.75 107.63)
		(width 0.2)
		(layer "F.Cu")
		(net 1215)
	)
	(segment
		(start 181.565 126.06)
		(end 181.565 124.805)
		(width 0.2)
		(layer "F.Cu")
		(net 1216)
	)
	(segment
		(start 183.68 107)
		(end 183.68 107.98)
		(width 0.2)
		(layer "F.Cu")
		(net 1217)
	)
	(segment
		(start 182.94 108.72)
		(end 182.94 109.725)
		(width 0.2)
		(layer "F.Cu")
		(net 1217)
	)
	(segment
		(start 183.68 107.98)
		(end 182.94 108.72)
		(width 0.2)
		(layer "F.Cu")
		(net 1217)
	)
	(segment
		(start 183.413525 123.947019)
		(end 183.451706 123.947019)
		(width 0.2)
		(layer "F.Cu")
		(net 1218)
	)
	(segment
		(start 183.451706 123.947019)
		(end 183.468579 123.963892)
		(width 0.2)
		(layer "F.Cu")
		(net 1218)
	)
	(segment
		(start 183.468579 125.481421)
		(end 182.93 126.02)
		(width 0.2)
		(layer "F.Cu")
		(net 1218)
	)
	(segment
		(start 183.468579 123.963892)
		(end 183.468579 125.481421)
		(width 0.2)
		(layer "F.Cu")
		(net 1218)
	)
	(segment
		(start 182.93 126.02)
		(end 182.93 126.725)
		(width 0.2)
		(layer "F.Cu")
		(net 1218)
	)
	(segment
		(start 181.64 88.94)
		(end 182.265 88.315)
		(width 0.2)
		(layer "F.Cu")
		(net 1219)
	)
	(segment
		(start 181.64 89.175)
		(end 181.64 88.94)
		(width 0.2)
		(layer "F.Cu")
		(net 1219)
	)
	(segment
		(start 183.744468 88.315)
		(end 183.754468 88.305)
		(width 0.2)
		(layer "F.Cu")
		(net 1219)
	)
	(segment
		(start 182.764468 88.315)
		(end 183.744468 88.315)
		(width 0.2)
		(layer "F.Cu")
		(net 1219)
	)
	(segment
		(start 182.265 88.315)
		(end 182.764468 88.315)
		(width 0.2)
		(layer "F.Cu")
		(net 1219)
	)
	(segment
		(start 183.659468 68.19)
		(end 183.809468 68.19)
		(width 0.2)
		(layer "F.Cu")
		(net 1220)
	)
	(segment
		(start 181.64 68.86)
		(end 182.185 68.315)
		(width 0.2)
		(layer "F.Cu")
		(net 1220)
	)
	(segment
		(start 182.185 68.315)
		(end 182.185 68.305322)
		(width 0.2)
		(layer "F.Cu")
		(net 1220)
	)
	(segment
		(start 182.185 68.305322)
		(end 182.290322 68.2)
		(width 0.2)
		(layer "F.Cu")
		(net 1220)
	)
	(segment
		(start 183.649468 68.2)
		(end 183.659468 68.19)
		(width 0.2)
		(layer "F.Cu")
		(net 1220)
	)
	(segment
		(start 182.290322 68.2)
		(end 183.649468 68.2)
		(width 0.2)
		(layer "F.Cu")
		(net 1220)
	)
	(segment
		(start 181.64 69.175)
		(end 181.64 68.86)
		(width 0.2)
		(layer "F.Cu")
		(net 1220)
	)
	(segment
		(start 161.729468 79.47)
		(end 161.769468 79.51)
		(width 0.1)
		(layer "F.Cu")
		(net 1221)
	)
	(segment
		(start 161.729468 78.59)
		(end 161.729468 79.47)
		(width 0.1)
		(layer "F.Cu")
		(net 1221)
	)
	(segment
		(start 161.647234 79.632234)
		(end 161.769468 79.51)
		(width 0.1)
		(layer "F.Cu")
		(net 1221)
	)
	(segment
		(start 161.647234 80.652234)
		(end 161.647234 79.632234)
		(width 0.1)
		(layer "F.Cu")
		(net 1221)
	)
	(segment
		(start 145.105391 127.463)
		(end 145.105391 126.709)
		(width 0.2)
		(layer "F.Cu")
		(net 1222)
	)
	(segment
		(start 145.105391 126.709)
		(end 145.424391 126.39)
		(width 0.2)
		(layer "F.Cu")
		(net 1222)
	)
	(segment
		(start 144.494391 126.39)
		(end 144.484391 126.4)
		(width 0.2)
		(layer "F.Cu")
		(net 1222)
	)
	(segment
		(start 145.424391 126.39)
		(end 144.494391 126.39)
		(width 0.2)
		(layer "F.Cu")
		(net 1222)
	)
	(segment
		(start 130.530532 73.65)
		(end 130.525 73.65)
		(width 0.19)
		(layer "F.Cu")
		(net 1223)
	)
	(via
		(at 92.8125 110.7)
		(size 0.45)
		(drill 0.1)
		(layers "F.Cu" "B.Cu")
		(net 1223)
	)
	(via
		(at 130.525 73.65)
		(size 0.45)
		(drill 0.1)
		(layers "F.Cu" "B.Cu")
		(net 1223)
	)
	(segment
		(start 94.865001 104.42)
		(end 94.865001 107.203371)
		(width 0.19)
		(layer "B.Cu")
		(net 1223)
	)
	(segment
		(start 95.285 110.77663)
		(end 94.27663 111.785)
		(width 0.19)
		(layer "B.Cu")
		(net 1223)
	)
	(segment
		(start 95.180001 104.08)
		(end 95.180001 104.105)
		(width 0.19)
		(layer "B.Cu")
		(net 1223)
	)
	(segment
		(start 93.32337 111.785)
		(end 92.915 111.37663)
		(width 0.19)
		(layer "B.Cu")
		(net 1223)
	)
	(segment
		(start 95.180001 104.105)
		(end 94.865001 104.42)
		(width 0.19)
		(layer "B.Cu")
		(net 1223)
	)
	(segment
		(start 94.865001 107.203371)
		(end 95.285 107.62337)
		(width 0.19)
		(layer "B.Cu")
		(net 1223)
	)
	(segment
		(start 92.915 111.37663)
		(end 92.915 110.8025)
		(width 0.19)
		(layer "B.Cu")
		(net 1223)
	)
	(segment
		(start 94.27663 111.785)
		(end 93.32337 111.785)
		(width 0.19)
		(layer "B.Cu")
		(net 1223)
	)
	(segment
		(start 92.915 110.8025)
		(end 92.8125 110.7)
		(width 0.19)
		(layer "B.Cu")
		(net 1223)
	)
	(segment
		(start 95.285 107.62337)
		(end 95.285 110.77663)
		(width 0.19)
		(layer "B.Cu")
		(net 1223)
	)
	(segment
		(start 118.45702 111.912213)
		(end 118.556014 111.813218)
		(width 0.15)
		(layer "In7.Cu")
		(net 1223)
	)
	(segment
		(start 126.9375 87.606956)
		(end 126.9375 86.443044)
		(width 0.15)
		(layer "In7.Cu")
		(net 1223)
	)
	(segment
		(start 119.446971 110.922264)
		(end 119.545966 110.823268)
		(width 0.15)
		(layer "In7.Cu")
		(net 1223)
	)
	(segment
		(start 118.183795 110.249523)
		(end 118.36991 110.435638)
		(width 0.15)
		(layer "In7.Cu")
		(net 1223)
	)
	(segment
		(start 130.8375 73.3375)
		(end 130.525 73.65)
		(width 0.15)
		(layer "In7.Cu")
		(net 1223)
	)
	(segment
		(start 125.0375 73.043044)
		(end 124.5375 72.543044)
		(width 0.15)
		(layer "In7.Cu")
		(net 1223)
	)
	(segment
		(start 118.166617 110.833384)
		(end 118.069389 110.736156)
		(width 0.15)
		(layer "In7.Cu")
		(net 1223)
	)
	(segment
		(start 118.364603 111.031371)
		(end 118.166613 110.833381)
		(width 0.15)
		(layer "In7.Cu")
		(net 1223)
	)
	(segment
		(start 117.675175 111.720803)
		(end 117.866585 111.912213)
		(width 0.15)
		(layer "In7.Cu")
		(net 1223)
	)
	(segment
		(start 125.1375 75.593044)
		(end 124.8875 75.343044)
		(width 0.15)
		(layer "In7.Cu")
		(net 1223)
	)
	(segment
		(start 95.125001 114.919457)
		(end 95.125001 118.176651)
		(width 0.15)
		(layer "In7.Cu")
		(net 1223)
	)
	(segment
		(start 124.8875 74.106956)
		(end 125.0375 73.956956)
		(width 0.15)
		(layer "In7.Cu")
		(net 1223)
	)
	(segment
		(start 113.86665 118.885)
		(end 116.674999 116.076651)
		(width 0.15)
		(layer "In7.Cu")
		(net 1223)
	)
	(segment
		(start 126.7375 83.806956)
		(end 126.7375 83.093044)
		(width 0.15)
		(layer "In7.Cu")
		(net 1223)
	)
	(segment
		(start 126.4875 82.843044)
		(end 126.4875 81.356956)
		(width 0.15)
		(layer "In7.Cu")
		(net 1223)
	)
	(segment
		(start 126.9375 94.743044)
		(end 126.5375 94.343044)
		(width 0.15)
		(layer "In7.Cu")
		(net 1223)
	)
	(segment
		(start 123.201809 105.992647)
		(end 126.9375 102.256956)
		(width 0.15)
		(layer "In7.Cu")
		(net 1223)
	)
	(segment
		(start 125.056956 71.4375)
		(end 132.143044 71.4375)
		(width 0.15)
		(layer "In7.Cu")
		(net 1223)
	)
	(segment
		(start 126.525002 89.082265)
		(end 126.525002 88.019454)
		(width 0.15)
		(layer "In7.Cu")
		(net 1223)
	)
	(segment
		(start 125.156956 78.5625)
		(end 124.8375 78.243044)
		(width 0.15)
		(layer "In7.Cu")
		(net 1223)
	)
	(segment
		(start 132.143044 71.4375)
		(end 132.7625 72.056956)
		(width 0.15)
		(layer "In7.Cu")
		(net 1223)
	)
	(segment
		(start 124.8375 77.156956)
		(end 125.1375 76.856956)
		(width 0.15)
		(layer "In7.Cu")
		(net 1223)
	)
	(segment
		(start 126.7375 83.093044)
		(end 126.4875 82.843044)
		(width 0.15)
		(layer "In7.Cu")
		(net 1223)
	)
	(segment
		(start 125.9875 84.556956)
		(end 126.7375 83.806956)
		(width 0.15)
		(layer "In7.Cu")
		(net 1223)
	)
	(segment
		(start 98.123349 121.174999)
		(end 101.376651 121.174999)
		(width 0.15)
		(layer "In7.Cu")
		(net 1223)
	)
	(segment
		(start 118.467137 110.532865)
		(end 118.467136 110.532863)
		(width 0.15)
		(layer "In7.Cu")
		(net 1223)
	)
	(segment
		(start 119.453552 109.740903)
		(end 123.201809 105.992647)
		(width 0.15)
		(layer "In7.Cu")
		(net 1223)
	)
	(segment
		(start 116.674998 112.519456)
		(end 116.675 112.519456)
		(width 0.15)
		(layer "In7.Cu")
		(net 1223)
	)
	(segment
		(start 126.4375 79.743044)
		(end 126.4375 79.143044)
		(width 0.15)
		(layer "In7.Cu")
		(net 1223)
	)
	(segment
		(start 126.6375 81.206956)
		(end 126.6375 79.943044)
		(width 0.15)
		(layer "In7.Cu")
		(net 1223)
	)
	(segment
		(start 131.243044 72.7625)
		(end 130.8375 73.168044)
		(width 0.15)
		(layer "In7.Cu")
		(net 1223)
	)
	(segment
		(start 124.8875 75.343044)
		(end 124.8875 74.106956)
		(width 0.15)
		(layer "In7.Cu")
		(net 1223)
	)
	(segment
		(start 124.5375 71.956956)
		(end 125.056956 71.4375)
		(width 0.15)
		(layer "In7.Cu")
		(net 1223)
	)
	(segment
		(start 119.354555 109.839897)
		(end 119.453552 109.740903)
		(width 0.15)
		(layer "In7.Cu")
		(net 1223)
	)
	(segment
		(start 118.556014 111.222782)
		(end 118.364603 111.031371)
		(width 0.15)
		(layer "In7.Cu")
		(net 1223)
	)
	(segment
		(start 132.7625 72.056956)
		(end 132.7625 72.543044)
		(width 0.15)
		(layer "In7.Cu")
		(net 1223)
	)
	(segment
		(start 117.883275 110.348518)
		(end 117.982271 110.249523)
		(width 0.15)
		(layer "In7.Cu")
		(net 1223)
	)
	(segment
		(start 126.4875 81.356956)
		(end 126.6375 81.206956)
		(width 0.15)
		(layer "In7.Cu")
		(net 1223)
	)
	(segment
		(start 126.4375 79.143044)
		(end 125.856956 78.5625)
		(width 0.15)
		(layer "In7.Cu")
		(net 1223)
	)
	(segment
		(start 118.166613 110.833381)
		(end 118.166617 110.833384)
		(width 0.15)
		(layer "In7.Cu")
		(net 1223)
	)
	(segment
		(start 124.8375 78.243044)
		(end 124.8375 77.156956)
		(width 0.15)
		(layer "In7.Cu")
		(net 1223)
	)
	(segment
		(start 126.6375 79.943044)
		(end 126.4375 79.743044)
		(width 0.15)
		(layer "In7.Cu")
		(net 1223)
	)
	(segment
		(start 92.9625 112.756956)
		(end 95.125001 114.919457)
		(width 0.15)
		(layer "In7.Cu")
		(net 1223)
	)
	(segment
		(start 126.9375 86.443044)
		(end 125.9875 85.493044)
		(width 0.15)
		(layer "In7.Cu")
		(net 1223)
	)
	(segment
		(start 92.9625 110.85)
		(end 92.9625 112.756956)
		(width 0.15)
		(layer "In7.Cu")
		(net 1223)
	)
	(segment
		(start 118.665126 110.730853)
		(end 118.856536 110.922264)
		(width 0.15)
		(layer "In7.Cu")
		(net 1223)
	)
	(segment
		(start 116.675 112.519456)
		(end 117.473652 111.720804)
		(width 0.15)
		(layer "In7.Cu")
		(net 1223)
	)
	(segment
		(start 126.5375 89.094763)
		(end 126.525002 89.082265)
		(width 0.15)
		(layer "In7.Cu")
		(net 1223)
	)
	(segment
		(start 92.8125 110.7)
		(end 92.9625 110.85)
		(width 0.15)
		(layer "In7.Cu")
		(net 1223)
	)
	(segment
		(start 132.543044 72.7625)
		(end 131.243044 72.7625)
		(width 0.15)
		(layer "In7.Cu")
		(net 1223)
	)
	(segment
		(start 125.9875 85.493044)
		(end 125.9875 84.556956)
		(width 0.15)
		(layer "In7.Cu")
		(net 1223)
	)
	(segment
		(start 125.856956 78.5625)
		(end 125.156956 78.5625)
		(width 0.15)
		(layer "In7.Cu")
		(net 1223)
	)
	(segment
		(start 118.36991 110.435638)
		(end 118.467137 110.532865)
		(width 0.15)
		(layer "In7.Cu")
		(net 1223)
	)
	(segment
		(start 125.0375 73.956956)
		(end 125.0375 73.043044)
		(width 0.15)
		(layer "In7.Cu")
		(net 1223)
	)
	(segment
		(start 103.66665 118.885)
		(end 113.86665 118.885)
		(width 0.15)
		(layer "In7.Cu")
		(net 1223)
	)
	(segment
		(start 132.7625 72.543044)
		(end 132.543044 72.7625)
		(width 0.15)
		(layer "In7.Cu")
		(net 1223)
	)
	(segment
		(start 124.5375 72.543044)
		(end 124.5375 71.956956)
		(width 0.15)
		(layer "In7.Cu")
		(net 1223)
	)
	(segment
		(start 126.525002 88.019454)
		(end 126.9375 87.606956)
		(width 0.15)
		(layer "In7.Cu")
		(net 1223)
	)
	(segment
		(start 125.1375 76.856956)
		(end 125.1375 75.593044)
		(width 0.15)
		(layer "In7.Cu")
		(net 1223)
	)
	(segment
		(start 119.545966 110.232832)
		(end 119.354555 110.041421)
		(width 0.15)
		(layer "In7.Cu")
		(net 1223)
	)
	(segment
		(start 117.473652 111.720804)
		(end 117.473651 111.720803)
		(width 0.15)
		(layer "In7.Cu")
		(net 1223)
	)
	(segment
		(start 95.125001 118.176651)
		(end 98.123349 121.174999)
		(width 0.15)
		(layer "In7.Cu")
		(net 1223)
	)
	(segment
		(start 116.674999 116.076651)
		(end 116.674998 112.519456)
		(width 0.15)
		(layer "In7.Cu")
		(net 1223)
	)
	(segment
		(start 126.9375 102.256956)
		(end 126.9375 94.743044)
		(width 0.15)
		(layer "In7.Cu")
		(net 1223)
	)
	(segment
		(start 101.376651 121.174999)
		(end 103.66665 118.885)
		(width 0.15)
		(layer "In7.Cu")
		(net 1223)
	)
	(segment
		(start 118.069389 110.736156)
		(end 117.883275 110.550042)
		(width 0.15)
		(layer "In7.Cu")
		(net 1223)
	)
	(segment
		(start 126.5375 94.343044)
		(end 126.5375 89.094763)
		(width 0.15)
		(layer "In7.Cu")
		(net 1223)
	)
	(segment
		(start 130.8375 73.168044)
		(end 130.8375 73.3375)
		(width 0.15)
		(layer "In7.Cu")
		(net 1223)
	)
	(segment
		(start 118.467136 110.532863)
		(end 118.665126 110.730853)
		(width 0.15)
		(layer "In7.Cu")
		(net 1223)
	)
	(arc
		(start 117.473651 111.720803)
		(mid 117.574413 111.679066)
		(end 117.675175 111.720803)
		(width 0.15)
		(layer "In7.Cu")
		(net 1223)
	)
	(arc
		(start 117.982271 110.249523)
		(mid 118.083034 110.207785)
		(end 118.183795 110.249523)
		(width 0.15)
		(layer "In7.Cu")
		(net 1223)
	)
	(arc
		(start 118.556014 111.813218)
		(mid 118.678297 111.518)
		(end 118.556014 111.222782)
		(width 0.15)
		(layer "In7.Cu")
		(net 1223)
	)
	(arc
		(start 119.545966 110.823268)
		(mid 119.668249 110.52805)
		(end 119.545966 110.232832)
		(width 0.15)
		(layer "In7.Cu")
		(net 1223)
	)
	(arc
		(start 119.354555 110.041421)
		(mid 119.312818 109.940659)
		(end 119.354555 109.839897)
		(width 0.15)
		(layer "In7.Cu")
		(net 1223)
	)
	(arc
		(start 118.856536 110.922264)
		(mid 119.151754 111.044547)
		(end 119.446971 110.922264)
		(width 0.15)
		(layer "In7.Cu")
		(net 1223)
	)
	(arc
		(start 117.883275 110.550042)
		(mid 117.841537 110.449281)
		(end 117.883275 110.348518)
		(width 0.15)
		(layer "In7.Cu")
		(net 1223)
	)
	(arc
		(start 117.866585 111.912213)
		(mid 118.161803 112.034496)
		(end 118.45702 111.912213)
		(width 0.15)
		(layer "In7.Cu")
		(net 1223)
	)
	(segment
		(start 189.581 125.491)
		(end 189.49 125.4)
		(width 0.1)
		(layer "F.Cu")
		(net 1232)
	)
	(segment
		(start 189.49 125.4)
		(end 188.476 125.4)
		(width 0.1)
		(layer "F.Cu")
		(net 1232)
	)
	(segment
		(start 189.581 126.613)
		(end 189.581 125.491)
		(width 0.1)
		(layer "F.Cu")
		(net 1232)
	)
	(segment
		(start 196.1 127.1)
		(end 196.4 126.8)
		(width 0.1)
		(layer "F.Cu")
		(net 1233)
	)
	(segment
		(start 198.601 126.899)
		(end 199.565 126.899)
		(width 0.1)
		(layer "F.Cu")
		(net 1233)
	)
	(segment
		(start 195.1 127.9)
		(end 195.2 127.8)
		(width 0.1)
		(layer "F.Cu")
		(net 1233)
	)
	(segment
		(start 195.58 130.3)
		(end 195.5 130.3)
		(width 0.1)
		(layer "F.Cu")
		(net 1233)
	)
	(segment
		(start 195.9 127.8)
		(end 196.1 127.6)
		(width 0.1)
		(layer "F.Cu")
		(net 1233)
	)
	(segment
		(start 198.5 126.8)
		(end 198.6 126.9)
		(width 0.1)
		(layer "F.Cu")
		(net 1233)
	)
	(segment
		(start 198.6 126.9)
		(end 198.601 126.899)
		(width 0.1)
		(layer "F.Cu")
		(net 1233)
	)
	(segment
		(start 196.4 126.8)
		(end 198.5 126.8)
		(width 0.1)
		(layer "F.Cu")
		(net 1233)
	)
	(segment
		(start 195.2 127.8)
		(end 195.9 127.8)
		(width 0.1)
		(layer "F.Cu")
		(net 1233)
	)
	(segment
		(start 196.1 127.6)
		(end 196.1 127.1)
		(width 0.1)
		(layer "F.Cu")
		(net 1233)
	)
	(segment
		(start 195.1 129.9)
		(end 195.1 127.9)
		(width 0.1)
		(layer "F.Cu")
		(net 1233)
	)
	(segment
		(start 195.5 130.3)
		(end 195.1 129.9)
		(width 0.1)
		(layer "F.Cu")
		(net 1233)
	)
	(segment
		(start 197.5 131.3)
		(end 198.301 130.499)
		(width 0.1)
		(layer "F.Cu")
		(net 1234)
	)
	(segment
		(start 195.58 131.3)
		(end 197.5 131.3)
		(width 0.1)
		(layer "F.Cu")
		(net 1234)
	)
	(segment
		(start 198.301 130.499)
		(end 199.565 130.499)
		(width 0.1)
		(layer "F.Cu")
		(net 1234)
	)
	(segment
		(start 98.2 62.8)
		(end 97.998 63.002)
		(width 0.1)
		(layer "F.Cu")
		(net 1235)
	)
	(segment
		(start 98.2 60.775)
		(end 98.2 62.8)
		(width 0.1)
		(layer "F.Cu")
		(net 1235)
	)
	(segment
		(start 97.998 63.002)
		(end 97.55 63.002)
		(width 0.1)
		(layer "F.Cu")
		(net 1235)
	)
	(segment
		(start 216.543 111.989)
		(end 216.543 112.338)
		(width 0.1)
		(layer "B.Cu")
		(net 1236)
	)
	(segment
		(start 216.543 112.338)
		(end 216.02 112.861)
		(width 0.1)
		(layer "B.Cu")
		(net 1236)
	)
	(segment
		(start 216.839 114.261)
		(end 217.07 114.03)
		(width 0.1)
		(layer "B.Cu")
		(net 1237)
	)
	(segment
		(start 216.02 114.261)
		(end 216.839 114.261)
		(width 0.1)
		(layer "B.Cu")
		(net 1237)
	)
	(segment
		(start 222.919 124.561)
		(end 223.08 124.4)
		(width 0.1)
		(layer "B.Cu")
		(net 1238)
	)
	(segment
		(start 221.98 124.601)
		(end 222.02 124.561)
		(width 0.1)
		(layer "B.Cu")
		(net 1238)
	)
	(segment
		(start 222.02 124.561)
		(end 222.919 124.561)
		(width 0.1)
		(layer "B.Cu")
		(net 1238)
	)
	(segment
		(start 222.583 122.558)
		(end 221.98 123.161)
		(width 0.1)
		(layer "B.Cu")
		(net 1239)
	)
	(segment
		(start 222.583 122.419)
		(end 222.583 122.558)
		(width 0.1)
		(layer "B.Cu")
		(net 1239)
	)
	(segment
		(start 221.98 123.161)
		(end 221.98 123.201)
		(width 0.1)
		(layer "B.Cu")
		(net 1239)
	)
	(segment
		(start 219.393 122.679698)
		(end 218.84 123.232698)
		(width 0.1)
		(layer "B.Cu")
		(net 1240)
	)
	(segment
		(start 219.393 122.400698)
		(end 219.393 122.679698)
		(width 0.1)
		(layer "B.Cu")
		(net 1240)
	)
	(segment
		(start 218.84 124.632698)
		(end 219.689 124.632698)
		(width 0.1)
		(layer "B.Cu")
		(net 1241)
	)
	(segment
		(start 219.92 124.401698)
		(end 219.92 124.4)
		(width 0.1)
		(layer "B.Cu")
		(net 1241)
	)
	(segment
		(start 219.689 124.632698)
		(end 219.92 124.401698)
		(width 0.1)
		(layer "B.Cu")
		(net 1241)
	)
	(segment
		(start 94.630532 78.15)
		(end 95.080532 77.7)
		(width 0.1)
		(layer "F.Cu")
		(net 1242)
	)
	(segment
		(start 153.075 104.21)
		(end 154.675 104.21)
		(width 0.1)
		(layer "F.Cu")
		(net 1242)
	)
	(segment
		(start 96.5 77)
		(end 96.85 77)
		(width 0.1)
		(layer "F.Cu")
		(net 1242)
	)
	(segment
		(start 95.080532 77.7)
		(end 95.8 77.7)
		(width 0.1)
		(layer "F.Cu")
		(net 1242)
	)
	(segment
		(start 95.8 77.7)
		(end 96.5 77)
		(width 0.1)
		(layer "F.Cu")
		(net 1242)
	)
	(via
		(at 154.675 104.21)
		(size 0.45)
		(drill 0.1)
		(layers "F.Cu" "B.Cu")
		(net 1242)
	)
	(via
		(at 96.85 77)
		(size 0.45)
		(drill 0.1)
		(layers "F.Cu" "B.Cu")
		(net 1242)
	)
	(segment
		(start 96.625 76.475)
		(end 96.1 75.95)
		(width 0.1)
		(layer "In4.Cu")
		(net 1242)
	)
	(segment
		(start 130.117156 79.367156)
		(end 130.117156 79.8)
		(width 0.1)
		(layer "In4.Cu")
		(net 1242)
	)
	(segment
		(start 130.35 80.032844)
		(end 130.35 82)
		(width 0.1)
		(layer "In4.Cu")
		(net 1242)
	)
	(segment
		(start 101.917159 69.199997)
		(end 108.834315 69.199997)
		(width 0.1)
		(layer "In4.Cu")
		(net 1242)
	)
	(segment
		(start 129.9 79.15)
		(end 130.117156 79.367156)
		(width 0.1)
		(layer "In4.Cu")
		(net 1242)
	)
	(segment
		(start 148.717158 106.2)
		(end 152.685 106.2)
		(width 0.1)
		(layer "In4.Cu")
		(net 1242)
	)
	(segment
		(start 131.9 76.45)
		(end 131.9 77)
		(width 0.1)
		(layer "In4.Cu")
		(net 1242)
	)
	(segment
		(start 132.05 74.8)
		(end 132.05 76.3)
		(width 0.1)
		(layer "In4.Cu")
		(net 1242)
	)
	(segment
		(start 131.9 77)
		(end 131.35 77.55)
		(width 0.1)
		(layer "In4.Cu")
		(net 1242)
	)
	(segment
		(start 100.7 70.95)
		(end 100.7 70.417156)
		(width 0.1)
		(layer "In4.Cu")
		(net 1242)
	)
	(segment
		(start 97.55 73.25)
		(end 97.8 73)
		(width 0.1)
		(layer "In4.Cu")
		(net 1242)
	)
	(segment
		(start 108.925738 69.29142)
		(end 127.7 69.29142)
		(width 0.1)
		(layer "In4.Cu")
		(net 1242)
	)
	(segment
		(start 96.85 77)
		(end 96.625 76.775)
		(width 0.1)
		(layer "In4.Cu")
		(net 1242)
	)
	(segment
		(start 130.117156 87.599998)
		(end 148.717158 106.2)
		(width 0.1)
		(layer "In4.Cu")
		(net 1242)
	)
	(segment
		(start 97.25 73.25)
		(end 97.55 73.25)
		(width 0.1)
		(layer "In4.Cu")
		(net 1242)
	)
	(segment
		(start 130.117156 82.232844)
		(end 130.117156 87.599998)
		(width 0.1)
		(layer "In4.Cu")
		(net 1242)
	)
	(segment
		(start 97.15 74.5)
		(end 97.15 73.35)
		(width 0.1)
		(layer "In4.Cu")
		(net 1242)
	)
	(segment
		(start 96.1 75.95)
		(end 96.1 75.55)
		(width 0.1)
		(layer "In4.Cu")
		(net 1242)
	)
	(segment
		(start 152.685 106.2)
		(end 154.675 104.21)
		(width 0.1)
		(layer "In4.Cu")
		(net 1242)
	)
	(segment
		(start 130.55858 69.15)
		(end 130.55858 71.05858)
		(width 0.1)
		(layer "In4.Cu")
		(net 1242)
	)
	(segment
		(start 100.7 70.417156)
		(end 101.917159 69.199997)
		(width 0.1)
		(layer "In4.Cu")
		(net 1242)
	)
	(segment
		(start 130.55858 71.05858)
		(end 131.25 71.75)
		(width 0.1)
		(layer "In4.Cu")
		(net 1242)
	)
	(segment
		(start 96.1 75.55)
		(end 97.15 74.5)
		(width 0.1)
		(layer "In4.Cu")
		(net 1242)
	)
	(segment
		(start 96.625 76.775)
		(end 96.625 76.475)
		(width 0.1)
		(layer "In4.Cu")
		(net 1242)
	)
	(segment
		(start 97.8 71.95)
		(end 98.2 71.55)
		(width 0.1)
		(layer "In4.Cu")
		(net 1242)
	)
	(segment
		(start 100.1 71.55)
		(end 100.7 70.95)
		(width 0.1)
		(layer "In4.Cu")
		(net 1242)
	)
	(segment
		(start 131.9 74.65)
		(end 132.05 74.8)
		(width 0.1)
		(layer "In4.Cu")
		(net 1242)
	)
	(segment
		(start 108.834315 69.199997)
		(end 108.925738 69.29142)
		(width 0.1)
		(layer "In4.Cu")
		(net 1242)
	)
	(segment
		(start 132.05 76.3)
		(end 131.9 76.45)
		(width 0.1)
		(layer "In4.Cu")
		(net 1242)
	)
	(segment
		(start 128.65 68.34142)
		(end 129.75 68.34142)
		(width 0.1)
		(layer "In4.Cu")
		(net 1242)
	)
	(segment
		(start 130.35 82)
		(end 130.117156 82.232844)
		(width 0.1)
		(layer "In4.Cu")
		(net 1242)
	)
	(segment
		(start 97.15 73.35)
		(end 97.25 73.25)
		(width 0.1)
		(layer "In4.Cu")
		(net 1242)
	)
	(segment
		(start 129.75 68.34142)
		(end 130.55858 69.15)
		(width 0.1)
		(layer "In4.Cu")
		(net 1242)
	)
	(segment
		(start 130.117156 79.8)
		(end 130.35 80.032844)
		(width 0.1)
		(layer "In4.Cu")
		(net 1242)
	)
	(segment
		(start 131.35 77.55)
		(end 130.6 77.55)
		(width 0.1)
		(layer "In4.Cu")
		(net 1242)
	)
	(segment
		(start 131.25 72.8)
		(end 131.9 73.45)
		(width 0.1)
		(layer "In4.Cu")
		(net 1242)
	)
	(segment
		(start 130.6 77.55)
		(end 129.9 78.25)
		(width 0.1)
		(layer "In4.Cu")
		(net 1242)
	)
	(segment
		(start 98.2 71.55)
		(end 100.1 71.55)
		(width 0.1)
		(layer "In4.Cu")
		(net 1242)
	)
	(segment
		(start 97.8 73)
		(end 97.8 71.95)
		(width 0.1)
		(layer "In4.Cu")
		(net 1242)
	)
	(segment
		(start 131.25 71.75)
		(end 131.25 72.8)
		(width 0.1)
		(layer "In4.Cu")
		(net 1242)
	)
	(segment
		(start 131.9 73.45)
		(end 131.9 74.65)
		(width 0.1)
		(layer "In4.Cu")
		(net 1242)
	)
	(segment
		(start 129.9 78.25)
		(end 129.9 79.15)
		(width 0.1)
		(layer "In4.Cu")
		(net 1242)
	)
	(segment
		(start 127.7 69.29142)
		(end 128.65 68.34142)
		(width 0.1)
		(layer "In4.Cu")
		(net 1242)
	)
	(segment
		(start 235.7 106.8)
		(end 236.9 106.8)
		(width 0.1)
		(layer "F.Cu")
		(net 1243)
	)
	(segment
		(start 230.1 107.8)
		(end 230.8 107.8)
		(width 0.1)
		(layer "F.Cu")
		(net 1243)
	)
	(segment
		(start 234.1 106.3)
		(end 234.6 106.8)
		(width 0.1)
		(layer "F.Cu")
		(net 1243)
	)
	(segment
		(start 232.3 106.3)
		(end 234.1 106.3)
		(width 0.1)
		(layer "F.Cu")
		(net 1243)
	)
	(segment
		(start 234.6 106.8)
		(end 235.7 106.8)
		(width 0.1)
		(layer "F.Cu")
		(net 1243)
	)
	(segment
		(start 230.8 107.8)
		(end 232.3 106.3)
		(width 0.1)
		(layer "F.Cu")
		(net 1243)
	)
	(via
		(at 230.1 107.8)
		(size 0.45)
		(drill 0.1)
		(layers "F.Cu" "B.Cu")
		(net 1243)
	)
	(via
		(at 236.9 106.8)
		(size 0.45)
		(drill 0.1)
		(layers "F.Cu" "B.Cu")
		(net 1243)
	)
	(segment
		(start 236.9 106.8)
		(end 236.194 106.8)
		(width 0.1)
		(layer "B.Cu")
		(net 1243)
	)
	(segment
		(start 230.2 107.7)
		(end 230.1 107.8)
		(width 0.1)
		(layer "B.Cu")
		(net 1243)
	)
	(segment
		(start 236.194 106.8)
		(end 236.18 106.814)
		(width 0.1)
		(layer "B.Cu")
		(net 1243)
	)
	(segment
		(start 231.1 107.7)
		(end 230.2 107.7)
		(width 0.1)
		(layer "B.Cu")
		(net 1243)
	)
	(segment
		(start 153.075 103.41)
		(end 154.675 103.41)
		(width 0.1)
		(layer "F.Cu")
		(net 1244)
	)
	(via
		(at 154.675 103.41)
		(size 0.45)
		(drill 0.1)
		(layers "F.Cu" "B.Cu")
		(net 1244)
	)
	(via
		(at 90.830532 73.65)
		(size 0.45)
		(drill 0.1)
		(layers "F.Cu" "B.Cu")
		(net 1244)
	)
	(segment
		(start 95.05 72.85)
		(end 95.75 72.85)
		(width 0.1)
		(layer "In4.Cu")
		(net 1244)
	)
	(segment
		(start 93.725 73.2)
		(end 93.9 73.375)
		(width 0.1)
		(layer "In4.Cu")
		(net 1244)
	)
	(segment
		(start 148.1 105.3)
		(end 152.8 105.3)
		(width 0.1)
		(layer "In4.Cu")
		(net 1244)
	)
	(segment
		(start 152.8 105.3)
		(end 154 104.1)
		(width 0.1)
		(layer "In4.Cu")
		(net 1244)
	)
	(segment
		(start 95.75 72.85)
		(end 96.9 71.7)
		(width 0.1)
		(layer "In4.Cu")
		(net 1244)
	)
	(segment
		(start 154 104.1)
		(end 154 104.085)
		(width 0.1)
		(layer "In4.Cu")
		(net 1244)
	)
	(segment
		(start 132.85 77.1)
		(end 132.05 77.9)
		(width 0.1)
		(layer "In4.Cu")
		(net 1244)
	)
	(segment
		(start 108.767158 68.85)
		(end 108.967158 69.05)
		(width 0.1)
		(layer "In4.Cu")
		(net 1244)
	)
	(segment
		(start 131.05 83.05)
		(end 131.15 83.15)
		(width 0.1)
		(layer "In4.Cu")
		(net 1244)
	)
	(segment
		(start 130.8 69.05)
		(end 130.8 70.75)
		(width 0.1)
		(layer "In4.Cu")
		(net 1244)
	)
	(segment
		(start 100.717158 70.117158)
		(end 101.984316 68.85)
		(width 0.1)
		(layer "In4.Cu")
		(net 1244)
	)
	(segment
		(start 130.8 70.75)
		(end 132.75 72.7)
		(width 0.1)
		(layer "In4.Cu")
		(net 1244)
	)
	(segment
		(start 132.05 77.9)
		(end 132.05 78.4)
		(width 0.1)
		(layer "In4.Cu")
		(net 1244)
	)
	(segment
		(start 101.984316 68.85)
		(end 108.767158 68.85)
		(width 0.1)
		(layer "In4.Cu")
		(net 1244)
	)
	(segment
		(start 98 71.2)
		(end 98.55 71.2)
		(width 0.1)
		(layer "In4.Cu")
		(net 1244)
	)
	(segment
		(start 128.55 68.1)
		(end 129.85 68.1)
		(width 0.1)
		(layer "In4.Cu")
		(net 1244)
	)
	(segment
		(start 98.55 71.2)
		(end 98.85 70.9)
		(width 0.1)
		(layer "In4.Cu")
		(net 1244)
	)
	(segment
		(start 98.85 70.9)
		(end 98.85 70.4)
		(width 0.1)
		(layer "In4.Cu")
		(net 1244)
	)
	(segment
		(start 94.525 73.375)
		(end 95.05 72.85)
		(width 0.1)
		(layer "In4.Cu")
		(net 1244)
	)
	(segment
		(start 93.05 73.825)
		(end 93.05 73.6)
		(width 0.1)
		(layer "In4.Cu")
		(net 1244)
	)
	(segment
		(start 91.230532 74.05)
		(end 92.825 74.05)
		(width 0.1)
		(layer "In4.Cu")
		(net 1244)
	)
	(segment
		(start 132.85 76.25)
		(end 132.85 77.1)
		(width 0.1)
		(layer "In4.Cu")
		(net 1244)
	)
	(segment
		(start 129.85 68.1)
		(end 130.8 69.05)
		(width 0.1)
		(layer "In4.Cu")
		(net 1244)
	)
	(segment
		(start 131.25 81.45)
		(end 131.05 81.65)
		(width 0.1)
		(layer "In4.Cu")
		(net 1244)
	)
	(segment
		(start 92.825 74.05)
		(end 93.05 73.825)
		(width 0.1)
		(layer "In4.Cu")
		(net 1244)
	)
	(segment
		(start 98.85 70.4)
		(end 99.132842 70.117158)
		(width 0.1)
		(layer "In4.Cu")
		(net 1244)
	)
	(segment
		(start 99.132842 70.117158)
		(end 100.717158 70.117158)
		(width 0.1)
		(layer "In4.Cu")
		(net 1244)
	)
	(segment
		(start 133 74.95)
		(end 133 76.1)
		(width 0.1)
		(layer "In4.Cu")
		(net 1244)
	)
	(segment
		(start 127.6 69.05)
		(end 128.55 68.1)
		(width 0.1)
		(layer "In4.Cu")
		(net 1244)
	)
	(segment
		(start 131.05 81.65)
		(end 131.05 83.05)
		(width 0.1)
		(layer "In4.Cu")
		(net 1244)
	)
	(segment
		(start 108.967158 69.05)
		(end 127.6 69.05)
		(width 0.1)
		(layer "In4.Cu")
		(net 1244)
	)
	(segment
		(start 93.9 73.375)
		(end 94.525 73.375)
		(width 0.1)
		(layer "In4.Cu")
		(net 1244)
	)
	(segment
		(start 133 76.1)
		(end 132.85 76.25)
		(width 0.1)
		(layer "In4.Cu")
		(net 1244)
	)
	(segment
		(start 131.95 80.2)
		(end 131.25 80.9)
		(width 0.1)
		(layer "In4.Cu")
		(net 1244)
	)
	(segment
		(start 93.05 73.6)
		(end 93.45 73.2)
		(width 0.1)
		(layer "In4.Cu")
		(net 1244)
	)
	(segment
		(start 132.75 74.7)
		(end 133 74.95)
		(width 0.1)
		(layer "In4.Cu")
		(net 1244)
	)
	(segment
		(start 131.95 78.5)
		(end 131.95 80.2)
		(width 0.1)
		(layer "In4.Cu")
		(net 1244)
	)
	(segment
		(start 93.45 73.2)
		(end 93.725 73.2)
		(width 0.1)
		(layer "In4.Cu")
		(net 1244)
	)
	(segment
		(start 97.5 71.7)
		(end 98 71.2)
		(width 0.1)
		(layer "In4.Cu")
		(net 1244)
	)
	(segment
		(start 131.15 84.95)
		(end 130.425 85.675)
		(width 0.1)
		(layer "In4.Cu")
		(net 1244)
	)
	(segment
		(start 131.15 83.15)
		(end 131.15 84.95)
		(width 0.1)
		(layer "In4.Cu")
		(net 1244)
	)
	(segment
		(start 90.830532 73.65)
		(end 91.230532 74.05)
		(width 0.1)
		(layer "In4.Cu")
		(net 1244)
	)
	(segment
		(start 130.425 87.625)
		(end 148.1 105.3)
		(width 0.1)
		(layer "In4.Cu")
		(net 1244)
	)
	(segment
		(start 96.9 71.7)
		(end 97.5 71.7)
		(width 0.1)
		(layer "In4.Cu")
		(net 1244)
	)
	(segment
		(start 131.25 80.9)
		(end 131.25 81.45)
		(width 0.1)
		(layer "In4.Cu")
		(net 1244)
	)
	(segment
		(start 132.75 72.7)
		(end 132.75 74.7)
		(width 0.1)
		(layer "In4.Cu")
		(net 1244)
	)
	(segment
		(start 154 104.085)
		(end 154.675 103.41)
		(width 0.1)
		(layer "In4.Cu")
		(net 1244)
	)
	(segment
		(start 132.05 78.4)
		(end 131.95 78.5)
		(width 0.1)
		(layer "In4.Cu")
		(net 1244)
	)
	(segment
		(start 130.425 85.675)
		(end 130.425 87.625)
		(width 0.1)
		(layer "In4.Cu")
		(net 1244)
	)
	(segment
		(start 237.72 107.824468)
		(end 236.198468 107.824468)
		(width 0.1)
		(layer "B.Cu")
		(net 1245)
	)
	(segment
		(start 236.198468 107.824468)
		(end 236.174 107.8)
		(width 0.1)
		(layer "B.Cu")
		(net 1245)
	)
	(segment
		(start 237.72 106.8)
		(end 237.72 107.824468)
		(width 0.1)
		(layer "B.Cu")
		(net 1245)
	)
	(segment
		(start 214.046 102.125)
		(end 213.225 102.125)
		(width 0.1)
		(layer "F.Cu")
		(net 1246)
	)
	(segment
		(start 213.225 102.125)
		(end 213.2 102.1)
		(width 0.1)
		(layer "F.Cu")
		(net 1246)
	)
	(via
		(at 213.2 102.1)
		(size 0.45)
		(drill 0.1)
		(layers "F.Cu" "B.Cu")
		(net 1246)
	)
	(segment
		(start 214.02 102.1)
		(end 214.12 102)
		(width 0.1)
		(layer "B.Cu")
		(net 1246)
	)
	(segment
		(start 213.2 102.1)
		(end 214.02 102.1)
		(width 0.1)
		(layer "B.Cu")
		(net 1246)
	)
	(segment
		(start 129.830532 72.15)
		(end 129.825 72.15)
		(width 0.19)
		(layer "F.Cu")
		(net 1247)
	)
	(via
		(at 129.825 72.15)
		(size 0.45)
		(drill 0.1)
		(layers "F.Cu" "B.Cu")
		(net 1247)
	)
	(via
		(at 91.995001 106.65)
		(size 0.45)
		(drill 0.1)
		(layers "F.Cu" "B.Cu")
		(net 1247)
	)
	(segment
		(start 92.180001 104.08)
		(end 92.180001 104.105)
		(width 0.19)
		(layer "B.Cu")
		(net 1247)
	)
	(segment
		(start 91.865001 104.42)
		(end 91.865001 106.52)
		(width 0.19)
		(layer "B.Cu")
		(net 1247)
	)
	(segment
		(start 91.865001 106.52)
		(end 91.995001 106.65)
		(width 0.19)
		(layer "B.Cu")
		(net 1247)
	)
	(segment
		(start 92.180001 104.105)
		(end 91.865001 104.42)
		(width 0.19)
		(layer "B.Cu")
		(net 1247)
	)
	(segment
		(start 130.1625 86.143044)
		(end 130.1625 85.256956)
		(width 0.15)
		(layer "In7.Cu")
		(net 1247)
	)
	(segment
		(start 91.5375 112.243044)
		(end 94.647501 115.353045)
		(width 0.15)
		(layer "In7.Cu")
		(net 1247)
	)
	(segment
		(start 124.309749 111.864545)
		(end 123.776 111.864545)
		(width 0.15)
		(layer "In7.Cu")
		(net 1247)
	)
	(segment
		(start 118.943151 116.161682)
		(end 119.418509 116.637039)
		(width 0.15)
		(layer "In7.Cu")
		(net 1247)
	)
	(segment
		(start 119.308403 118.282681)
		(end 119.405983 118.1851)
		(width 0.15)
		(layer "In7.Cu")
		(net 1247)
	)
	(segment
		(start 119.515737 116.734267)
		(end 119.515734 116.734265)
		(width 0.15)
		(layer "In7.Cu")
		(net 1247)
	)
	(segment
		(start 129.57 72.7625)
		(end 129.843044 72.7625)
		(width 0.15)
		(layer "In7.Cu")
		(net 1247)
	)
	(segment
		(start 120.381791 117.013426)
		(end 120.004343 116.635977)
		(width 0.15)
		(layer "In7.Cu")
		(net 1247)
	)
	(segment
		(start 124.448248 112.141044)
		(end 124.448248 112.003044)
		(width 0.15)
		(layer "In7.Cu")
		(net 1247)
	)
	(segment
		(start 125.240272 105.165272)
		(end 127.3625 103.043044)
		(width 0.15)
		(layer "In7.Cu")
		(net 1247)
	)
	(segment
		(start 123.3625 107.043044)
		(end 124.065272 106.340272)
		(width 0.15)
		(layer "In7.Cu")
		(net 1247)
	)
	(segment
		(start 119.028535 117.611784)
		(end 118.833373 117.416623)
		(width 0.15)
		(layer "In7.Cu")
		(net 1247)
	)
	(segment
		(start 129.843044 72.7625)
		(end 130.1375 72.468044)
		(width 0.15)
		(layer "In7.Cu")
		(net 1247)
	)
	(segment
		(start 118.735088 117.905233)
		(end 119.112535 118.282681)
		(width 0.15)
		(layer "In7.Cu")
		(net 1247)
	)
	(segment
		(start 91.995001 106.65)
		(end 91.817501 106.8275)
		(width 0.15)
		(layer "In7.Cu")
		(net 1247)
	)
	(segment
		(start 118.260791 116.259262)
		(end 118.358373 116.161681)
		(width 0.15)
		(layer "In7.Cu")
		(net 1247)
	)
	(segment
		(start 127.3625 103.043044)
		(end 127.3625 88.943044)
		(width 0.15)
		(layer "In7.Cu")
		(net 1247)
	)
	(segment
		(start 128.44 72.4125)
		(end 128.52 72.4125)
		(width 0.15)
		(layer "In7.Cu")
		(net 1247)
	)
	(segment
		(start 126.1625 73.143044)
		(end 126.543044 72.7625)
		(width 0.15)
		(layer "In7.Cu")
		(net 1247)
	)
	(segment
		(start 127.5625 76.556956)
		(end 126.5625 75.556956)
		(width 0.15)
		(layer "In7.Cu")
		(net 1247)
	)
	(segment
		(start 91.817501 106.8275)
		(end 91.817501 107.976955)
		(width 0.15)
		(layer "In7.Cu")
		(net 1247)
	)
	(segment
		(start 123.362499 111.864545)
		(end 122.690241 111.864545)
		(width 0.15)
		(layer "In7.Cu")
		(net 1247)
	)
	(segment
		(start 128.84 72.7625)
		(end 128.92 72.7625)
		(width 0.15)
		(layer "In7.Cu")
		(net 1247)
	)
	(segment
		(start 127.1625 79.256956)
		(end 127.1625 78.043044)
		(width 0.15)
		(layer "In7.Cu")
		(net 1247)
	)
	(segment
		(start 126.5625 74.356956)
		(end 126.1625 73.956956)
		(width 0.15)
		(layer "In7.Cu")
		(net 1247)
	)
	(segment
		(start 129.17 72.5125)
		(end 129.32 72.5125)
		(width 0.15)
		(layer "In7.Cu")
		(net 1247)
	)
	(segment
		(start 123.637501 110.484545)
		(end 123.362499 110.484545)
		(width 0.15)
		(layer "In7.Cu")
		(net 1247)
	)
	(segment
		(start 129.896901 72.221901)
		(end 129.825 72.15)
		(width 0.15)
		(layer "In7.Cu")
		(net 1247)
	)
	(segment
		(start 127.1625 82.256956)
		(end 127.1625 80.443044)
		(width 0.15)
		(layer "In7.Cu")
		(net 1247)
	)
	(segment
		(start 124.448248 110.761044)
		(end 124.448248 110.623044)
		(width 0.15)
		(layer "In7.Cu")
		(net 1247)
	)
	(segment
		(start 127.5625 79.656956)
		(end 127.1625 79.256956)
		(width 0.15)
		(layer "In7.Cu")
		(net 1247)
	)
	(segment
		(start 122.27674 110.071044)
		(end 122.27674 109.933044)
		(width 0.15)
		(layer "In7.Cu")
		(net 1247)
	)
	(segment
		(start 119.405983 117.989233)
		(end 119.028535 117.611784)
		(width 0.15)
		(layer "In7.Cu")
		(net 1247)
	)
	(segment
		(start 127.5625 80.043044)
		(end 127.5625 79.656956)
		(width 0.15)
		(layer "In7.Cu")
		(net 1247)
	)
	(segment
		(start 94.647501 118.374437)
		(end 97.925563 121.652499)
		(width 0.15)
		(layer "In7.Cu")
		(net 1247)
	)
	(segment
		(start 118.833373 117.416623)
		(end 118.833375 117.416623)
		(width 0.15)
		(layer "In7.Cu")
		(net 1247)
	)
	(segment
		(start 130.1625 85.256956)
		(end 127.1625 82.256956)
		(width 0.15)
		(layer "In7.Cu")
		(net 1247)
	)
	(segment
		(start 130.1375 72.4625)
		(end 129.896901 72.221901)
		(width 0.15)
		(layer "In7.Cu")
		(net 1247)
	)
	(segment
		(start 124.448248 109.381044)
		(end 124.448248 109.243044)
		(width 0.15)
		(layer "In7.Cu")
		(net 1247)
	)
	(segment
		(start 124.309749 110.484545)
		(end 123.637501 110.484545)
		(width 0.15)
		(layer "In7.Cu")
		(net 1247)
	)
	(segment
		(start 120.101925 115.953619)
		(end 121.320994 114.734549)
		(width 0.15)
		(layer "In7.Cu")
		(net 1247)
	)
	(segment
		(start 97.925563 121.652499)
		(end 101.574437 121.652499)
		(width 0.15)
		(layer "In7.Cu")
		(net 1247)
	)
	(segment
		(start 130.1375 72.468044)
		(end 130.1375 72.4625)
		(width 0.15)
		(layer "In7.Cu")
		(net 1247)
	)
	(segment
		(start 103.864436 119.3625)
		(end 114.706956 119.3625)
		(width 0.15)
		(layer "In7.Cu")
		(net 1247)
	)
	(segment
		(start 123.776 111.864545)
		(end 123.362499 111.864545)
		(width 0.15)
		(layer "In7.Cu")
		(net 1247)
	)
	(segment
		(start 127.1625 80.443044)
		(end 127.5625 80.043044)
		(width 0.15)
		(layer "In7.Cu")
		(net 1247)
	)
	(segment
		(start 123.3625 112.693044)
		(end 123.362499 112.693044)
		(width 0.15)
		(layer "In7.Cu")
		(net 1247)
	)
	(segment
		(start 123.362499 108.001044)
		(end 123.362499 107.863044)
		(width 0.15)
		(layer "In7.Cu")
		(net 1247)
	)
	(segment
		(start 126.1625 73.956956)
		(end 126.1625 73.143044)
		(width 0.15)
		(layer "In7.Cu")
		(net 1247)
	)
	(segment
		(start 123.362499 109.519543)
		(end 123.637501 109.519543)
		(width 0.15)
		(layer "In7.Cu")
		(net 1247)
	)
	(segment
		(start 123.637501 110.899543)
		(end 124.309749 110.899543)
		(width 0.15)
		(layer "In7.Cu")
		(net 1247)
	)
	(segment
		(start 101.574437 121.652499)
		(end 103.864436 119.3625)
		(width 0.15)
		(layer "In7.Cu")
		(net 1247)
	)
	(segment
		(start 122.690241 109.519543)
		(end 123.362499 109.519543)
		(width 0.15)
		(layer "In7.Cu")
		(net 1247)
	)
	(segment
		(start 119.515734 116.734265)
		(end 119.710896 116.929426)
		(width 0.15)
		(layer "In7.Cu")
		(net 1247)
	)
	(segment
		(start 115.156956 119.8125)
		(end 116.243044 119.8125)
		(width 0.15)
		(layer "In7.Cu")
		(net 1247)
	)
	(segment
		(start 123.362499 110.899543)
		(end 123.637501 110.899543)
		(width 0.15)
		(layer "In7.Cu")
		(net 1247)
	)
	(segment
		(start 127.5625 77.643044)
		(end 127.5625 76.556956)
		(width 0.15)
		(layer "In7.Cu")
		(net 1247)
	)
	(segment
		(start 117.877772 118.177772)
		(end 118.15031 117.905233)
		(width 0.15)
		(layer "In7.Cu")
		(net 1247)
	)
	(segment
		(start 122.690241 108.139543)
		(end 123.224 108.139543)
		(width 0.15)
		(layer "In7.Cu")
		(net 1247)
	)
	(segment
		(start 91.5375 108.256956)
		(end 91.5375 112.243044)
		(width 0.15)
		(layer "In7.Cu")
		(net 1247)
	)
	(segment
		(start 128.68 72.5725)
		(end 128.68 72.6025)
		(width 0.15)
		(layer "In7.Cu")
		(net 1247)
	)
	(segment
		(start 116.243044 119.8125)
		(end 117.877772 118.177772)
		(width 0.15)
		(layer "In7.Cu")
		(net 1247)
	)
	(segment
		(start 128.28 72.6025)
		(end 128.28 72.5725)
		(width 0.15)
		(layer "In7.Cu")
		(net 1247)
	)
	(segment
		(start 123.362499 110.484545)
		(end 122.690241 110.484545)
		(width 0.15)
		(layer "In7.Cu")
		(net 1247)
	)
	(segment
		(start 122.27674 108.691044)
		(end 122.27674 108.553044)
		(width 0.15)
		(layer "In7.Cu")
		(net 1247)
	)
	(segment
		(start 123.362499 107.863044)
		(end 123.3625 107.043044)
		(width 0.15)
		(layer "In7.Cu")
		(net 1247)
	)
	(segment
		(start 123.637501 109.519543)
		(end 124.309749 109.519543)
		(width 0.15)
		(layer "In7.Cu")
		(net 1247)
	)
	(segment
		(start 91.817501 107.976955)
		(end 91.5375 108.256956)
		(width 0.15)
		(layer "In7.Cu")
		(net 1247)
	)
	(segment
		(start 94.647501 115.353045)
		(end 94.647501 118.374437)
		(width 0.15)
		(layer "In7.Cu")
		(net 1247)
	)
	(segment
		(start 119.710896 116.929426)
		(end 120.088344 117.306874)
		(width 0.15)
		(layer "In7.Cu")
		(net 1247)
	)
	(segment
		(start 127.3625 88.943044)
		(end 130.1625 86.143044)
		(width 0.15)
		(layer "In7.Cu")
		(net 1247)
	)
	(segment
		(start 124.065272 106.340272)
		(end 124.690272 105.715272)
		(width 0.15)
		(layer "In7.Cu")
		(net 1247)
	)
	(segment
		(start 122.690241 110.899543)
		(end 123.362499 110.899543)
		(width 0.15)
		(layer "In7.Cu")
		(net 1247)
	)
	(segment
		(start 123.224 109.104545)
		(end 122.690241 109.104545)
		(width 0.15)
		(layer "In7.Cu")
		(net 1247)
	)
	(segment
		(start 114.706956 119.3625)
		(end 115.156956 119.8125)
		(width 0.15)
		(layer "In7.Cu")
		(net 1247)
	)
	(segment
		(start 121.320994 114.734549)
		(end 123.3625 112.693044)
		(width 0.15)
		(layer "In7.Cu")
		(net 1247)
	)
	(segment
		(start 120.284211 117.306874)
		(end 120.381791 117.209293)
		(width 0.15)
		(layer "In7.Cu")
		(net 1247)
	)
	(segment
		(start 126.5625 75.556956)
		(end 126.5625 74.356956)
		(width 0.15)
		(layer "In7.Cu")
		(net 1247)
	)
	(segment
		(start 120.004343 116.051199)
		(end 120.101925 115.953619)
		(width 0.15)
		(layer "In7.Cu")
		(net 1247)
	)
	(segment
		(start 124.690272 105.715272)
		(end 124.690272 105.409728)
		(width 0.15)
		(layer "In7.Cu")
		(net 1247)
	)
	(segment
		(start 123.637501 109.104545)
		(end 123.224 109.104545)
		(width 0.15)
		(layer "In7.Cu")
		(net 1247)
	)
	(segment
		(start 124.690272 105.409728)
		(end 124.934728 105.165272)
		(width 0.15)
		(layer "In7.Cu")
		(net 1247)
	)
	(segment
		(start 124.934728 105.165272)
		(end 125.240272 105.165272)
		(width 0.15)
		(layer "In7.Cu")
		(net 1247)
	)
	(segment
		(start 126.543044 72.7625)
		(end 128.12 72.7625)
		(width 0.15)
		(layer "In7.Cu")
		(net 1247)
	)
	(segment
		(start 119.418509 116.637039)
		(end 119.515737 116.734267)
		(width 0.15)
		(layer "In7.Cu")
		(net 1247)
	)
	(segment
		(start 118.833375 117.416623)
		(end 118.736148 117.319397)
		(width 0.15)
		(layer "In7.Cu")
		(net 1247)
	)
	(segment
		(start 127.1625 78.043044)
		(end 127.5625 77.643044)
		(width 0.15)
		(layer "In7.Cu")
		(net 1247)
	)
	(segment
		(start 124.309749 109.104545)
		(end 123.637501 109.104545)
		(width 0.15)
		(layer "In7.Cu")
		(net 1247)
	)
	(segment
		(start 122.27674 111.451044)
		(end 122.27674 111.313044)
		(width 0.15)
		(layer "In7.Cu")
		(net 1247)
	)
	(segment
		(start 123.776 112.279543)
		(end 124.309749 112.279543)
		(width 0.15)
		(layer "In7.Cu")
		(net 1247)
	)
	(segment
		(start 118.736148 117.319397)
		(end 118.260792 116.844041)
		(width 0.15)
		(layer "In7.Cu")
		(net 1247)
	)
	(arc
		(start 122.27674 111.313044)
		(mid 122.397852 111.020655)
		(end 122.690241 110.899543)
		(width 0.15)
		(layer "In7.Cu")
		(net 1247)
	)
	(arc
		(start 128.92 72.7625)
		(mid 129.008388 72.725888)
		(end 129.045 72.6375)
		(width 0.15)
		(layer "In7.Cu")
		(net 1247)
	)
	(arc
		(start 124.309749 109.519543)
		(mid 124.407683 109.478978)
		(end 124.448248 109.381044)
		(width 0.15)
		(layer "In7.Cu")
		(net 1247)
	)
	(arc
		(start 128.28 72.5725)
		(mid 128.326863 72.459363)
		(end 128.44 72.4125)
		(width 0.15)
		(layer "In7.Cu")
		(net 1247)
	)
	(arc
		(start 123.224 108.139543)
		(mid 123.321934 108.098978)
		(end 123.362499 108.001044)
		(width 0.15)
		(layer "In7.Cu")
		(net 1247)
	)
	(arc
		(start 122.27674 108.553044)
		(mid 122.397852 108.260655)
		(end 122.690241 108.139543)
		(width 0.15)
		(layer "In7.Cu")
		(net 1247)
	)
	(arc
		(start 124.448248 112.003044)
		(mid 124.407683 111.90511)
		(end 124.309749 111.864545)
		(width 0.15)
		(layer "In7.Cu")
		(net 1247)
	)
	(arc
		(start 123.362499 112.693044)
		(mid 123.483611 112.400655)
		(end 123.776 112.279543)
		(width 0.15)
		(layer "In7.Cu")
		(net 1247)
	)
	(arc
		(start 118.358373 116.161681)
		(mid 118.650763 116.040569)
		(end 118.943151 116.161682)
		(width 0.15)
		(layer "In7.Cu")
		(net 1247)
	)
	(arc
		(start 129.445 72.6375)
		(mid 129.481612 72.725888)
		(end 129.57 72.7625)
		(width 0.15)
		(layer "In7.Cu")
		(net 1247)
	)
	(arc
		(start 122.690241 111.864545)
		(mid 122.397852 111.743433)
		(end 122.27674 111.451044)
		(width 0.15)
		(layer "In7.Cu")
		(net 1247)
	)
	(arc
		(start 119.405983 118.1851)
		(mid 119.446549 118.087166)
		(end 119.405983 117.989233)
		(width 0.15)
		(layer "In7.Cu")
		(net 1247)
	)
	(arc
		(start 124.448248 110.623044)
		(mid 124.407683 110.52511)
		(end 124.309749 110.484545)
		(width 0.15)
		(layer "In7.Cu")
		(net 1247)
	)
	(arc
		(start 122.690241 110.484545)
		(mid 122.397852 110.363433)
		(end 122.27674 110.071044)
		(width 0.15)
		(layer "In7.Cu")
		(net 1247)
	)
	(arc
		(start 129.32 72.5125)
		(mid 129.408388 72.549112)
		(end 129.445 72.6375)
		(width 0.15)
		(layer "In7.Cu")
		(net 1247)
	)
	(arc
		(start 118.15031 117.905233)
		(mid 118.442699 117.784122)
		(end 118.735088 117.905233)
		(width 0.15)
		(layer "In7.Cu")
		(net 1247)
	)
	(arc
		(start 128.68 72.6025)
		(mid 128.726863 72.715637)
		(end 128.84 72.7625)
		(width 0.15)
		(layer "In7.Cu")
		(net 1247)
	)
	(arc
		(start 120.088344 117.306874)
		(mid 120.186278 117.347439)
		(end 120.284211 117.306874)
		(width 0.15)
		(layer "In7.Cu")
		(net 1247)
	)
	(arc
		(start 128.12 72.7625)
		(mid 128.233137 72.715637)
		(end 128.28 72.6025)
		(width 0.15)
		(layer "In7.Cu")
		(net 1247)
	)
	(arc
		(start 124.448248 109.243044)
		(mid 124.407683 109.14511)
		(end 124.309749 109.104545)
		(width 0.15)
		(layer "In7.Cu")
		(net 1247)
	)
	(arc
		(start 124.309749 112.279543)
		(mid 124.407683 112.238978)
		(end 124.448248 112.141044)
		(width 0.15)
		(layer "In7.Cu")
		(net 1247)
	)
	(arc
		(start 129.045 72.6375)
		(mid 129.081612 72.549112)
		(end 129.17 72.5125)
		(width 0.15)
		(layer "In7.Cu")
		(net 1247)
	)
	(arc
		(start 119.112535 118.282681)
		(mid 119.210469 118.323247)
		(end 119.308403 118.282681)
		(width 0.15)
		(layer "In7.Cu")
		(net 1247)
	)
	(arc
		(start 122.690241 109.104545)
		(mid 122.397852 108.983433)
		(end 122.27674 108.691044)
		(width 0.15)
		(layer "In7.Cu")
		(net 1247)
	)
	(arc
		(start 120.381791 117.209293)
		(mid 120.422357 117.111359)
		(end 120.381791 117.013426)
		(width 0.15)
		(layer "In7.Cu")
		(net 1247)
	)
	(arc
		(start 128.52 72.4125)
		(mid 128.633137 72.459363)
		(end 128.68 72.5725)
		(width 0.15)
		(layer "In7.Cu")
		(net 1247)
	)
	(arc
		(start 122.27674 109.933044)
		(mid 122.397852 109.640655)
		(end 122.690241 109.519543)
		(width 0.15)
		(layer "In7.Cu")
		(net 1247)
	)
	(arc
		(start 124.309749 110.899543)
		(mid 124.407683 110.858978)
		(end 124.448248 110.761044)
		(width 0.15)
		(layer "In7.Cu")
		(net 1247)
	)
	(arc
		(start 120.004343 116.635977)
		(mid 119.883232 116.343588)
		(end 120.004343 116.051199)
		(width 0.15)
		(layer "In7.Cu")
		(net 1247)
	)
	(arc
		(start 118.260792 116.844041)
		(mid 118.139681 116.551651)
		(end 118.260791 116.259262)
		(width 0.15)
		(layer "In7.Cu")
		(net 1247)
	)
	(segment
		(start 131.630532 75.15)
		(end 131.625 75.15)
		(width 0.19)
		(layer "F.Cu")
		(net 1248)
	)
	(via
		(at 92.865002 107.6)
		(size 0.45)
		(drill 0.1)
		(layers "F.Cu" "B.Cu")
		(net 1248)
	)
	(via
		(at 131.625 75.15)
		(size 0.45)
		(drill 0.1)
		(layers "F.Cu" "B.Cu")
		(net 1248)
	)
	(segment
		(start 92.680003 105.98)
		(end 92.680003 106.005)
		(width 0.19)
		(layer "B.Cu")
		(net 1248)
	)
	(segment
		(start 92.680003 106.005)
		(end 92.995002 106.319999)
		(width 0.19)
		(layer "B.Cu")
		(net 1248)
	)
	(segment
		(start 92.995002 106.319999)
		(end 92.995002 107.47)
		(width 0.19)
		(layer "B.Cu")
		(net 1248)
	)
	(segment
		(start 92.995002 107.47)
		(end 92.865002 107.6)
		(width 0.19)
		(layer "B.Cu")
		(net 1248)
	)
	(segment
		(start 93.856956 106.6625)
		(end 95.6375 108.443044)
		(width 0.15)
		(layer "In7.Cu")
		(net 1248)
	)
	(segment
		(start 113.2375 116.8625)
		(end 114.1125 115.9875)
		(width 0.15)
		(layer "In7.Cu")
		(net 1248)
	)
	(segment
		(start 135.374999 72.013909)
		(end 134.574999 72.813909)
		(width 0.15)
		(layer "In7.Cu")
		(net 1248)
	)
	(segment
		(start 132.293044 76.0375)
		(end 131.9375 75.681956)
		(width 0.15)
		(layer "In7.Cu")
		(net 1248)
	)
	(segment
		(start 121.9625 70.043044)
		(end 123.743044 68.2625)
		(width 0.15)
		(layer "In7.Cu")
		(net 1248)
	)
	(segment
		(start 134.256956 68.2625)
		(end 135.374999 69.380543)
		(width 0.15)
		(layer "In7.Cu")
		(net 1248)
	)
	(segment
		(start 123.743044 68.2625)
		(end 134.256956 68.2625)
		(width 0.15)
		(layer "In7.Cu")
		(net 1248)
	)
	(segment
		(start 121.2625 71.643044)
		(end 121.9625 70.943044)
		(width 0.15)
		(layer "In7.Cu")
		(net 1248)
	)
	(segment
		(start 123.9625 80.456956)
		(end 122.8625 79.356956)
		(width 0.15)
		(layer "In7.Cu")
		(net 1248)
	)
	(segment
		(start 121.2625 72.456956)
		(end 121.2625 71.643044)
		(width 0.15)
		(layer "In7.Cu")
		(net 1248)
	)
	(segment
		(start 97 117.4)
		(end 98.9 119.3)
		(width 0.15)
		(layer "In7.Cu")
		(net 1248)
	)
	(segment
		(start 124.650003 88.594459)
		(end 122.8625 86.806956)
		(width 0.15)
		(layer "In7.Cu")
		(net 1248)
	)
	(segment
		(start 100.6 119.3)
		(end 103.4375 116.4625)
		(width 0.15)
		(layer "In7.Cu")
		(net 1248)
	)
	(segment
		(start 134.574999 73.886091)
		(end 134.774999 74.086091)
		(width 0.15)
		(layer "In7.Cu")
		(net 1248)
	)
	(segment
		(start 122.110832 102.244711)
		(end 124.650003 99.705541)
		(width 0.15)
		(layer "In7.Cu")
		(net 1248)
	)
	(segment
		(start 134.774999 75.313909)
		(end 134.051408 76.0375)
		(width 0.15)
		(layer "In7.Cu")
		(net 1248)
	)
	(segment
		(start 93.443044 106.6625)
		(end 93.856956 106.6625)
		(width 0.15)
		(layer "In7.Cu")
		(net 1248)
	)
	(segment
		(start 122.0625 74.206956)
		(end 122.0625 73.256956)
		(width 0.15)
		(layer "In7.Cu")
		(net 1248)
	)
	(segment
		(start 131.9375 75.4625)
		(end 131.625 75.15)
		(width 0.15)
		(layer "In7.Cu")
		(net 1248)
	)
	(segment
		(start 122.8625 86.806956)
		(end 122.8625 82.393044)
		(width 0.15)
		(layer "In7.Cu")
		(net 1248)
	)
	(segment
		(start 103.4375 116.4625)
		(end 104.356956 116.4625)
		(width 0.15)
		(layer "In7.Cu")
		(net 1248)
	)
	(segment
		(start 134.574999 72.813909)
		(end 134.574999 73.886091)
		(width 0.15)
		(layer "In7.Cu")
		(net 1248)
	)
	(segment
		(start 95.6375 108.443044)
		(end 95.6375 111.143044)
		(width 0.15)
		(layer "In7.Cu")
		(net 1248)
	)
	(segment
		(start 93.042502 107.063042)
		(end 93.443044 106.6625)
		(width 0.15)
		(layer "In7.Cu")
		(net 1248)
	)
	(segment
		(start 122.8625 79.356956)
		(end 122.8625 75.006956)
		(width 0.15)
		(layer "In7.Cu")
		(net 1248)
	)
	(segment
		(start 93.042502 107.4225)
		(end 93.042502 107.063042)
		(width 0.15)
		(layer "In7.Cu")
		(net 1248)
	)
	(segment
		(start 135.374999 69.380543)
		(end 135.374999 72.013909)
		(width 0.15)
		(layer "In7.Cu")
		(net 1248)
	)
	(segment
		(start 122.0625 73.256956)
		(end 121.2625 72.456956)
		(width 0.15)
		(layer "In7.Cu")
		(net 1248)
	)
	(segment
		(start 92.865002 107.6)
		(end 93.042502 107.4225)
		(width 0.15)
		(layer "In7.Cu")
		(net 1248)
	)
	(segment
		(start 131.9375 75.681956)
		(end 131.9375 75.4625)
		(width 0.15)
		(layer "In7.Cu")
		(net 1248)
	)
	(segment
		(start 98.9 119.3)
		(end 100.6 119.3)
		(width 0.15)
		(layer "In7.Cu")
		(net 1248)
	)
	(segment
		(start 121.9625 70.943044)
		(end 121.9625 70.043044)
		(width 0.15)
		(layer "In7.Cu")
		(net 1248)
	)
	(segment
		(start 122.8625 75.006956)
		(end 122.0625 74.206956)
		(width 0.15)
		(layer "In7.Cu")
		(net 1248)
	)
	(segment
		(start 95.6375 111.143044)
		(end 97 112.505544)
		(width 0.15)
		(layer "In7.Cu")
		(net 1248)
	)
	(segment
		(start 134.051408 76.0375)
		(end 132.293044 76.0375)
		(width 0.15)
		(layer "In7.Cu")
		(net 1248)
	)
	(segment
		(start 123.9625 81.293044)
		(end 123.9625 80.456956)
		(width 0.15)
		(layer "In7.Cu")
		(net 1248)
	)
	(segment
		(start 114.1125 110.243044)
		(end 122.110832 102.244711)
		(width 0.15)
		(layer "In7.Cu")
		(net 1248)
	)
	(segment
		(start 122.8625 82.393044)
		(end 123.9625 81.293044)
		(width 0.15)
		(layer "In7.Cu")
		(net 1248)
	)
	(segment
		(start 134.774999 74.086091)
		(end 134.774999 75.313909)
		(width 0.15)
		(layer "In7.Cu")
		(net 1248)
	)
	(segment
		(start 97 112.505544)
		(end 97 117.4)
		(width 0.15)
		(layer "In7.Cu")
		(net 1248)
	)
	(segment
		(start 114.1125 115.9875)
		(end 114.1125 110.243044)
		(width 0.15)
		(layer "In7.Cu")
		(net 1248)
	)
	(segment
		(start 104.356956 116.4625)
		(end 104.756956 116.8625)
		(width 0.15)
		(layer "In7.Cu")
		(net 1248)
	)
	(segment
		(start 124.650003 99.705541)
		(end 124.650003 88.594459)
		(width 0.15)
		(layer "In7.Cu")
		(net 1248)
	)
	(segment
		(start 104.756956 116.8625)
		(end 113.2375 116.8625)
		(width 0.15)
		(layer "In7.Cu")
		(net 1248)
	)
	(segment
		(start 133.230532 76.65)
		(end 133.225 76.65)
		(width 0.19)
		(layer "F.Cu")
		(net 1249)
	)
	(via
		(at 93.3 108.5125)
		(size 0.45)
		(drill 0.1)
		(layers "F.Cu" "B.Cu")
		(net 1249)
	)
	(via
		(at 133.225 76.65)
		(size 0.45)
		(drill 0.1)
		(layers "F.Cu" "B.Cu")
		(net 1249)
	)
	(segment
		(start 93.3 108.5125)
		(end 93.4025 108.615)
		(width 0.19)
		(layer "B.Cu")
		(net 1249)
	)
	(segment
		(start 91.62337 110.085)
		(end 90.105001 108.566631)
		(width 0.19)
		(layer "B.Cu")
		(net 1249)
	)
	(segment
		(start 90.105001 108.566631)
		(end 90.105001 106.285001)
		(width 0.19)
		(layer "B.Cu")
		(net 1249)
	)
	(segment
		(start 94.185 109.02337)
		(end 94.185 109.67663)
		(width 0.19)
		(layer "B.Cu")
		(net 1249)
	)
	(segment
		(start 90.105001 106.285001)
		(end 89.8 105.98)
		(width 0.19)
		(layer "B.Cu")
		(net 1249)
	)
	(segment
		(start 93.77663 110.085)
		(end 91.62337 110.085)
		(width 0.19)
		(layer "B.Cu")
		(net 1249)
	)
	(segment
		(start 93.4025 108.615)
		(end 93.77663 108.615)
		(width 0.19)
		(layer "B.Cu")
		(net 1249)
	)
	(segment
		(start 93.77663 108.615)
		(end 94.185 109.02337)
		(width 0.19)
		(layer "B.Cu")
		(net 1249)
	)
	(segment
		(start 94.185 109.67663)
		(end 93.77663 110.085)
		(width 0.19)
		(layer "B.Cu")
		(net 1249)
	)
	(segment
		(start 130.1125 75.481956)
		(end 130.1125 74.906956)
		(width 0.15)
		(layer "In7.Cu")
		(net 1249)
	)
	(segment
		(start 103.217228 117.8)
		(end 100.927229 120.089999)
		(width 0.15)
		(layer "In7.Cu")
		(net 1249)
	)
	(segment
		(start 96.210001 117.727229)
		(end 96.210001 114.315545)
		(width 0.15)
		(layer "In7.Cu")
		(net 1249)
	)
	(segment
		(start 124.6125 87.256956)
		(end 125.440003 88.084459)
		(width 0.15)
		(layer "In7.Cu")
		(net 1249)
	)
	(segment
		(start 124.6125 85.843044)
		(end 124.6125 87.256956)
		(width 0.15)
		(layer "In7.Cu")
		(net 1249)
	)
	(segment
		(start 122.8125 73.306956)
		(end 123.9625 74.456956)
		(width 0.15)
		(layer "In7.Cu")
		(net 1249)
	)
	(segment
		(start 129.1625 76.431956)
		(end 130.1125 75.481956)
		(width 0.15)
		(layer "In7.Cu")
		(net 1249)
	)
	(segment
		(start 133.5375 76.9625)
		(end 133.225 76.65)
		(width 0.15)
		(layer "In7.Cu")
		(net 1249)
	)
	(segment
		(start 115.1125 116.104728)
		(end 113.417228 117.8)
		(width 0.15)
		(layer "In7.Cu")
		(net 1249)
	)
	(segment
		(start 133.218044 77.4125)
		(end 133.5375 77.093044)
		(width 0.15)
		(layer "In7.Cu")
		(net 1249)
	)
	(segment
		(start 132.881956 74.5375)
		(end 133.8875 73.531956)
		(width 0.15)
		(layer "In7.Cu")
		(net 1249)
	)
	(segment
		(start 123.968044 69.6625)
		(end 122.8125 70.818044)
		(width 0.15)
		(layer "In7.Cu")
		(net 1249)
	)
	(segment
		(start 130.481956 74.5375)
		(end 132.881956 74.5375)
		(width 0.15)
		(layer "In7.Cu")
		(net 1249)
	)
	(segment
		(start 124.8125 85.106956)
		(end 124.8125 85.643044)
		(width 0.15)
		(layer "In7.Cu")
		(net 1249)
	)
	(segment
		(start 124.5125 81.406956)
		(end 124.7625 81.656956)
		(width 0.15)
		(layer "In7.Cu")
		(net 1249)
	)
	(segment
		(start 130.1125 74.906956)
		(end 130.481956 74.5375)
		(width 0.15)
		(layer "In7.Cu")
		(net 1249)
	)
	(segment
		(start 133.5375 77.093044)
		(end 133.5375 76.9625)
		(width 0.15)
		(layer "In7.Cu")
		(net 1249)
	)
	(segment
		(start 124.8125 85.643044)
		(end 124.6125 85.843044)
		(width 0.15)
		(layer "In7.Cu")
		(net 1249)
	)
	(segment
		(start 93.756956 108.6625)
		(end 93.45 108.6625)
		(width 0.15)
		(layer "In7.Cu")
		(net 1249)
	)
	(segment
		(start 100.927229 120.089999)
		(end 98.572771 120.089999)
		(width 0.15)
		(layer "In7.Cu")
		(net 1249)
	)
	(segment
		(start 130.924049 77.008558)
		(end 131.120107 77.008558)
		(width 0.15)
		(layer "In7.Cu")
		(net 1249)
	)
	(segment
		(start 130.520107 77.4125)
		(end 129.481956 77.4125)
		(width 0.15)
		(layer "In7.Cu")
		(net 1249)
	)
	(segment
		(start 125.440003 101.215541)
		(end 115.1125 111.543044)
		(width 0.15)
		(layer "In7.Cu")
		(net 1249)
	)
	(segment
		(start 96.210001 114.315545)
		(end 94.3375 112.443044)
		(width 0.15)
		(layer "In7.Cu")
		(net 1249)
	)
	(segment
		(start 115.1125 111.543044)
		(end 115.1125 116.104728)
		(width 0.15)
		(layer "In7.Cu")
		(net 1249)
	)
	(segment
		(start 93.45 108.6625)
		(end 93.3 108.5125)
		(width 0.15)
		(layer "In7.Cu")
		(net 1249)
	)
	(segment
		(start 124.6625 79.456956)
		(end 124.6625 79.993044)
		(width 0.15)
		(layer "In7.Cu")
		(net 1249)
	)
	(segment
		(start 123.9625 77.406956)
		(end 123.9625 78.756956)
		(width 0.15)
		(layer "In7.Cu")
		(net 1249)
	)
	(segment
		(start 124.5125 80.143044)
		(end 124.5125 81.406956)
		(width 0.15)
		(layer "In7.Cu")
		(net 1249)
	)
	(segment
		(start 94.7375 109.643044)
		(end 93.756956 108.6625)
		(width 0.15)
		(layer "In7.Cu")
		(net 1249)
	)
	(segment
		(start 125.440003 88.084459)
		(end 125.440003 101.215541)
		(width 0.15)
		(layer "In7.Cu")
		(net 1249)
	)
	(segment
		(start 129.481956 77.4125)
		(end 129.1625 77.093044)
		(width 0.15)
		(layer "In7.Cu")
		(net 1249)
	)
	(segment
		(start 124.4125 83.093044)
		(end 124.4125 84.706956)
		(width 0.15)
		(layer "In7.Cu")
		(net 1249)
	)
	(segment
		(start 131.524049 77.4125)
		(end 133.218044 77.4125)
		(width 0.15)
		(layer "In7.Cu")
		(net 1249)
	)
	(segment
		(start 122.8125 70.818044)
		(end 122.8125 73.306956)
		(width 0.15)
		(layer "In7.Cu")
		(net 1249)
	)
	(segment
		(start 133.356956 69.6625)
		(end 123.968044 69.6625)
		(width 0.15)
		(layer "In7.Cu")
		(net 1249)
	)
	(segment
		(start 133.8875 73.531956)
		(end 133.8875 70.193044)
		(width 0.15)
		(layer "In7.Cu")
		(net 1249)
	)
	(segment
		(start 123.9625 75.743044)
		(end 123.5625 76.143044)
		(width 0.15)
		(layer "In7.Cu")
		(net 1249)
	)
	(segment
		(start 124.4125 84.706956)
		(end 124.8125 85.106956)
		(width 0.15)
		(layer "In7.Cu")
		(net 1249)
	)
	(segment
		(start 133.8875 70.193044)
		(end 133.356956 69.6625)
		(width 0.15)
		(layer "In7.Cu")
		(net 1249)
	)
	(segment
		(start 129.1625 77.093044)
		(end 129.1625 76.431956)
		(width 0.15)
		(layer "In7.Cu")
		(net 1249)
	)
	(segment
		(start 94.3375 112.443044)
		(end 94.3375 111.456956)
		(width 0.15)
		(layer "In7.Cu")
		(net 1249)
	)
	(segment
		(start 123.9625 74.456956)
		(end 123.9625 75.743044)
		(width 0.15)
		(layer "In7.Cu")
		(net 1249)
	)
	(segment
		(start 124.7625 82.743044)
		(end 124.4125 83.093044)
		(width 0.15)
		(layer "In7.Cu")
		(net 1249)
	)
	(segment
		(start 123.5625 77.006956)
		(end 123.9625 77.406956)
		(width 0.15)
		(layer "In7.Cu")
		(net 1249)
	)
	(segment
		(start 123.9625 78.756956)
		(end 124.6625 79.456956)
		(width 0.15)
		(layer "In7.Cu")
		(net 1249)
	)
	(segment
		(start 98.572771 120.089999)
		(end 96.210001 117.727229)
		(width 0.15)
		(layer "In7.Cu")
		(net 1249)
	)
	(segment
		(start 124.6625 79.993044)
		(end 124.5125 80.143044)
		(width 0.15)
		(layer "In7.Cu")
		(net 1249)
	)
	(segment
		(start 124.7625 81.656956)
		(end 124.7625 82.743044)
		(width 0.15)
		(layer "In7.Cu")
		(net 1249)
	)
	(segment
		(start 123.5625 76.143044)
		(end 123.5625 77.006956)
		(width 0.15)
		(layer "In7.Cu")
		(net 1249)
	)
	(segment
		(start 113.417228 117.8)
		(end 103.217228 117.8)
		(width 0.15)
		(layer "In7.Cu")
		(net 1249)
	)
	(segment
		(start 94.3375 111.456956)
		(end 94.7375 111.056956)
		(width 0.15)
		(layer "In7.Cu")
		(net 1249)
	)
	(segment
		(start 94.7375 111.056956)
		(end 94.7375 109.643044)
		(width 0.15)
		(layer "In7.Cu")
		(net 1249)
	)
	(arc
		(start 131.322078 77.210529)
		(mid 131.381234 77.353344)
		(end 131.524049 77.4125)
		(width 0.15)
		(layer "In7.Cu")
		(net 1249)
	)
	(arc
		(start 130.520107 77.4125)
		(mid 130.662922 77.353344)
		(end 130.722078 77.210529)
		(width 0.15)
		(layer "In7.Cu")
		(net 1249)
	)
	(arc
		(start 130.722078 77.210529)
		(mid 130.781234 77.067714)
		(end 130.924049 77.008558)
		(width 0.15)
		(layer "In7.Cu")
		(net 1249)
	)
	(arc
		(start 131.120107 77.008558)
		(mid 131.262922 77.067714)
		(end 131.322078 77.210529)
		(width 0.15)
		(layer "In7.Cu")
		(net 1249)
	)
	(segment
		(start 131.430532 73.65)
		(end 131.425 73.65)
		(width 0.19)
		(layer "F.Cu")
		(net 1250)
	)
	(via
		(at 131.425 73.65)
		(size 0.45)
		(drill 0.1)
		(layers "F.Cu" "B.Cu")
		(net 1250)
	)
	(via
		(at 93.3875 110.7)
		(size 0.45)
		(drill 0.1)
		(layers "F.Cu" "B.Cu")
		(net 1250)
	)
	(segment
		(start 94.180001 104.08)
		(end 94.180001 104.105)
		(width 0.19)
		(layer "B.Cu")
		(net 1250)
	)
	(segment
		(start 94.915 109.265926)
		(end 94.915 109.523115)
		(width 0.19)
		(layer "B.Cu")
		(net 1250)
	)
	(segment
		(start 93.285 110.8025)
		(end 93.3875 110.7)
		(width 0.19)
		(layer "B.Cu")
		(net 1250)
	)
	(segment
		(start 94.915 110.62337)
		(end 94.12337 111.415)
		(width 0.19)
		(layer "B.Cu")
		(net 1250)
	)
	(segment
		(start 94.495001 104.42)
		(end 94.495001 107.356631)
		(width 0.19)
		(layer "B.Cu")
		(net 1250)
	)
	(segment
		(start 93.47663 111.415)
		(end 93.285 111.22337)
		(width 0.19)
		(layer "B.Cu")
		(net 1250)
	)
	(segment
		(start 94.915 109.523115)
		(end 94.915 110.62337)
		(width 0.19)
		(layer "B.Cu")
		(net 1250)
	)
	(segment
		(start 94.695 108.385926)
		(end 94.635 108.385926)
		(width 0.19)
		(layer "B.Cu")
		(net 1250)
	)
	(segment
		(start 94.180001 104.105)
		(end 94.495001 104.42)
		(width 0.19)
		(layer "B.Cu")
		(net 1250)
	)
	(segment
		(start 94.495001 107.356631)
		(end 94.915 107.77663)
		(width 0.19)
		(layer "B.Cu")
		(net 1250)
	)
	(segment
		(start 94.915 107.77663)
		(end 94.915 108.165926)
		(width 0.19)
		(layer "B.Cu")
		(net 1250)
	)
	(segment
		(start 94.415 108.605926)
		(end 94.415 108.715926)
		(width 0.19)
		(layer "B.Cu")
		(net 1250)
	)
	(segment
		(start 94.915 109.155926)
		(end 94.915 109.265926)
		(width 0.19)
		(layer "B.Cu")
		(net 1250)
	)
	(segment
		(start 93.285 111.22337)
		(end 93.285 110.8025)
		(width 0.19)
		(layer "B.Cu")
		(net 1250)
	)
	(segment
		(start 94.635 108.935926)
		(end 94.695 108.935926)
		(width 0.19)
		(layer "B.Cu")
		(net 1250)
	)
	(segment
		(start 94.12337 111.415)
		(end 93.47663 111.415)
		(width 0.19)
		(layer "B.Cu")
		(net 1250)
	)
	(arc
		(start 94.915 108.165926)
		(mid 94.850563 108.321489)
		(end 94.695 108.385926)
		(width 0.19)
		(layer "B.Cu")
		(net 1250)
	)
	(arc
		(start 94.415 108.715926)
		(mid 94.479437 108.871489)
		(end 94.635 108.935926)
		(width 0.19)
		(layer "B.Cu")
		(net 1250)
	)
	(arc
		(start 94.635 108.385926)
		(mid 94.479437 108.450363)
		(end 94.415 108.605926)
		(width 0.19)
		(layer "B.Cu")
		(net 1250)
	)
	(arc
		(start 94.695 108.935926)
		(mid 94.850563 109.000363)
		(end 94.915 109.155926)
		(width 0.19)
		(layer "B.Cu")
		(net 1250)
	)
	(segment
		(start 93.3875 110.7)
		(end 93.2375 110.85)
		(width 0.15)
		(layer "In7.Cu")
		(net 1250)
	)
	(segment
		(start 117.874932 110.930613)
		(end 117.688818 110.744499)
		(width 0.15)
		(layer "In7.Cu")
		(net 1250)
	)
	(segment
		(start 126.2125 81.243044)
		(end 126.3625 81.093044)
		(width 0.15)
		(layer "In7.Cu")
		(net 1250)
	)
	(segment
		(start 131.1125 73.281956)
		(end 131.1125 73.3375)
		(width 0.15)
		(layer "In7.Cu")
		(net 1250)
	)
	(segment
		(start 126.2625 94.456956)
		(end 126.2625 89.2)
		(width 0.15)
		(layer "In7.Cu")
		(net 1250)
	)
	(segment
		(start 126.25 89.1875)
		(end 126.25 87.905544)
		(width 0.15)
		(layer "In7.Cu")
		(net 1250)
	)
	(segment
		(start 109.633983 118.609999)
		(end 109.933983 118.609999)
		(width 0.15)
		(layer "In7.Cu")
		(net 1250)
	)
	(segment
		(start 118.859581 110.536398)
		(end 119.050992 110.727808)
		(width 0.15)
		(layer "In7.Cu")
		(net 1250)
	)
	(segment
		(start 133.0375 72.656956)
		(end 132.656956 73.0375)
		(width 0.15)
		(layer "In7.Cu")
		(net 1250)
	)
	(segment
		(start 126.4625 83.693044)
		(end 126.4625 83.206956)
		(width 0.15)
		(layer "In7.Cu")
		(net 1250)
	)
	(segment
		(start 124.8625 75.706956)
		(end 124.6125 75.456956)
		(width 0.15)
		(layer "In7.Cu")
		(net 1250)
	)
	(segment
		(start 95.400003 114.805547)
		(end 95.400003 118.062741)
		(width 0.15)
		(layer "In7.Cu")
		(net 1250)
	)
	(segment
		(start 124.7625 73.843044)
		(end 124.7625 73.156956)
		(width 0.15)
		(layer "In7.Cu")
		(net 1250)
	)
	(segment
		(start 132.656956 73.0375)
		(end 131.356956 73.0375)
		(width 0.15)
		(layer "In7.Cu")
		(net 1250)
	)
	(segment
		(start 113.752739 118.609999)
		(end 116.399997 115.962741)
		(width 0.15)
		(layer "In7.Cu")
		(net 1250)
	)
	(segment
		(start 124.8625 76.743044)
		(end 124.8625 75.706956)
		(width 0.15)
		(layer "In7.Cu")
		(net 1250)
	)
	(segment
		(start 117.869631 111.526348)
		(end 118.061041 111.717758)
		(width 0.15)
		(layer "In7.Cu")
		(net 1250)
	)
	(segment
		(start 93.2375 112.643044)
		(end 95.400003 114.805547)
		(width 0.15)
		(layer "In7.Cu")
		(net 1250)
	)
	(segment
		(start 124.5625 78.356956)
		(end 124.5625 77.043044)
		(width 0.15)
		(layer "In7.Cu")
		(net 1250)
	)
	(segment
		(start 126.3625 81.093044)
		(end 126.3625 80.056956)
		(width 0.15)
		(layer "In7.Cu")
		(net 1250)
	)
	(segment
		(start 110.183983 118.359999)
		(end 110.483983 118.359999)
		(width 0.15)
		(layer "In7.Cu")
		(net 1250)
	)
	(segment
		(start 125.7125 84.443044)
		(end 126.4625 83.693044)
		(width 0.15)
		(layer "In7.Cu")
		(net 1250)
	)
	(segment
		(start 111.033983 118.609999)
		(end 111.327368 118.609999)
		(width 0.15)
		(layer "In7.Cu")
		(net 1250)
	)
	(segment
		(start 124.6125 73.993044)
		(end 124.7625 73.843044)
		(width 0.15)
		(layer "In7.Cu")
		(net 1250)
	)
	(segment
		(start 125.043044 78.8375)
		(end 124.5625 78.356956)
		(width 0.15)
		(layer "In7.Cu")
		(net 1250)
	)
	(segment
		(start 111.327368 118.609999)
		(end 113.752739 118.609999)
		(width 0.15)
		(layer "In7.Cu")
		(net 1250)
	)
	(segment
		(start 93.2375 110.85)
		(end 93.2375 112.643044)
		(width 0.15)
		(layer "In7.Cu")
		(net 1250)
	)
	(segment
		(start 124.5625 77.043044)
		(end 124.8625 76.743044)
		(width 0.15)
		(layer "In7.Cu")
		(net 1250)
	)
	(segment
		(start 124.2625 71.843044)
		(end 124.943044 71.1625)
		(width 0.15)
		(layer "In7.Cu")
		(net 1250)
	)
	(segment
		(start 123.007353 105.798191)
		(end 126.6625 102.143044)
		(width 0.15)
		(layer "In7.Cu")
		(net 1250)
	)
	(segment
		(start 132.256956 71.1625)
		(end 133.0375 71.943044)
		(width 0.15)
		(layer "In7.Cu")
		(net 1250)
	)
	(segment
		(start 117.972158 111.027838)
		(end 117.97216 111.027841)
		(width 0.15)
		(layer "In7.Cu")
		(net 1250)
	)
	(segment
		(start 126.1625 79.856956)
		(end 126.1625 79.256956)
		(width 0.15)
		(layer "In7.Cu")
		(net 1250)
	)
	(segment
		(start 119.351511 110.427288)
		(end 119.1601 110.235877)
		(width 0.15)
		(layer "In7.Cu")
		(net 1250)
	)
	(segment
		(start 117.688819 110.154063)
		(end 117.787817 110.055066)
		(width 0.15)
		(layer "In7.Cu")
		(net 1250)
	)
	(segment
		(start 119.1601 109.645442)
		(end 119.259096 109.546447)
		(width 0.15)
		(layer "In7.Cu")
		(net 1250)
	)
	(segment
		(start 118.564366 110.241182)
		(end 118.661593 110.338409)
		(width 0.15)
		(layer "In7.Cu")
		(net 1250)
	)
	(segment
		(start 118.661593 110.338409)
		(end 118.661591 110.338408)
		(width 0.15)
		(layer "In7.Cu")
		(net 1250)
	)
	(segment
		(start 118.170148 111.225828)
		(end 117.972158 111.027838)
		(width 0.15)
		(layer "In7.Cu")
		(net 1250)
	)
	(segment
		(start 133.0375 71.943044)
		(end 133.0375 72.656956)
		(width 0.15)
		(layer "In7.Cu")
		(net 1250)
	)
	(segment
		(start 110.733983 118.609999)
		(end 111.033983 118.609999)
		(width 0.15)
		(layer "In7.Cu")
		(net 1250)
	)
	(segment
		(start 118.262565 111.717758)
		(end 118.361559 111.618763)
		(width 0.15)
		(layer "In7.Cu")
		(net 1250)
	)
	(segment
		(start 126.25 87.905544)
		(end 126.6625 87.493044)
		(width 0.15)
		(layer "In7.Cu")
		(net 1250)
	)
	(segment
		(start 126.6625 102.143044)
		(end 126.6625 94.856956)
		(width 0.15)
		(layer "In7.Cu")
		(net 1250)
	)
	(segment
		(start 126.3625 80.056956)
		(end 126.1625 79.856956)
		(width 0.15)
		(layer "In7.Cu")
		(net 1250)
	)
	(segment
		(start 126.2625 89.2)
		(end 126.25 89.1875)
		(width 0.15)
		(layer "In7.Cu")
		(net 1250)
	)
	(segment
		(start 126.1625 79.256956)
		(end 125.743044 78.8375)
		(width 0.15)
		(layer "In7.Cu")
		(net 1250)
	)
	(segment
		(start 101.262741 120.899997)
		(end 103.552739 118.609999)
		(width 0.15)
		(layer "In7.Cu")
		(net 1250)
	)
	(segment
		(start 124.943044 71.1625)
		(end 132.256956 71.1625)
		(width 0.15)
		(layer "In7.Cu")
		(net 1250)
	)
	(segment
		(start 125.743044 78.8375)
		(end 125.043044 78.8375)
		(width 0.15)
		(layer "In7.Cu")
		(net 1250)
	)
	(segment
		(start 119.259096 109.546447)
		(end 123.007353 105.798191)
		(width 0.15)
		(layer "In7.Cu")
		(net 1250)
	)
	(segment
		(start 118.378251 110.055067)
		(end 118.564366 110.241182)
		(width 0.15)
		(layer "In7.Cu")
		(net 1250)
	)
	(segment
		(start 126.4625 83.206956)
		(end 126.2125 82.956956)
		(width 0.15)
		(layer "In7.Cu")
		(net 1250)
	)
	(segment
		(start 124.7625 73.156956)
		(end 124.2625 72.656956)
		(width 0.15)
		(layer "In7.Cu")
		(net 1250)
	)
	(segment
		(start 98.237259 120.899997)
		(end 101.262741 120.899997)
		(width 0.15)
		(layer "In7.Cu")
		(net 1250)
	)
	(segment
		(start 125.7125 85.606956)
		(end 125.7125 84.443044)
		(width 0.15)
		(layer "In7.Cu")
		(net 1250)
	)
	(segment
		(start 116.399997 112.405547)
		(end 117.279196 111.526348)
		(width 0.15)
		(layer "In7.Cu")
		(net 1250)
	)
	(segment
		(start 116.399997 115.962741)
		(end 116.399997 112.405547)
		(width 0.15)
		(layer "In7.Cu")
		(net 1250)
	)
	(segment
		(start 126.6625 87.493044)
		(end 126.6625 86.556956)
		(width 0.15)
		(layer "In7.Cu")
		(net 1250)
	)
	(segment
		(start 103.552739 118.609999)
		(end 108.833983 118.609999)
		(width 0.15)
		(layer "In7.Cu")
		(net 1250)
	)
	(segment
		(start 131.356956 73.0375)
		(end 131.1125 73.281956)
		(width 0.15)
		(layer "In7.Cu")
		(net 1250)
	)
	(segment
		(start 126.6625 86.556956)
		(end 125.7125 85.606956)
		(width 0.15)
		(layer "In7.Cu")
		(net 1250)
	)
	(segment
		(start 119.252516 110.727808)
		(end 119.351511 110.628812)
		(width 0.15)
		(layer "In7.Cu")
		(net 1250)
	)
	(segment
		(start 118.361559 111.417239)
		(end 118.170148 111.225828)
		(width 0.15)
		(layer "In7.Cu")
		(net 1250)
	)
	(segment
		(start 126.2125 82.956956)
		(end 126.2125 81.243044)
		(width 0.15)
		(layer "In7.Cu")
		(net 1250)
	)
	(segment
		(start 117.97216 111.027841)
		(end 117.874932 110.930613)
		(width 0.15)
		(layer "In7.Cu")
		(net 1250)
	)
	(segment
		(start 131.1125 73.3375)
		(end 131.425 73.65)
		(width 0.15)
		(layer "In7.Cu")
		(net 1250)
	)
	(segment
		(start 124.6125 75.456956)
		(end 124.6125 73.993044)
		(width 0.15)
		(layer "In7.Cu")
		(net 1250)
	)
	(segment
		(start 126.6625 94.856956)
		(end 126.2625 94.456956)
		(width 0.15)
		(layer "In7.Cu")
		(net 1250)
	)
	(segment
		(start 118.661591 110.338408)
		(end 118.859581 110.536398)
		(width 0.15)
		(layer "In7.Cu")
		(net 1250)
	)
	(segment
		(start 109.083983 118.359999)
		(end 109.383983 118.359999)
		(width 0.15)
		(layer "In7.Cu")
		(net 1250)
	)
	(segment
		(start 95.400003 118.062741)
		(end 98.237259 120.899997)
		(width 0.15)
		(layer "In7.Cu")
		(net 1250)
	)
	(segment
		(start 124.2625 72.656956)
		(end 124.2625 71.843044)
		(width 0.15)
		(layer "In7.Cu")
		(net 1250)
	)
	(arc
		(start 110.608983 118.484999)
		(mid 110.645595 118.573387)
		(end 110.733983 118.609999)
		(width 0.15)
		(layer "In7.Cu")
		(net 1250)
	)
	(arc
		(start 110.058983 118.484999)
		(mid 110.095595 118.396611)
		(end 110.183983 118.359999)
		(width 0.15)
		(layer "In7.Cu")
		(net 1250)
	)
	(arc
		(start 108.833983 118.609999)
		(mid 108.922371 118.573387)
		(end 108.958983 118.484999)
		(width 0.15)
		(layer "In7.Cu")
		(net 1250)
	)
	(arc
		(start 117.787817 110.055066)
		(mid 118.083034 109.932784)
		(end 118.378251 110.055067)
		(width 0.15)
		(layer "In7.Cu")
		(net 1250)
	)
	(arc
		(start 109.933983 118.609999)
		(mid 110.022371 118.573387)
		(end 110.058983 118.484999)
		(width 0.15)
		(layer "In7.Cu")
		(net 1250)
	)
	(arc
		(start 109.508983 118.484999)
		(mid 109.545595 118.573387)
		(end 109.633983 118.609999)
		(width 0.15)
		(layer "In7.Cu")
		(net 1250)
	)
	(arc
		(start 109.383983 118.359999)
		(mid 109.472371 118.396611)
		(end 109.508983 118.484999)
		(width 0.15)
		(layer "In7.Cu")
		(net 1250)
	)
	(arc
		(start 119.1601 110.235877)
		(mid 119.037816 109.94066)
		(end 119.1601 109.645442)
		(width 0.15)
		(layer "In7.Cu")
		(net 1250)
	)
	(arc
		(start 108.958983 118.484999)
		(mid 108.995595 118.396611)
		(end 109.083983 118.359999)
		(width 0.15)
		(layer "In7.Cu")
		(net 1250)
	)
	(arc
		(start 110.483983 118.359999)
		(mid 110.572371 118.396611)
		(end 110.608983 118.484999)
		(width 0.15)
		(layer "In7.Cu")
		(net 1250)
	)
	(arc
		(start 117.279196 111.526348)
		(mid 117.574413 111.404065)
		(end 117.869631 111.526348)
		(width 0.15)
		(layer "In7.Cu")
		(net 1250)
	)
	(arc
		(start 119.050992 110.727808)
		(mid 119.151754 110.769545)
		(end 119.252516 110.727808)
		(width 0.15)
		(layer "In7.Cu")
		(net 1250)
	)
	(arc
		(start 119.351511 110.628812)
		(mid 119.393248 110.52805)
		(end 119.351511 110.427288)
		(width 0.15)
		(layer "In7.Cu")
		(net 1250)
	)
	(arc
		(start 118.061041 111.717758)
		(mid 118.161803 111.759495)
		(end 118.262565 111.717758)
		(width 0.15)
		(layer "In7.Cu")
		(net 1250)
	)
	(arc
		(start 117.688818 110.744499)
		(mid 117.566536 110.44928)
		(end 117.688819 110.154063)
		(width 0.15)
		(layer "In7.Cu")
		(net 1250)
	)
	(arc
		(start 118.361559 111.618763)
		(mid 118.403296 111.518001)
		(end 118.361559 111.417239)
		(width 0.15)
		(layer "In7.Cu")
		(net 1250)
	)
	(segment
		(start 130.730532 72.15)
		(end 130.725 72.15)
		(width 0.19)
		(layer "F.Cu")
		(net 1251)
	)
	(via
		(at 130.725 72.15)
		(size 0.45)
		(drill 0.1)
		(layers "F.Cu" "B.Cu")
		(net 1251)
	)
	(via
		(at 91.365001 106.65)
		(size 0.45)
		(drill 0.1)
		(layers "F.Cu" "B.Cu")
		(net 1251)
	)
	(segment
		(start 91.180001 104.08)
		(end 91.180001 104.105)
		(width 0.19)
		(layer "B.Cu")
		(net 1251)
	)
	(segment
		(start 91.495001 104.42)
		(end 91.495001 106.52)
		(width 0.19)
		(layer "B.Cu")
		(net 1251)
	)
	(segment
		(start 91.495001 106.52)
		(end 91.365001 106.65)
		(width 0.19)
		(layer "B.Cu")
		(net 1251)
	)
	(segment
		(start 91.180001 104.105)
		(end 91.495001 104.42)
		(width 0.19)
		(layer "B.Cu")
		(net 1251)
	)
	(segment
		(start 126.8375 74.243044)
		(end 126.4375 73.843044)
		(width 0.15)
		(layer "In7.Cu")
		(net 1251)
	)
	(segment
		(start 122.551742 108.691044)
		(end 122.551742 108.553044)
		(width 0.15)
		(layer "In7.Cu")
		(net 1251)
	)
	(segment
		(start 123.776 111.589543)
		(end 123.362499 111.589543)
		(width 0.15)
		(layer "In7.Cu")
		(net 1251)
	)
	(segment
		(start 123.362499 109.794545)
		(end 123.637501 109.794545)
		(width 0.15)
		(layer "In7.Cu")
		(net 1251)
	)
	(segment
		(start 119.502859 118.477136)
		(end 119.600439 118.379555)
		(width 0.15)
		(layer "In7.Cu")
		(net 1251)
	)
	(segment
		(start 119.321281 116.928723)
		(end 119.321279 116.92872)
		(width 0.15)
		(layer "In7.Cu")
		(net 1251)
	)
	(segment
		(start 91.2625 112.356956)
		(end 94.372502 115.466958)
		(width 0.15)
		(layer "In7.Cu")
		(net 1251)
	)
	(segment
		(start 127.4375 79.143044)
		(end 127.4375 78.156956)
		(width 0.15)
		(layer "In7.Cu")
		(net 1251)
	)
	(segment
		(start 126.4375 73.843044)
		(end 126.4375 73.256956)
		(width 0.15)
		(layer "In7.Cu")
		(net 1251)
	)
	(segment
		(start 97.811654 121.927498)
		(end 101.688346 121.927498)
		(width 0.15)
		(layer "In7.Cu")
		(net 1251)
	)
	(segment
		(start 124.72325 109.381044)
		(end 124.72325 109.243044)
		(width 0.15)
		(layer "In7.Cu")
		(net 1251)
	)
	(segment
		(start 118.748695 116.356138)
		(end 119.224053 116.831495)
		(width 0.15)
		(layer "In7.Cu")
		(net 1251)
	)
	(segment
		(start 91.365001 106.65)
		(end 91.542501 106.8275)
		(width 0.15)
		(layer "In7.Cu")
		(net 1251)
	)
	(segment
		(start 130.4125 72.581956)
		(end 130.4125 72.4625)
		(width 0.15)
		(layer "In7.Cu")
		(net 1251)
	)
	(segment
		(start 127.4375 82.143044)
		(end 127.4375 80.556956)
		(width 0.15)
		(layer "In7.Cu")
		(net 1251)
	)
	(segment
		(start 119.027829 117.222166)
		(end 119.027832 117.22217)
		(width 0.15)
		(layer "In7.Cu")
		(net 1251)
	)
	(segment
		(start 123.776 112.554545)
		(end 124.309749 112.554545)
		(width 0.15)
		(layer "In7.Cu")
		(net 1251)
	)
	(segment
		(start 118.930604 117.124942)
		(end 118.455248 116.649584)
		(width 0.15)
		(layer "In7.Cu")
		(net 1251)
	)
	(segment
		(start 123.637501 108.001044)
		(end 123.637501 107.863044)
		(width 0.15)
		(layer "In7.Cu")
		(net 1251)
	)
	(segment
		(start 119.600439 117.794776)
		(end 119.222991 117.417327)
		(width 0.15)
		(layer "In7.Cu")
		(net 1251)
	)
	(segment
		(start 123.637501 110.209543)
		(end 123.362499 110.209543)
		(width 0.15)
		(layer "In7.Cu")
		(net 1251)
	)
	(segment
		(start 119.51644 117.123882)
		(end 119.893888 117.50133)
		(width 0.15)
		(layer "In7.Cu")
		(net 1251)
	)
	(segment
		(start 127.8375 80.156956)
		(end 127.8375 79.543044)
		(width 0.15)
		(layer "In7.Cu")
		(net 1251)
	)
	(segment
		(start 116.356956 120.0875)
		(end 118.072228 118.372228)
		(width 0.15)
		(layer "In7.Cu")
		(net 1251)
	)
	(segment
		(start 119.222991 117.417327)
		(end 119.027829 117.222166)
		(width 0.15)
		(layer "In7.Cu")
		(net 1251)
	)
	(segment
		(start 119.321279 116.92872)
		(end 119.51644 117.123882)
		(width 0.15)
		(layer "In7.Cu")
		(net 1251)
	)
	(segment
		(start 123.362499 111.174545)
		(end 123.637501 111.174545)
		(width 0.15)
		(layer "In7.Cu")
		(net 1251)
	)
	(segment
		(start 127.8375 79.543044)
		(end 127.4375 79.143044)
		(width 0.15)
		(layer "In7.Cu")
		(net 1251)
	)
	(segment
		(start 119.224053 116.831495)
		(end 119.321281 116.928723)
		(width 0.15)
		(layer "In7.Cu")
		(net 1251)
	)
	(segment
		(start 120.478667 117.50133)
		(end 120.576247 117.403749)
		(width 0.15)
		(layer "In7.Cu")
		(net 1251)
	)
	(segment
		(start 118.072228 118.372228)
		(end 118.344766 118.099689)
		(width 0.15)
		(layer "In7.Cu")
		(net 1251)
	)
	(segment
		(start 123.637501 109.794545)
		(end 124.309749 109.794545)
		(width 0.15)
		(layer "In7.Cu")
		(net 1251)
	)
	(segment
		(start 126.8375 75.443044)
		(end 126.8375 74.243044)
		(width 0.15)
		(layer "In7.Cu")
		(net 1251)
	)
	(segment
		(start 127.4375 80.556956)
		(end 127.8375 80.156956)
		(width 0.15)
		(layer "In7.Cu")
		(net 1251)
	)
	(segment
		(start 122.690241 108.414545)
		(end 123.224 108.414545)
		(width 0.15)
		(layer "In7.Cu")
		(net 1251)
	)
	(segment
		(start 118.540633 118.099688)
		(end 118.91808 118.477136)
		(width 0.15)
		(layer "In7.Cu")
		(net 1251)
	)
	(segment
		(start 91.2625 108.143044)
		(end 91.2625 112.356956)
		(width 0.15)
		(layer "In7.Cu")
		(net 1251)
	)
	(segment
		(start 115.043044 120.0875)
		(end 116.356956 120.0875)
		(width 0.15)
		(layer "In7.Cu")
		(net 1251)
	)
	(segment
		(start 119.027832 117.22217)
		(end 118.930604 117.124942)
		(width 0.15)
		(layer "In7.Cu")
		(net 1251)
	)
	(segment
		(start 129.956956 73.0375)
		(end 130.4125 72.581956)
		(width 0.15)
		(layer "In7.Cu")
		(net 1251)
	)
	(segment
		(start 123.6375 107.156956)
		(end 124.259728 106.534728)
		(width 0.15)
		(layer "In7.Cu")
		(net 1251)
	)
	(segment
		(start 122.551742 111.451044)
		(end 122.551742 111.313044)
		(width 0.15)
		(layer "In7.Cu")
		(net 1251)
	)
	(segment
		(start 130.4375 85.143044)
		(end 127.4375 82.143044)
		(width 0.15)
		(layer "In7.Cu")
		(net 1251)
	)
	(segment
		(start 122.690241 109.794545)
		(end 123.362499 109.794545)
		(width 0.15)
		(layer "In7.Cu")
		(net 1251)
	)
	(segment
		(start 123.362499 111.589543)
		(end 122.690241 111.589543)
		(width 0.15)
		(layer "In7.Cu")
		(net 1251)
	)
	(segment
		(start 130.4375 86.256956)
		(end 130.4375 85.143044)
		(width 0.15)
		(layer "In7.Cu")
		(net 1251)
	)
	(segment
		(start 122.690241 111.174545)
		(end 123.362499 111.174545)
		(width 0.15)
		(layer "In7.Cu")
		(net 1251)
	)
	(segment
		(start 123.224 108.829543)
		(end 122.690241 108.829543)
		(width 0.15)
		(layer "In7.Cu")
		(net 1251)
	)
	(segment
		(start 126.656956 73.0375)
		(end 129.956956 73.0375)
		(width 0.15)
		(layer "In7.Cu")
		(net 1251)
	)
	(segment
		(start 123.637501 108.829543)
		(end 123.224 108.829543)
		(width 0.15)
		(layer "In7.Cu")
		(net 1251)
	)
	(segment
		(start 120.198799 116.245654)
		(end 120.29638 116.148075)
		(width 0.15)
		(layer "In7.Cu")
		(net 1251)
	)
	(segment
		(start 127.4375 78.156956)
		(end 127.8375 77.756956)
		(width 0.15)
		(layer "In7.Cu")
		(net 1251)
	)
	(segment
		(start 130.4125 72.4625)
		(end 130.725 72.15)
		(width 0.15)
		(layer "In7.Cu")
		(net 1251)
	)
	(segment
		(start 114.593044 119.6375)
		(end 115.043044 120.0875)
		(width 0.15)
		(layer "In7.Cu")
		(net 1251)
	)
	(segment
		(start 101.688346 121.927498)
		(end 103.978344 119.6375)
		(width 0.15)
		(layer "In7.Cu")
		(net 1251)
	)
	(segment
		(start 127.6375 103.156956)
		(end 127.6375 89.056956)
		(width 0.15)
		(layer "In7.Cu")
		(net 1251)
	)
	(segment
		(start 127.8375 76.443044)
		(end 126.8375 75.443044)
		(width 0.15)
		(layer "In7.Cu")
		(net 1251)
	)
	(segment
		(start 124.72325 110.761044)
		(end 124.72325 110.623044)
		(width 0.15)
		(layer "In7.Cu")
		(net 1251)
	)
	(segment
		(start 122.551742 110.071044)
		(end 122.551742 109.933044)
		(width 0.15)
		(layer "In7.Cu")
		(net 1251)
	)
	(segment
		(start 124.72325 112.141044)
		(end 124.72325 112.003044)
		(width 0.15)
		(layer "In7.Cu")
		(net 1251)
	)
	(segment
		(start 123.6375 112.806956)
		(end 123.637501 112.693044)
		(width 0.15)
		(layer "In7.Cu")
		(net 1251)
	)
	(segment
		(start 120.576247 116.81897)
		(end 120.198799 116.441521)
		(width 0.15)
		(layer "In7.Cu")
		(net 1251)
	)
	(segment
		(start 120.604151 115.840305)
		(end 121.51545 114.929005)
		(width 0.15)
		(layer "In7.Cu")
		(net 1251)
	)
	(segment
		(start 118.455247 116.453718)
		(end 118.552829 116.356137)
		(width 0.15)
		(layer "In7.Cu")
		(net 1251)
	)
	(segment
		(start 91.542501 106.8275)
		(end 91.542501 107.863043)
		(width 0.15)
		(layer "In7.Cu")
		(net 1251)
	)
	(segment
		(start 124.259728 106.534728)
		(end 127.6375 103.156956)
		(width 0.15)
		(layer "In7.Cu")
		(net 1251)
	)
	(segment
		(start 127.8375 77.756956)
		(end 127.8375 76.443044)
		(width 0.15)
		(layer "In7.Cu")
		(net 1251)
	)
	(segment
		(start 123.637501 111.174545)
		(end 124.309749 111.174545)
		(width 0.15)
		(layer "In7.Cu")
		(net 1251)
	)
	(segment
		(start 94.372502 115.466958)
		(end 94.372502 118.488346)
		(width 0.15)
		(layer "In7.Cu")
		(net 1251)
	)
	(segment
		(start 103.978344 119.6375)
		(end 114.593044 119.6375)
		(width 0.15)
		(layer "In7.Cu")
		(net 1251)
	)
	(segment
		(start 123.637501 107.863044)
		(end 123.6375 107.156956)
		(width 0.15)
		(layer "In7.Cu")
		(net 1251)
	)
	(segment
		(start 124.309749 108.829543)
		(end 123.637501 108.829543)
		(width 0.15)
		(layer "In7.Cu")
		(net 1251)
	)
	(segment
		(start 94.372502 118.488346)
		(end 97.811654 121.927498)
		(width 0.15)
		(layer "In7.Cu")
		(net 1251)
	)
	(segment
		(start 124.309749 110.209543)
		(end 123.637501 110.209543)
		(width 0.15)
		(layer "In7.Cu")
		(net 1251)
	)
	(segment
		(start 124.309749 111.589543)
		(end 123.776 111.589543)
		(width 0.15)
		(layer "In7.Cu")
		(net 1251)
	)
	(segment
		(start 91.542501 107.863043)
		(end 91.2625 108.143044)
		(width 0.15)
		(layer "In7.Cu")
		(net 1251)
	)
	(segment
		(start 118.344766 118.099689)
		(end 118.344765 118.099688)
		(width 0.15)
		(layer "In7.Cu")
		(net 1251)
	)
	(segment
		(start 120.29638 116.148075)
		(end 120.604151 115.840305)
		(width 0.15)
		(layer "In7.Cu")
		(net 1251)
	)
	(segment
		(start 127.6375 89.056956)
		(end 130.4375 86.256956)
		(width 0.15)
		(layer "In7.Cu")
		(net 1251)
	)
	(segment
		(start 123.362499 110.209543)
		(end 122.690241 110.209543)
		(width 0.15)
		(layer "In7.Cu")
		(net 1251)
	)
	(segment
		(start 126.4375 73.256956)
		(end 126.656956 73.0375)
		(width 0.15)
		(layer "In7.Cu")
		(net 1251)
	)
	(segment
		(start 121.51545 114.929005)
		(end 123.6375 112.806956)
		(width 0.15)
		(layer "In7.Cu")
		(net 1251)
	)
	(arc
		(start 122.690241 110.209543)
		(mid 122.592307 110.168978)
		(end 122.551742 110.071044)
		(width 0.15)
		(layer "In7.Cu")
		(net 1251)
	)
	(arc
		(start 124.72325 110.623044)
		(mid 124.602138 110.330655)
		(end 124.309749 110.209543)
		(width 0.15)
		(layer "In7.Cu")
		(net 1251)
	)
	(arc
		(start 122.551742 109.933044)
		(mid 122.592307 109.83511)
		(end 122.690241 109.794545)
		(width 0.15)
		(layer "In7.Cu")
		(net 1251)
	)
	(arc
		(start 120.198799 116.441521)
		(mid 120.158233 116.343588)
		(end 120.198799 116.245654)
		(width 0.15)
		(layer "In7.Cu")
		(net 1251)
	)
	(arc
		(start 122.551742 108.553044)
		(mid 122.592307 108.45511)
		(end 122.690241 108.414545)
		(width 0.15)
		(layer "In7.Cu")
		(net 1251)
	)
	(arc
		(start 122.690241 108.829543)
		(mid 122.592307 108.788978)
		(end 122.551742 108.691044)
		(width 0.15)
		(layer "In7.Cu")
		(net 1251)
	)
	(arc
		(start 122.690241 111.589543)
		(mid 122.592307 111.548978)
		(end 122.551742 111.451044)
		(width 0.15)
		(layer "In7.Cu")
		(net 1251)
	)
	(arc
		(start 118.91808 118.477136)
		(mid 119.21047 118.598247)
		(end 119.502859 118.477136)
		(width 0.15)
		(layer "In7.Cu")
		(net 1251)
	)
	(arc
		(start 124.309749 111.174545)
		(mid 124.602138 111.053433)
		(end 124.72325 110.761044)
		(width 0.15)
		(layer "In7.Cu")
		(net 1251)
	)
	(arc
		(start 124.309749 109.794545)
		(mid 124.602138 109.673433)
		(end 124.72325 109.381044)
		(width 0.15)
		(layer "In7.Cu")
		(net 1251)
	)
	(arc
		(start 118.455248 116.649584)
		(mid 118.414682 116.551651)
		(end 118.455247 116.453718)
		(width 0.15)
		(layer "In7.Cu")
		(net 1251)
	)
	(arc
		(start 122.551742 111.313044)
		(mid 122.592307 111.21511)
		(end 122.690241 111.174545)
		(width 0.15)
		(layer "In7.Cu")
		(net 1251)
	)
	(arc
		(start 124.72325 109.243044)
		(mid 124.602138 108.950655)
		(end 124.309749 108.829543)
		(width 0.15)
		(layer "In7.Cu")
		(net 1251)
	)
	(arc
		(start 119.893888 117.50133)
		(mid 120.186278 117.622441)
		(end 120.478667 117.50133)
		(width 0.15)
		(layer "In7.Cu")
		(net 1251)
	)
	(arc
		(start 120.576247 117.403749)
		(mid 120.697359 117.111359)
		(end 120.576247 116.81897)
		(width 0.15)
		(layer "In7.Cu")
		(net 1251)
	)
	(arc
		(start 124.72325 112.003044)
		(mid 124.602138 111.710655)
		(end 124.309749 111.589543)
		(width 0.15)
		(layer "In7.Cu")
		(net 1251)
	)
	(arc
		(start 119.600439 118.379555)
		(mid 119.721551 118.087165)
		(end 119.600439 117.794776)
		(width 0.15)
		(layer "In7.Cu")
		(net 1251)
	)
	(arc
		(start 124.309749 112.554545)
		(mid 124.602138 112.433433)
		(end 124.72325 112.141044)
		(width 0.15)
		(layer "In7.Cu")
		(net 1251)
	)
	(arc
		(start 118.344765 118.099688)
		(mid 118.442699 118.059122)
		(end 118.540633 118.099688)
		(width 0.15)
		(layer "In7.Cu")
		(net 1251)
	)
	(arc
		(start 123.224 108.414545)
		(mid 123.516389 108.293433)
		(end 123.637501 108.001044)
		(width 0.15)
		(layer "In7.Cu")
		(net 1251)
	)
	(arc
		(start 123.637501 112.693044)
		(mid 123.678066 112.59511)
		(end 123.776 112.554545)
		(width 0.15)
		(layer "In7.Cu")
		(net 1251)
	)
	(arc
		(start 118.552829 116.356137)
		(mid 118.650763 116.315571)
		(end 118.748695 116.356138)
		(width 0.15)
		(layer "In7.Cu")
		(net 1251)
	)
	(segment
		(start 100.695532 80.265)
		(end 100.580532 80.15)
		(width 0.19)
		(layer "F.Cu")
		(net 1252)
	)
	(segment
		(start 100.695532 80.885)
		(end 100.695532 80.265)
		(width 0.19)
		(layer "F.Cu")
		(net 1252)
	)
	(segment
		(start 100.430532 81.15)
		(end 100.695532 80.885)
		(width 0.19)
		(layer "F.Cu")
		(net 1252)
	)
	(via
		(at 92.102261 112.097739)
		(size 0.45)
		(drill 0.1)
		(layers "F.Cu" "B.Cu")
		(net 1252)
	)
	(via
		(at 100.580532 80.15)
		(size 0.45)
		(drill 0.1)
		(layers "F.Cu" "B.Cu")
		(net 1252)
	)
	(segment
		(start 92.286109 112.097739)
		(end 92.102261 112.097739)
		(width 0.19)
		(layer "B.Cu")
		(net 1252)
	)
	(segment
		(start 96.68 106.015)
		(end 96.365 106.33)
		(width 0.19)
		(layer "B.Cu")
		(net 1252)
	)
	(segment
		(start 96.365 111.59663)
		(end 94.77663 113.185)
		(width 0.19)
		(layer "B.Cu")
		(net 1252)
	)
	(segment
		(start 93.37337 113.185)
		(end 92.286109 112.097739)
		(width 0.19)
		(layer "B.Cu")
		(net 1252)
	)
	(segment
		(start 96.68 105.99)
		(end 96.68 106.015)
		(width 0.19)
		(layer "B.Cu")
		(net 1252)
	)
	(segment
		(start 96.365 106.33)
		(end 96.365 111.59663)
		(width 0.19)
		(layer "B.Cu")
		(net 1252)
	)
	(segment
		(start 94.77663 113.185)
		(end 93.37337 113.185)
		(width 0.19)
		(layer "B.Cu")
		(net 1252)
	)
	(segment
		(start 93.993044 109.7125)
		(end 92.168044 109.7125)
		(width 0.15)
		(layer "In5.Cu")
		(net 1252)
	)
	(segment
		(start 97.7375 87.118044)
		(end 97.7375 88.393044)
		(width 0.15)
		(layer "In5.Cu")
		(net 1252)
	)
	(segment
		(start 100.743032 80.3125)
		(end 100.743032 84.112512)
		(width 0.15)
		(layer "In5.Cu")
		(net 1252)
	)
	(segment
		(start 91.5625 111.306956)
		(end 92.102261 111.846716)
		(width 0.15)
		(layer "In5.Cu")
		(net 1252)
	)
	(segment
		(start 92.168044 109.7125)
		(end 91.5625 110.318044)
		(width 0.15)
		(layer "In5.Cu")
		(net 1252)
	)
	(segment
		(start 94.7625 91.368044)
		(end 94.7625 108.943044)
		(width 0.15)
		(layer "In5.Cu")
		(net 1252)
	)
	(segment
		(start 91.5625 110.318044)
		(end 91.5625 111.306956)
		(width 0.15)
		(layer "In5.Cu")
		(net 1252)
	)
	(segment
		(start 97.7375 88.393044)
		(end 94.7625 91.368044)
		(width 0.15)
		(layer "In5.Cu")
		(net 1252)
	)
	(segment
		(start 94.7625 108.943044)
		(end 93.993044 109.7125)
		(width 0.15)
		(layer "In5.Cu")
		(net 1252)
	)
	(segment
		(start 100.743032 84.112512)
		(end 97.7375 87.118044)
		(width 0.15)
		(layer "In5.Cu")
		(net 1252)
	)
	(segment
		(start 100.580532 80.15)
		(end 100.743032 80.3125)
		(width 0.15)
		(layer "In5.Cu")
		(net 1252)
	)
	(segment
		(start 92.102261 111.846716)
		(end 92.102261 112.097739)
		(width 0.15)
		(layer "In5.Cu")
		(net 1252)
	)
	(segment
		(start 101.065532 80.265)
		(end 101.180532 80.15)
		(width 0.19)
		(layer "F.Cu")
		(net 1253)
	)
	(segment
		(start 101.330532 81.15)
		(end 101.065532 80.885)
		(width 0.19)
		(layer "F.Cu")
		(net 1253)
	)
	(segment
		(start 101.065532 80.885)
		(end 101.065532 80.265)
		(width 0.19)
		(layer "F.Cu")
		(net 1253)
	)
	(via
		(at 101.180532 80.15)
		(size 0.45)
		(drill 0.1)
		(layers "F.Cu" "B.Cu")
		(net 1253)
	)
	(via
		(at 92.547739 111.652261)
		(size 0.45)
		(drill 0.1)
		(layers "F.Cu" "B.Cu")
		(net 1253)
	)
	(segment
		(start 95.878843 111.559528)
		(end 95.995 111.44337)
		(width 0.19)
		(layer "B.Cu")
		(net 1253)
	)
	(segment
		(start 95.299014 112.139357)
		(end 95.299014 112.139356)
		(width 0.19)
		(layer "B.Cu")
		(net 1253)
	)
	(segment
		(start 93.52663 112.815)
		(end 94.62337 112.815)
		(width 0.19)
		(layer "B.Cu")
		(net 1253)
	)
	(segment
		(start 94.719186 112.487253)
		(end 94.648749 112.416816)
		(width 0.19)
		(layer "B.Cu")
		(net 1253)
	)
	(segment
		(start 95.68 106.015)
		(end 95.68 105.99)
		(width 0.19)
		(layer "B.Cu")
		(net 1253)
	)
	(segment
		(start 95.995 110.630536)
		(end 95.995 106.33)
		(width 0.19)
		(layer "B.Cu")
		(net 1253)
	)
	(segment
		(start 95.228561 111.605041)
		(end 95.286546 111.547057)
		(width 0.19)
		(layer "B.Cu")
		(net 1253)
	)
	(segment
		(start 95.241033 112.19734)
		(end 95.299014 112.139357)
		(width 0.19)
		(layer "B.Cu")
		(net 1253)
	)
	(segment
		(start 95.995 111.44337)
		(end 95.995 110.630536)
		(width 0.19)
		(layer "B.Cu")
		(net 1253)
	)
	(segment
		(start 94.648748 112.184886)
		(end 94.706733 112.126902)
		(width 0.19)
		(layer "B.Cu")
		(net 1253)
	)
	(segment
		(start 95.518476 111.547058)
		(end 95.58893 111.617512)
		(width 0.19)
		(layer "B.Cu")
		(net 1253)
	)
	(segment
		(start 95.820862 111.617511)
		(end 95.878843 111.559528)
		(width 0.19)
		(layer "B.Cu")
		(net 1253)
	)
	(segment
		(start 95.995 106.33)
		(end 95.68 106.015)
		(width 0.19)
		(layer "B.Cu")
		(net 1253)
	)
	(segment
		(start 94.62337 112.815)
		(end 94.719185 112.719185)
		(width 0.19)
		(layer "B.Cu")
		(net 1253)
	)
	(segment
		(start 94.938663 112.126903)
		(end 95.009101 112.197341)
		(width 0.19)
		(layer "B.Cu")
		(net 1253)
	)
	(segment
		(start 92.547739 111.836109)
		(end 93.52663 112.815)
		(width 0.19)
		(layer "B.Cu")
		(net 1253)
	)
	(segment
		(start 95.299015 111.907424)
		(end 95.228562 111.836971)
		(width 0.19)
		(layer "B.Cu")
		(net 1253)
	)
	(segment
		(start 92.547739 111.652261)
		(end 92.547739 111.836109)
		(width 0.19)
		(layer "B.Cu")
		(net 1253)
	)
	(arc
		(start 95.009101 112.197341)
		(mid 95.125066 112.245376)
		(end 95.241033 112.19734)
		(width 0.19)
		(layer "B.Cu")
		(net 1253)
	)
	(arc
		(start 94.648749 112.416816)
		(mid 94.600715 112.30085)
		(end 94.648748 112.184886)
		(width 0.19)
		(layer "B.Cu")
		(net 1253)
	)
	(arc
		(start 95.228562 111.836971)
		(mid 95.180528 111.721005)
		(end 95.228561 111.605041)
		(width 0.19)
		(layer "B.Cu")
		(net 1253)
	)
	(arc
		(start 94.706733 112.126902)
		(mid 94.822698 112.078868)
		(end 94.938663 112.126903)
		(width 0.19)
		(layer "B.Cu")
		(net 1253)
	)
	(arc
		(start 95.299014 112.139356)
		(mid 95.347049 112.02339)
		(end 95.299015 111.907424)
		(width 0.19)
		(layer "B.Cu")
		(net 1253)
	)
	(arc
		(start 95.58893 111.617512)
		(mid 95.704895 111.665547)
		(end 95.820862 111.617511)
		(width 0.19)
		(layer "B.Cu")
		(net 1253)
	)
	(arc
		(start 95.286546 111.547057)
		(mid 95.402511 111.499023)
		(end 95.518476 111.547058)
		(width 0.19)
		(layer "B.Cu")
		(net 1253)
	)
	(arc
		(start 94.719185 112.719185)
		(mid 94.76722 112.603219)
		(end 94.719186 112.487253)
		(width 0.19)
		(layer "B.Cu")
		(net 1253)
	)
	(segment
		(start 98.0125 88.506956)
		(end 95.0375 91.481956)
		(width 0.15)
		(layer "In5.Cu")
		(net 1253)
	)
	(segment
		(start 95.0375 109.056956)
		(end 94.106956 109.9875)
		(width 0.15)
		(layer "In5.Cu")
		(net 1253)
	)
	(segment
		(start 91.8375 111.193044)
		(end 92.296716 111.652261)
		(width 0.15)
		(layer "In5.Cu")
		(net 1253)
	)
	(segment
		(start 92.296716 111.652261)
		(end 92.547739 111.652261)
		(width 0.15)
		(layer "In5.Cu")
		(net 1253)
	)
	(segment
		(start 92.281956 109.9875)
		(end 91.8375 110.431956)
		(width 0.15)
		(layer "In5.Cu")
		(net 1253)
	)
	(segment
		(start 98.0125 87.231956)
		(end 98.0125 88.506956)
		(width 0.15)
		(layer "In5.Cu")
		(net 1253)
	)
	(segment
		(start 101.018032 84.226424)
		(end 98.0125 87.231956)
		(width 0.15)
		(layer "In5.Cu")
		(net 1253)
	)
	(segment
		(start 95.0375 91.481956)
		(end 95.0375 109.056956)
		(width 0.15)
		(layer "In5.Cu")
		(net 1253)
	)
	(segment
		(start 101.180532 80.15)
		(end 101.018032 80.3125)
		(width 0.15)
		(layer "In5.Cu")
		(net 1253)
	)
	(segment
		(start 91.8375 110.431956)
		(end 91.8375 111.193044)
		(width 0.15)
		(layer "In5.Cu")
		(net 1253)
	)
	(segment
		(start 94.106956 109.9875)
		(end 92.281956 109.9875)
		(width 0.15)
		(layer "In5.Cu")
		(net 1253)
	)
	(segment
		(start 101.018032 80.3125)
		(end 101.018032 84.226424)
		(width 0.15)
		(layer "In5.Cu")
		(net 1253)
	)
	(segment
		(start 93.9 91)
		(end 93.785 90.885)
		(width 0.19)
		(layer "F.Cu")
		(net 1254)
	)
	(segment
		(start 90.115 90.885)
		(end 89.6 91.4)
		(width 0.19)
		(layer "F.Cu")
		(net 1254)
	)
	(segment
		(start 99.065532 84.765)
		(end 99.180532 84.65)
		(width 0.19)
		(layer "F.Cu")
		(net 1254)
	)
	(segment
		(start 99.065532 85.385)
		(end 99.065532 84.765)
		(width 0.19)
		(layer "F.Cu")
		(net 1254)
	)
	(segment
		(start 93.785 90.885)
		(end 90.115 90.885)
		(width 0.19)
		(layer "F.Cu")
		(net 1254)
	)
	(segment
		(start 99.330532 85.65)
		(end 99.065532 85.385)
		(width 0.19)
		(layer "F.Cu")
		(net 1254)
	)
	(via
		(at 99.180532 84.65)
		(size 0.45)
		(drill 0.1)
		(layers "F.Cu" "B.Cu")
		(net 1254)
	)
	(via
		(at 93.9 91)
		(size 0.45)
		(drill 0.1)
		(layers "F.Cu" "B.Cu")
		(net 1254)
	)
	(segment
		(start 95.32 92.613668)
		(end 95.45 92.613668)
		(width 0.15)
		(layer "In7.Cu")
		(net 1254)
	)
	(segment
		(start 97.01074 90.756955)
		(end 97.898991 91.645206)
		(width 0.15)
		(layer "In7.Cu")
		(net 1254)
	)
	(segment
		(start 97.929978 89.837716)
		(end 98.818193 90.725932)
		(width 0.15)
		(layer "In7.Cu")
		(net 1254)
	)
	(segment
		(start 97.648907 89.556642)
		(end 97.746135 89.65387)
		(width 0.15)
		(layer "In7.Cu")
		(net 1254)
	)
	(segment
		(start 99.018032 88.1)
		(end 99.018032 87.723576)
		(width 0.15)
		(layer "In7.Cu")
		(net 1254)
	)
	(segment
		(start 96.656347 88.921173)
		(end 96.748272 88.829249)
		(width 0.15)
		(layer "In7.Cu")
		(net 1254)
	)
	(segment
		(start 99.018032 84.8125)
		(end 99.180532 84.65)
		(width 0.15)
		(layer "In7.Cu")
		(net 1254)
	)
	(segment
		(start 98.675976 88.918478)
		(end 99.018032 88.576424)
		(width 0.15)
		(layer "In7.Cu")
		(net 1254)
	)
	(segment
		(start 94.9225 90.96)
		(end 94.9225 92.216168)
		(width 0.15)
		(layer "In7.Cu")
		(net 1254)
	)
	(segment
		(start 97.746135 89.65387)
		(end 97.74613 89.653869)
		(width 0.15)
		(layer "In7.Cu")
		(net 1254)
	)
	(segment
		(start 95.8475 92.216168)
		(end 95.8475 90.96)
		(width 0.15)
		(layer "In7.Cu")
		(net 1254)
	)
	(segment
		(start 98.461141 91.645206)
		(end 98.553064 91.553282)
		(width 0.15)
		(layer "In7.Cu")
		(net 1254)
	)
	(segment
		(start 99.472266 90.071858)
		(end 98.58405 89.183642)
		(width 0.15)
		(layer "In7.Cu")
		(net 1254)
	)
	(segment
		(start 96.921514 88.829249)
		(end 97.648907 89.556642)
		(width 0.15)
		(layer "In7.Cu")
		(net 1254)
	)
	(segment
		(start 97.480968 89.919033)
		(end 97.383739 89.821807)
		(width 0.15)
		(layer "In7.Cu")
		(net 1254)
	)
	(segment
		(start 96.1 90.8375)
		(end 96.756956 90.8375)
		(width 0.15)
		(layer "In7.Cu")
		(net 1254)
	)
	(segment
		(start 96.756956 90.8375)
		(end 96.837499 90.756955)
		(width 0.15)
		(layer "In7.Cu")
		(net 1254)
	)
	(segment
		(start 97.383739 89.821807)
		(end 96.656348 89.094413)
		(width 0.15)
		(layer "In7.Cu")
		(net 1254)
	)
	(segment
		(start 98.553064 90.991132)
		(end 97.664812 90.10288)
		(width 0.15)
		(layer "In7.Cu")
		(net 1254)
	)
	(segment
		(start 95.2875 86.806956)
		(end 95.706956 86.3875)
		(width 0.15)
		(layer "In7.Cu")
		(net 1254)
	)
	(segment
		(start 99.018032 88.576424)
		(end 99.018032 88.1)
		(width 0.15)
		(layer "In7.Cu")
		(net 1254)
	)
	(segment
		(start 98.58405 89.010401)
		(end 98.675976 88.918478)
		(width 0.15)
		(layer "In7.Cu")
		(net 1254)
	)
	(segment
		(start 98.106956 86.3875)
		(end 99.018032 85.476424)
		(width 0.15)
		(layer "In7.Cu")
		(net 1254)
	)
	(segment
		(start 98.556956 87.2625)
		(end 95.456956 87.2625)
		(width 0.15)
		(layer "In7.Cu")
		(net 1254)
	)
	(segment
		(start 94.0625 90.8375)
		(end 94.8 90.8375)
		(width 0.15)
		(layer "In7.Cu")
		(net 1254)
	)
	(segment
		(start 97.74613 89.653869)
		(end 97.929978 89.837716)
		(width 0.15)
		(layer "In7.Cu")
		(net 1254)
	)
	(segment
		(start 95.706956 86.3875)
		(end 98.106956 86.3875)
		(width 0.15)
		(layer "In7.Cu")
		(net 1254)
	)
	(segment
		(start 95.456956 87.2625)
		(end 95.2875 87.093044)
		(width 0.15)
		(layer "In7.Cu")
		(net 1254)
	)
	(segment
		(start 97.664812 90.10288)
		(end 97.480964 89.919032)
		(width 0.15)
		(layer "In7.Cu")
		(net 1254)
	)
	(segment
		(start 99.018032 85.476424)
		(end 99.018032 84.8125)
		(width 0.15)
		(layer "In7.Cu")
		(net 1254)
	)
	(segment
		(start 95.97 90.8375)
		(end 96.1 90.8375)
		(width 0.15)
		(layer "In7.Cu")
		(net 1254)
	)
	(segment
		(start 95.2875 87.093044)
		(end 95.2875 86.806956)
		(width 0.15)
		(layer "In7.Cu")
		(net 1254)
	)
	(segment
		(start 93.9 91)
		(end 94.0625 90.8375)
		(width 0.15)
		(layer "In7.Cu")
		(net 1254)
	)
	(segment
		(start 97.480964 89.919032)
		(end 97.480968 89.919033)
		(width 0.15)
		(layer "In7.Cu")
		(net 1254)
	)
	(segment
		(start 99.018032 87.723576)
		(end 98.556956 87.2625)
		(width 0.15)
		(layer "In7.Cu")
		(net 1254)
	)
	(segment
		(start 99.380343 90.725932)
		(end 99.472266 90.634008)
		(width 0.15)
		(layer "In7.Cu")
		(net 1254)
	)
	(arc
		(start 96.748272 88.829249)
		(mid 96.834892 88.79337)
		(end 96.921514 88.829249)
		(width 0.15)
		(layer "In7.Cu")
		(net 1254)
	)
	(arc
		(start 95.45 92.613668)
		(mid 95.731075 92.497243)
		(end 95.8475 92.216168)
		(width 0.15)
		(layer "In7.Cu")
		(net 1254)
	)
	(arc
		(start 96.837499 90.756955)
		(mid 96.924119 90.721076)
		(end 97.01074 90.756955)
		(width 0.15)
		(layer "In7.Cu")
		(net 1254)
	)
	(arc
		(start 98.818193 90.725932)
		(mid 99.099268 90.842357)
		(end 99.380343 90.725932)
		(width 0.15)
		(layer "In7.Cu")
		(net 1254)
	)
	(arc
		(start 95.8475 90.96)
		(mid 95.883379 90.873379)
		(end 95.97 90.8375)
		(width 0.15)
		(layer "In7.Cu")
		(net 1254)
	)
	(arc
		(start 98.58405 89.183642)
		(mid 98.54817 89.097022)
		(end 98.58405 89.010401)
		(width 0.15)
		(layer "In7.Cu")
		(net 1254)
	)
	(arc
		(start 99.472266 90.634008)
		(mid 99.588691 90.352933)
		(end 99.472266 90.071858)
		(width 0.15)
		(layer "In7.Cu")
		(net 1254)
	)
	(arc
		(start 98.553064 91.553282)
		(mid 98.669489 91.272207)
		(end 98.553064 90.991132)
		(width 0.15)
		(layer "In7.Cu")
		(net 1254)
	)
	(arc
		(start 96.656348 89.094413)
		(mid 96.620469 89.007792)
		(end 96.656347 88.921173)
		(width 0.15)
		(layer "In7.Cu")
		(net 1254)
	)
	(arc
		(start 94.8 90.8375)
		(mid 94.886621 90.873379)
		(end 94.9225 90.96)
		(width 0.15)
		(layer "In7.Cu")
		(net 1254)
	)
	(arc
		(start 97.898991 91.645206)
		(mid 98.180066 91.761631)
		(end 98.461141 91.645206)
		(width 0.15)
		(layer "In7.Cu")
		(net 1254)
	)
	(arc
		(start 94.9225 92.216168)
		(mid 95.038925 92.497243)
		(end 95.32 92.613668)
		(width 0.15)
		(layer "In7.Cu")
		(net 1254)
	)
	(segment
		(start 89.92 93.785)
		(end 92.685 93.785)
		(width 0.19)
		(layer "F.Cu")
		(net 1255)
	)
	(segment
		(start 98.695532 73.385)
		(end 98.695532 72.765)
		(width 0.19)
		(layer "F.Cu")
		(net 1255)
	)
	(segment
		(start 98.695532 72.765)
		(end 98.580532 72.65)
		(width 0.19)
		(layer "F.Cu")
		(net 1255)
	)
	(segment
		(start 89.58 94.1)
		(end 89.605 94.1)
		(width 0.19)
		(layer "F.Cu")
		(net 1255)
	)
	(segment
		(start 98.430532 73.65)
		(end 98.695532 73.385)
		(width 0.19)
		(layer "F.Cu")
		(net 1255)
	)
	(segment
		(start 92.685 93.785)
		(end 92.8 93.9)
		(width 0.19)
		(layer "F.Cu")
		(net 1255)
	)
	(segment
		(start 89.605 94.1)
		(end 89.92 93.785)
		(width 0.19)
		(layer "F.Cu")
		(net 1255)
	)
	(via
		(at 98.580532 72.65)
		(size 0.45)
		(drill 0.1)
		(layers "F.Cu" "B.Cu")
		(net 1255)
	)
	(via
		(at 92.8 93.9)
		(size 0.45)
		(drill 0.1)
		(layers "F.Cu" "B.Cu")
		(net 1255)
	)
	(segment
		(start 93.6875 92.743044)
		(end 93.6875 93.306956)
		(width 0.15)
		(layer "In7.Cu")
		(net 1255)
	)
	(segment
		(start 92.9625 93.7375)
		(end 92.8 93.9)
		(width 0.15)
		(layer "In7.Cu")
		(net 1255)
	)
	(segment
		(start 98.456956 74.6375)
		(end 97.056956 74.6375)
		(width 0.15)
		(layer "In7.Cu")
		(net 1255)
	)
	(segment
		(start 91.3375 86.756956)
		(end 91.3375 89.943044)
		(width 0.15)
		(layer "In7.Cu")
		(net 1255)
	)
	(segment
		(start 98.743032 71.762512)
		(end 99.243044 71.2625)
		(width 0.15)
		(layer "In7.Cu")
		(net 1255)
	)
	(segment
		(start 92.9375 91.543044)
		(end 92.9375 91.993044)
		(width 0.15)
		(layer "In7.Cu")
		(net 1255)
	)
	(segment
		(start 91.3375 89.943044)
		(end 92.9375 91.543044)
		(width 0.15)
		(layer "In7.Cu")
		(net 1255)
	)
	(segment
		(start 100.3375 72.756956)
		(end 98.456956 74.6375)
		(width 0.15)
		(layer "In7.Cu")
		(net 1255)
	)
	(segment
		(start 98.580532 72.65)
		(end 98.743032 72.4875)
		(width 0.15)
		(layer "In7.Cu")
		(net 1255)
	)
	(segment
		(start 93.0375 79.156956)
		(end 93.0375 85.056956)
		(width 0.15)
		(layer "In7.Cu")
		(net 1255)
	)
	(segment
		(start 99.856956 71.2625)
		(end 100.3375 71.743044)
		(width 0.15)
		(layer "In7.Cu")
		(net 1255)
	)
	(segment
		(start 99.243044 71.2625)
		(end 99.856956 71.2625)
		(width 0.15)
		(layer "In7.Cu")
		(net 1255)
	)
	(segment
		(start 96.1375 76.056956)
		(end 93.0375 79.156956)
		(width 0.15)
		(layer "In7.Cu")
		(net 1255)
	)
	(segment
		(start 96.1375 75.556956)
		(end 96.1375 76.056956)
		(width 0.15)
		(layer "In7.Cu")
		(net 1255)
	)
	(segment
		(start 98.743032 72.4875)
		(end 98.743032 71.762512)
		(width 0.15)
		(layer "In7.Cu")
		(net 1255)
	)
	(segment
		(start 93.0375 85.056956)
		(end 91.3375 86.756956)
		(width 0.15)
		(layer "In7.Cu")
		(net 1255)
	)
	(segment
		(start 92.9375 91.993044)
		(end 93.6875 92.743044)
		(width 0.15)
		(layer "In7.Cu")
		(net 1255)
	)
	(segment
		(start 93.256956 93.7375)
		(end 92.9625 93.7375)
		(width 0.15)
		(layer "In7.Cu")
		(net 1255)
	)
	(segment
		(start 100.3375 71.743044)
		(end 100.3375 72.756956)
		(width 0.15)
		(layer "In7.Cu")
		(net 1255)
	)
	(segment
		(start 97.056956 74.6375)
		(end 96.1375 75.556956)
		(width 0.15)
		(layer "In7.Cu")
		(net 1255)
	)
	(segment
		(start 93.6875 93.306956)
		(end 93.256956 93.7375)
		(width 0.15)
		(layer "In7.Cu")
		(net 1255)
	)
	(segment
		(start 99.065532 81.765)
		(end 99.180532 81.65)
		(width 0.19)
		(layer "F.Cu")
		(net 1256)
	)
	(segment
		(start 89.58 96.9)
		(end 89.605 96.9)
		(width 0.19)
		(layer "F.Cu")
		(net 1256)
	)
	(segment
		(start 89.92 96.585)
		(end 93.485 96.585)
		(width 0.19)
		(layer "F.Cu")
		(net 1256)
	)
	(segment
		(start 99.065532 82.385)
		(end 99.065532 81.765)
		(width 0.19)
		(layer "F.Cu")
		(net 1256)
	)
	(segment
		(start 99.330532 82.65)
		(end 99.065532 82.385)
		(width 0.19)
		(layer "F.Cu")
		(net 1256)
	)
	(segment
		(start 89.605 96.9)
		(end 89.92 96.585)
		(width 0.19)
		(layer "F.Cu")
		(net 1256)
	)
	(segment
		(start 93.485 96.585)
		(end 93.6 96.7)
		(width 0.19)
		(layer "F.Cu")
		(net 1256)
	)
	(via
		(at 99.180532 81.65)
		(size 0.45)
		(drill 0.1)
		(layers "F.Cu" "B.Cu")
		(net 1256)
	)
	(via
		(at 93.6 96.7)
		(size 0.45)
		(drill 0.1)
		(layers "F.Cu" "B.Cu")
		(net 1256)
	)
	(segment
		(start 98.388018 93.606435)
		(end 99.322228 92.672228)
		(width 0.15)
		(layer "In7.Cu")
		(net 1256)
	)
	(segment
		(start 99.7375 86.543044)
		(end 99.7375 85.456956)
		(width 0.15)
		(layer "In7.Cu")
		(net 1256)
	)
	(segment
		(start 96.361226 93.59136)
		(end 97.284934 94.515067)
		(width 0.15)
		(layer "In7.Cu")
		(net 1256)
	)
	(segment
		(start 95.707168 94.245449)
		(end 96.630861 95.169142)
		(width 0.15)
		(layer "In7.Cu")
		(net 1256)
	)
	(segment
		(start 96.365693 95.434303)
		(end 96.365696 95.434305)
		(width 0.15)
		(layer "In7.Cu")
		(net 1256)
	)
	(segment
		(start 93.6 96.7)
		(end 93.7625 96.5375)
		(width 0.15)
		(layer "In7.Cu")
		(net 1256)
	)
	(segment
		(start 95.442003 94.510613)
		(end 96.365696 95.434305)
		(width 0.15)
		(layer "In7.Cu")
		(net 1256)
	)
	(segment
		(start 97.284931 94.515065)
		(end 98.208669 95.438803)
		(width 0.15)
		(layer "In7.Cu")
		(net 1256)
	)
	(segment
		(start 96.630858 95.169141)
		(end 97.554595 96.092879)
		(width 0.15)
		(layer "In7.Cu")
		(net 1256)
	)
	(segment
		(start 99.018032 81.8125)
		(end 99.180532 81.65)
		(width 0.15)
		(layer "In7.Cu")
		(net 1256)
	)
	(segment
		(start 100.3375 84.856956)
		(end 100.3375 83.943044)
		(width 0.15)
		(layer "In7.Cu")
		(net 1256)
	)
	(segment
		(start 99.018032 82.623576)
		(end 99.018032 81.8125)
		(width 0.15)
		(layer "In7.Cu")
		(net 1256)
	)
	(segment
		(start 97.284931 94.515065)
		(end 97.284934 94.515067)
		(width 0.15)
		(layer "In7.Cu")
		(net 1256)
	)
	(segment
		(start 99.7375 85.456956)
		(end 100.3375 84.856956)
		(width 0.15)
		(layer "In7.Cu")
		(net 1256)
	)
	(segment
		(start 97.550096 94.249903)
		(end 98.473803 95.173611)
		(width 0.15)
		(layer "In7.Cu")
		(net 1256)
	)
	(segment
		(start 96.361226 93.41812)
		(end 96.453151 93.326196)
		(width 0.15)
		(layer "In7.Cu")
		(net 1256)
	)
	(segment
		(start 95.456956 96.5375)
		(end 95.722228 96.272228)
		(width 0.15)
		(layer "In7.Cu")
		(net 1256)
	)
	(segment
		(start 95.442003 94.337373)
		(end 95.533928 94.245449)
		(width 0.15)
		(layer "In7.Cu")
		(net 1256)
	)
	(segment
		(start 96.365693 95.434303)
		(end 96.935844 96.004454)
		(width 0.15)
		(layer "In7.Cu")
		(net 1256)
	)
	(segment
		(start 96.626391 93.326196)
		(end 97.550099 94.249904)
		(width 0.15)
		(layer "In7.Cu")
		(net 1256)
	)
	(segment
		(start 100.3375 91.656956)
		(end 100.3375 87.143044)
		(width 0.15)
		(layer "In7.Cu")
		(net 1256)
	)
	(segment
		(start 97.550099 94.249904)
		(end 97.550096 94.249903)
		(width 0.15)
		(layer "In7.Cu")
		(net 1256)
	)
	(segment
		(start 95.722228 96.272228)
		(end 95.722227 96.272227)
		(width 0.15)
		(layer "In7.Cu")
		(net 1256)
	)
	(segment
		(start 100.3375 87.143044)
		(end 99.7375 86.543044)
		(width 0.15)
		(layer "In7.Cu")
		(net 1256)
	)
	(segment
		(start 95.895467 96.272227)
		(end 96.28177 96.65853)
		(width 0.15)
		(layer "In7.Cu")
		(net 1256)
	)
	(segment
		(start 96.630861 95.169142)
		(end 96.630858 95.169141)
		(width 0.15)
		(layer "In7.Cu")
		(net 1256)
	)
	(segment
		(start 99.035955 95.173611)
		(end 99.127878 95.081687)
		(width 0.15)
		(layer "In7.Cu")
		(net 1256)
	)
	(segment
		(start 99.127878 94.519535)
		(end 98.388018 93.779675)
		(width 0.15)
		(layer "In7.Cu")
		(net 1256)
	)
	(segment
		(start 96.843921 96.65853)
		(end 96.935844 96.566606)
		(width 0.15)
		(layer "In7.Cu")
		(net 1256)
	)
	(segment
		(start 99.322228 92.672228)
		(end 100.3375 91.656956)
		(width 0.15)
		(layer "In7.Cu")
		(net 1256)
	)
	(segment
		(start 100.3375 83.943044)
		(end 99.018032 82.623576)
		(width 0.15)
		(layer "In7.Cu")
		(net 1256)
	)
	(segment
		(start 98.116746 96.092879)
		(end 98.208669 96.000955)
		(width 0.15)
		(layer "In7.Cu")
		(net 1256)
	)
	(segment
		(start 93.7625 96.5375)
		(end 95.456956 96.5375)
		(width 0.15)
		(layer "In7.Cu")
		(net 1256)
	)
	(arc
		(start 95.533928 94.245449)
		(mid 95.620547 94.209571)
		(end 95.707168 94.245449)
		(width 0.15)
		(layer "In7.Cu")
		(net 1256)
	)
	(arc
		(start 98.388018 93.779675)
		(mid 98.352139 93.693055)
		(end 98.388018 93.606435)
		(width 0.15)
		(layer "In7.Cu")
		(net 1256)
	)
	(arc
		(start 96.361226 93.59136)
		(mid 96.325348 93.504739)
		(end 96.361226 93.41812)
		(width 0.15)
		(layer "In7.Cu")
		(net 1256)
	)
	(arc
		(start 98.473803 95.173611)
		(mid 98.754879 95.290036)
		(end 99.035955 95.173611)
		(width 0.15)
		(layer "In7.Cu")
		(net 1256)
	)
	(arc
		(start 95.442003 94.510613)
		(mid 95.406125 94.423992)
		(end 95.442003 94.337373)
		(width 0.15)
		(layer "In7.Cu")
		(net 1256)
	)
	(arc
		(start 97.554595 96.092879)
		(mid 97.835671 96.209304)
		(end 98.116746 96.092879)
		(width 0.15)
		(layer "In7.Cu")
		(net 1256)
	)
	(arc
		(start 95.722227 96.272227)
		(mid 95.808847 96.236348)
		(end 95.895467 96.272227)
		(width 0.15)
		(layer "In7.Cu")
		(net 1256)
	)
	(arc
		(start 98.208669 96.000955)
		(mid 98.325094 95.719879)
		(end 98.208669 95.438803)
		(width 0.15)
		(layer "In7.Cu")
		(net 1256)
	)
	(arc
		(start 96.453151 93.326196)
		(mid 96.53977 93.290318)
		(end 96.626391 93.326196)
		(width 0.15)
		(layer "In7.Cu")
		(net 1256)
	)
	(arc
		(start 99.127878 95.081687)
		(mid 99.244303 94.800611)
		(end 99.127878 94.519535)
		(width 0.15)
		(layer "In7.Cu")
		(net 1256)
	)
	(arc
		(start 96.935844 96.566606)
		(mid 97.052269 96.28553)
		(end 96.935844 96.004454)
		(width 0.15)
		(layer "In7.Cu")
		(net 1256)
	)
	(arc
		(start 96.28177 96.65853)
		(mid 96.562846 96.774955)
		(end 96.843921 96.65853)
		(width 0.15)
		(layer "In7.Cu")
		(net 1256)
	)
	(segment
		(start 99.065532 76.385)
		(end 99.065532 75.815)
		(width 0.19)
		(layer "F.Cu")
		(net 1257)
	)
	(segment
		(start 89.58 99.8)
		(end 89.605 99.8)
		(width 0.19)
		(layer "F.Cu")
		(net 1257)
	)
	(segment
		(start 99.330532 76.65)
		(end 99.065532 76.385)
		(width 0.19)
		(layer "F.Cu")
		(net 1257)
	)
	(segment
		(start 89.92 99.485)
		(end 92.685 99.485)
		(width 0.19)
		(layer "F.Cu")
		(net 1257)
	)
	(segment
		(start 99.065532 75.815)
		(end 99.180532 75.7)
		(width 0.19)
		(layer "F.Cu")
		(net 1257)
	)
	(segment
		(start 92.685 99.485)
		(end 92.8 99.6)
		(width 0.19)
		(layer "F.Cu")
		(net 1257)
	)
	(segment
		(start 89.605 99.8)
		(end 89.92 99.485)
		(width 0.19)
		(layer "F.Cu")
		(net 1257)
	)
	(via
		(at 99.180532 75.7)
		(size 0.45)
		(drill 0.1)
		(layers "F.Cu" "B.Cu")
		(net 1257)
	)
	(via
		(at 92.8 99.6)
		(size 0.45)
		(drill 0.1)
		(layers "F.Cu" "B.Cu")
		(net 1257)
	)
	(segment
		(start 94.5375 86.356956)
		(end 94.5375 82.643044)
		(width 0.15)
		(layer "In7.Cu")
		(net 1257)
	)
	(segment
		(start 93.9375 98.856956)
		(end 93.9375 97.743044)
		(width 0.15)
		(layer "In7.Cu")
		(net 1257)
	)
	(segment
		(start 92.3375 89.793044)
		(end 92.3375 88.556956)
		(width 0.15)
		(layer "In7.Cu")
		(net 1257)
	)
	(segment
		(start 99.018032 76.676424)
		(end 99.018032 75.8625)
		(width 0.15)
		(layer "In7.Cu")
		(net 1257)
	)
	(segment
		(start 92.984486 87.062408)
		(end 93.311041 87.388963)
		(width 0.15)
		(layer "In7.Cu")
		(net 1257)
	)
	(segment
		(start 92.9375 95.856956)
		(end 94.5375 94.256956)
		(width 0.15)
		(layer "In7.Cu")
		(net 1257)
	)
	(segment
		(start 94.5375 82.643044)
		(end 94.0375 82.143044)
		(width 0.15)
		(layer "In7.Cu")
		(net 1257)
	)
	(segment
		(start 94.0375 82.143044)
		(end 94.0375 80.656956)
		(width 0.15)
		(layer "In7.Cu")
		(net 1257)
	)
	(segment
		(start 96.856956 78.8375)
		(end 99.018032 76.676424)
		(width 0.15)
		(layer "In7.Cu")
		(net 1257)
	)
	(segment
		(start 94.433133 87.202905)
		(end 94.14896 86.918732)
		(width 0.15)
		(layer "In7.Cu")
		(net 1257)
	)
	(segment
		(start 93.4875 91.793044)
		(end 93.4875 90.943044)
		(width 0.15)
		(layer "In7.Cu")
		(net 1257)
	)
	(segment
		(start 92.8 99.6)
		(end 92.9625 99.4375)
		(width 0.15)
		(layer "In7.Cu")
		(net 1257)
	)
	(segment
		(start 92.862029 87.470276)
		(end 92.719323 87.32757)
		(width 0.15)
		(layer "In7.Cu")
		(net 1257)
	)
	(segment
		(start 99.018032 75.8625)
		(end 99.180532 75.7)
		(width 0.15)
		(layer "In7.Cu")
		(net 1257)
	)
	(segment
		(start 94.5375 94.256956)
		(end 94.5375 92.543044)
		(width 0.15)
		(layer "In7.Cu")
		(net 1257)
	)
	(segment
		(start 93.4875 90.943044)
		(end 92.3375 89.793044)
		(width 0.15)
		(layer "In7.Cu")
		(net 1257)
	)
	(segment
		(start 93.756956 92.0625)
		(end 93.4875 91.793044)
		(width 0.15)
		(layer "In7.Cu")
		(net 1257)
	)
	(segment
		(start 92.719323 87.15433)
		(end 92.811246 87.062408)
		(width 0.15)
		(layer "In7.Cu")
		(net 1257)
	)
	(segment
		(start 95.856956 78.8375)
		(end 96.856956 78.8375)
		(width 0.15)
		(layer "In7.Cu")
		(net 1257)
	)
	(segment
		(start 92.9625 99.4375)
		(end 93.356956 99.4375)
		(width 0.15)
		(layer "In7.Cu")
		(net 1257)
	)
	(segment
		(start 94.14896 86.745492)
		(end 94.5375 86.356956)
		(width 0.15)
		(layer "In7.Cu")
		(net 1257)
	)
	(segment
		(start 94.34121 87.856981)
		(end 94.433133 87.765057)
		(width 0.15)
		(layer "In7.Cu")
		(net 1257)
	)
	(segment
		(start 93.311039 87.38896)
		(end 93.779059 87.856981)
		(width 0.15)
		(layer "In7.Cu")
		(net 1257)
	)
	(segment
		(start 93.356956 99.4375)
		(end 93.9375 98.856956)
		(width 0.15)
		(layer "In7.Cu")
		(net 1257)
	)
	(segment
		(start 92.9375 96.743044)
		(end 92.9375 95.856956)
		(width 0.15)
		(layer "In7.Cu")
		(net 1257)
	)
	(segment
		(start 94.0375 80.656956)
		(end 95.856956 78.8375)
		(width 0.15)
		(layer "In7.Cu")
		(net 1257)
	)
	(segment
		(start 92.3375 88.556956)
		(end 92.862028 88.032428)
		(width 0.15)
		(layer "In7.Cu")
		(net 1257)
	)
	(segment
		(start 93.9375 97.743044)
		(end 92.9375 96.743044)
		(width 0.15)
		(layer "In7.Cu")
		(net 1257)
	)
	(segment
		(start 94.056956 92.0625)
		(end 93.756956 92.0625)
		(width 0.15)
		(layer "In7.Cu")
		(net 1257)
	)
	(segment
		(start 93.311041 87.388963)
		(end 93.311039 87.38896)
		(width 0.15)
		(layer "In7.Cu")
		(net 1257)
	)
	(segment
		(start 94.5375 92.543044)
		(end 94.056956 92.0625)
		(width 0.15)
		(layer "In7.Cu")
		(net 1257)
	)
	(arc
		(start 92.811246 87.062408)
		(mid 92.897867 87.026528)
		(end 92.984486 87.062408)
		(width 0.15)
		(layer "In7.Cu")
		(net 1257)
	)
	(arc
		(start 94.433133 87.765057)
		(mid 94.549558 87.483981)
		(end 94.433133 87.202905)
		(width 0.15)
		(layer "In7.Cu")
		(net 1257)
	)
	(arc
		(start 94.14896 86.918732)
		(mid 94.113081 86.832112)
		(end 94.14896 86.745492)
		(width 0.15)
		(layer "In7.Cu")
		(net 1257)
	)
	(arc
		(start 93.779059 87.856981)
		(mid 94.060135 87.973406)
		(end 94.34121 87.856981)
		(width 0.15)
		(layer "In7.Cu")
		(net 1257)
	)
	(arc
		(start 92.719323 87.32757)
		(mid 92.683443 87.240951)
		(end 92.719323 87.15433)
		(width 0.15)
		(layer "In7.Cu")
		(net 1257)
	)
	(arc
		(start 92.862028 88.032428)
		(mid 92.978453 87.751353)
		(end 92.862029 87.470276)
		(width 0.15)
		(layer "In7.Cu")
		(net 1257)
	)
	(segment
		(start 93.9 90.4)
		(end 93.785 90.515)
		(width 0.19)
		(layer "F.Cu")
		(net 1258)
	)
	(segment
		(start 98.430532 85.65)
		(end 98.695532 85.385)
		(width 0.19)
		(layer "F.Cu")
		(net 1258)
	)
	(segment
		(start 89.715 90.515)
		(end 89.6 90.4)
		(width 0.19)
		(layer "F.Cu")
		(net 1258)
	)
	(segment
		(start 98.695532 84.765)
		(end 98.580532 84.65)
		(width 0.19)
		(layer "F.Cu")
		(net 1258)
	)
	(segment
		(start 93.785 90.515)
		(end 89.715 90.515)
		(width 0.19)
		(layer "F.Cu")
		(net 1258)
	)
	(segment
		(start 98.695532 85.385)
		(end 98.695532 84.765)
		(width 0.19)
		(layer "F.Cu")
		(net 1258)
	)
	(via
		(at 93.9 90.4)
		(size 0.45)
		(drill 0.1)
		(layers "F.Cu" "B.Cu")
		(net 1258)
	)
	(via
		(at 98.580532 84.65)
		(size 0.45)
		(drill 0.1)
		(layers "F.Cu" "B.Cu")
		(net 1258)
	)
	(segment
		(start 98.35861 91.185585)
		(end 97.470358 90.297333)
		(width 0.15)
		(layer "In7.Cu")
		(net 1258)
	)
	(segment
		(start 97.115966 88.634796)
		(end 97.843359 89.362189)
		(width 0.15)
		(layer "In7.Cu")
		(net 1258)
	)
	(segment
		(start 93.9 90.4)
		(end 94.0625 90.5625)
		(width 0.15)
		(layer "In7.Cu")
		(net 1258)
	)
	(segment
		(start 95.0125 87.206956)
		(end 95.0125 86.693044)
		(width 0.15)
		(layer "In7.Cu")
		(net 1258)
	)
	(segment
		(start 98.096746 85.591218)
		(end 98.227753 85.722225)
		(width 0.15)
		(layer "In7.Cu")
		(net 1258)
	)
	(segment
		(start 98.227753 85.877788)
		(end 98.188863 85.91668)
		(width 0.15)
		(layer "In7.Cu")
		(net 1258)
	)
	(segment
		(start 98.135637 85.396764)
		(end 98.096746 85.435654)
		(width 0.15)
		(layer "In7.Cu")
		(net 1258)
	)
	(segment
		(start 95.593044 86.1125)
		(end 97.993044 86.1125)
		(width 0.15)
		(layer "In7.Cu")
		(net 1258)
	)
	(segment
		(start 97.843359 89.362189)
		(end 97.940587 89.459417)
		(width 0.15)
		(layer "In7.Cu")
		(net 1258)
	)
	(segment
		(start 95.32 92.338668)
		(end 95.45 92.338668)
		(width 0.15)
		(layer "In7.Cu")
		(net 1258)
	)
	(segment
		(start 98.389596 88.815945)
		(end 98.481521 88.724023)
		(width 0.15)
		(layer "In7.Cu")
		(net 1258)
	)
	(segment
		(start 97.28651 90.113485)
		(end 97.286511 90.11349)
		(width 0.15)
		(layer "In7.Cu")
		(net 1258)
	)
	(segment
		(start 98.743032 88.462512)
		(end 98.743032 88.1)
		(width 0.15)
		(layer "In7.Cu")
		(net 1258)
	)
	(segment
		(start 98.743032 87.837488)
		(end 98.443044 87.5375)
		(width 0.15)
		(layer "In7.Cu")
		(net 1258)
	)
	(segment
		(start 94.0625 90.5625)
		(end 94.8 90.5625)
		(width 0.15)
		(layer "In7.Cu")
		(net 1258)
	)
	(segment
		(start 95.97 90.5625)
		(end 96.1 90.5625)
		(width 0.15)
		(layer "In7.Cu")
		(net 1258)
	)
	(segment
		(start 97.940587 89.459417)
		(end 97.940585 89.459414)
		(width 0.15)
		(layer "In7.Cu")
		(net 1258)
	)
	(segment
		(start 97.286511 90.11349)
		(end 97.189285 90.016261)
		(width 0.15)
		(layer "In7.Cu")
		(net 1258)
	)
	(segment
		(start 99.277812 90.266311)
		(end 98.389596 89.378095)
		(width 0.15)
		(layer "In7.Cu")
		(net 1258)
	)
	(segment
		(start 95.343044 87.5375)
		(end 95.0125 87.206956)
		(width 0.15)
		(layer "In7.Cu")
		(net 1258)
	)
	(segment
		(start 98.743032 84.8125)
		(end 98.743032 85.362512)
		(width 0.15)
		(layer "In7.Cu")
		(net 1258)
	)
	(segment
		(start 98.580532 84.65)
		(end 98.743032 84.8125)
		(width 0.15)
		(layer "In7.Cu")
		(net 1258)
	)
	(segment
		(start 98.124432 89.643262)
		(end 99.012648 90.531477)
		(width 0.15)
		(layer "In7.Cu")
		(net 1258)
	)
	(segment
		(start 95.0125 86.693044)
		(end 95.593044 86.1125)
		(width 0.15)
		(layer "In7.Cu")
		(net 1258)
	)
	(segment
		(start 97.189285 90.016261)
		(end 96.461891 89.28887)
		(width 0.15)
		(layer "In7.Cu")
		(net 1258)
	)
	(segment
		(start 97.205194 90.5625)
		(end 98.093445 91.450751)
		(width 0.15)
		(layer "In7.Cu")
		(net 1258)
	)
	(segment
		(start 98.481521 88.724023)
		(end 98.743032 88.462512)
		(width 0.15)
		(layer "In7.Cu")
		(net 1258)
	)
	(segment
		(start 98.743032 88.1)
		(end 98.743032 87.837488)
		(width 0.15)
		(layer "In7.Cu")
		(net 1258)
	)
	(segment
		(start 98.266687 91.450751)
		(end 98.35861 91.358827)
		(width 0.15)
		(layer "In7.Cu")
		(net 1258)
	)
	(segment
		(start 98.188863 85.91668)
		(end 97.993044 86.1125)
		(width 0.15)
		(layer "In7.Cu")
		(net 1258)
	)
	(segment
		(start 98.422208 85.527772)
		(end 98.2912 85.396764)
		(width 0.15)
		(layer "In7.Cu")
		(net 1258)
	)
	(segment
		(start 95.5725 92.216168)
		(end 95.5725 90.96)
		(width 0.15)
		(layer "In7.Cu")
		(net 1258)
	)
	(segment
		(start 97.940585 89.459414)
		(end 98.124432 89.643262)
		(width 0.15)
		(layer "In7.Cu")
		(net 1258)
	)
	(segment
		(start 98.443044 87.5375)
		(end 95.343044 87.5375)
		(width 0.15)
		(layer "In7.Cu")
		(net 1258)
	)
	(segment
		(start 99.185889 90.531477)
		(end 99.277812 90.439553)
		(width 0.15)
		(layer "In7.Cu")
		(net 1258)
	)
	(segment
		(start 98.743032 85.362512)
		(end 98.577772 85.527772)
		(width 0.15)
		(layer "In7.Cu")
		(net 1258)
	)
	(segment
		(start 96.461893 88.726718)
		(end 96.553816 88.634796)
		(width 0.15)
		(layer "In7.Cu")
		(net 1258)
	)
	(segment
		(start 95.1975 90.96)
		(end 95.1975 92.216168)
		(width 0.15)
		(layer "In7.Cu")
		(net 1258)
	)
	(segment
		(start 96.1 90.5625)
		(end 96.643044 90.5625)
		(width 0.15)
		(layer "In7.Cu")
		(net 1258)
	)
	(segment
		(start 97.470358 90.297333)
		(end 97.28651 90.113485)
		(width 0.15)
		(layer "In7.Cu")
		(net 1258)
	)
	(arc
		(start 98.096746 85.435654)
		(mid 98.064528 85.513436)
		(end 98.096746 85.591218)
		(width 0.15)
		(layer "In7.Cu")
		(net 1258)
	)
	(arc
		(start 96.553816 88.634796)
		(mid 96.834891 88.518371)
		(end 97.115966 88.634796)
		(width 0.15)
		(layer "In7.Cu")
		(net 1258)
	)
	(arc
		(start 95.45 92.338668)
		(mid 95.536621 92.302789)
		(end 95.5725 92.216168)
		(width 0.15)
		(layer "In7.Cu")
		(net 1258)
	)
	(arc
		(start 98.389596 89.378095)
		(mid 98.273171 89.09702)
		(end 98.389596 88.815945)
		(width 0.15)
		(layer "In7.Cu")
		(net 1258)
	)
	(arc
		(start 96.461891 89.28887)
		(mid 96.345466 89.007795)
		(end 96.461893 88.726718)
		(width 0.15)
		(layer "In7.Cu")
		(net 1258)
	)
	(arc
		(start 98.093445 91.450751)
		(mid 98.180066 91.486631)
		(end 98.266687 91.450751)
		(width 0.15)
		(layer "In7.Cu")
		(net 1258)
	)
	(arc
		(start 99.012648 90.531477)
		(mid 99.099269 90.567356)
		(end 99.185889 90.531477)
		(width 0.15)
		(layer "In7.Cu")
		(net 1258)
	)
	(arc
		(start 98.227753 85.722225)
		(mid 98.259971 85.800007)
		(end 98.227753 85.877788)
		(width 0.15)
		(layer "In7.Cu")
		(net 1258)
	)
	(arc
		(start 95.1975 92.216168)
		(mid 95.233379 92.302789)
		(end 95.32 92.338668)
		(width 0.15)
		(layer "In7.Cu")
		(net 1258)
	)
	(arc
		(start 99.277812 90.439553)
		(mid 99.313692 90.352932)
		(end 99.277812 90.266311)
		(width 0.15)
		(layer "In7.Cu")
		(net 1258)
	)
	(arc
		(start 98.2912 85.396764)
		(mid 98.213419 85.364545)
		(end 98.135637 85.396764)
		(width 0.15)
		(layer "In7.Cu")
		(net 1258)
	)
	(arc
		(start 95.5725 90.96)
		(mid 95.688925 90.678925)
		(end 95.97 90.5625)
		(width 0.15)
		(layer "In7.Cu")
		(net 1258)
	)
	(arc
		(start 94.8 90.5625)
		(mid 95.081075 90.678925)
		(end 95.1975 90.96)
		(width 0.15)
		(layer "In7.Cu")
		(net 1258)
	)
	(arc
		(start 98.35861 91.358827)
		(mid 98.39449 91.272206)
		(end 98.35861 91.185585)
		(width 0.15)
		(layer "In7.Cu")
		(net 1258)
	)
	(arc
		(start 96.643044 90.5625)
		(mid 96.924119 90.446075)
		(end 97.205194 90.5625)
		(width 0.15)
		(layer "In7.Cu")
		(net 1258)
	)
	(arc
		(start 98.577772 85.527772)
		(mid 98.49999 85.55999)
		(end 98.422208 85.527772)
		(width 0.15)
		(layer "In7.Cu")
		(net 1258)
	)
	(segment
		(start 99.180532 72.64)
		(end 99.180532 72.65)
		(width 0.19)
		(layer "F.Cu")
		(net 1259)
	)
	(segment
		(start 99.065532 73.385)
		(end 99.330532 73.65)
		(width 0.19)
		(layer "F.Cu")
		(net 1259)
	)
	(segment
		(start 89.92 93.415)
		(end 92.685 93.415)
		(width 0.19)
		(layer "F.Cu")
		(net 1259)
	)
	(segment
		(start 99.065532 72.765)
		(end 99.065532 73.385)
		(width 0.19)
		(layer "F.Cu")
		(net 1259)
	)
	(segment
		(start 92.685 93.415)
		(end 92.8 93.3)
		(width 0.19)
		(layer "F.Cu")
		(net 1259)
	)
	(segment
		(start 99.180532 72.65)
		(end 99.065532 72.765)
		(width 0.19)
		(layer "F.Cu")
		(net 1259)
	)
	(segment
		(start 89.58 93.1)
		(end 89.605 93.1)
		(width 0.19)
		(layer "F.Cu")
		(net 1259)
	)
	(segment
		(start 89.605 93.1)
		(end 89.92 93.415)
		(width 0.19)
		(layer "F.Cu")
		(net 1259)
	)
	(via
		(at 92.8 93.3)
		(size 0.45)
		(drill 0.1)
		(layers "F.Cu" "B.Cu")
		(net 1259)
	)
	(via
		(at 99.180532 72.64)
		(size 0.45)
		(drill 0.1)
		(layers "F.Cu" "B.Cu")
		(net 1259)
	)
	(segment
		(start 98.647266 73.832004)
		(end 98.343211 73.527949)
		(width 0.15)
		(layer "In7.Cu")
		(net 1259)
	)
	(segment
		(start 91.527772 90.777772)
		(end 91.747228 90.997228)
		(width 0.15)
		(layer "In7.Cu")
		(net 1259)
	)
	(segment
		(start 95.8625 75.443044)
		(end 95.8625 75.943044)
		(width 0.15)
		(layer "In7.Cu")
		(net 1259)
	)
	(segment
		(start 92.6625 92.106956)
		(end 93.4125 92.856956)
		(width 0.15)
		(layer "In7.Cu")
		(net 1259)
	)
	(segment
		(start 95.8625 75.943044)
		(end 92.7625 79.043044)
		(width 0.15)
		(layer "In7.Cu")
		(net 1259)
	)
	(segment
		(start 91.0625 86.643044)
		(end 91.0625 90.056956)
		(width 0.15)
		(layer "In7.Cu")
		(net 1259)
	)
	(segment
		(start 98.343044 74.3625)
		(end 96.943044 74.3625)
		(width 0.15)
		(layer "In7.Cu")
		(net 1259)
	)
	(segment
		(start 92.6625 91.656956)
		(end 92.6625 92.106956)
		(width 0.15)
		(layer "In7.Cu")
		(net 1259)
	)
	(segment
		(start 93.4125 93.193044)
		(end 93.143044 93.4625)
		(width 0.15)
		(layer "In7.Cu")
		(net 1259)
	)
	(segment
		(start 91.747228 90.997228)
		(end 92.002772 90.997228)
		(width 0.15)
		(layer "In7.Cu")
		(net 1259)
	)
	(segment
		(start 92.9625 93.4625)
		(end 92.8 93.3)
		(width 0.15)
		(layer "In7.Cu")
		(net 1259)
	)
	(segment
		(start 99.018032 71.876424)
		(end 99.356956 71.5375)
		(width 0.15)
		(layer "In7.Cu")
		(net 1259)
	)
	(segment
		(start 92.002772 90.997228)
		(end 92.6625 91.656956)
		(width 0.15)
		(layer "In7.Cu")
		(net 1259)
	)
	(segment
		(start 96.943044 74.3625)
		(end 95.8625 75.443044)
		(width 0.15)
		(layer "In7.Cu")
		(net 1259)
	)
	(segment
		(start 91.0625 90.056956)
		(end 91.527772 90.522228)
		(width 0.15)
		(layer "In7.Cu")
		(net 1259)
	)
	(segment
		(start 99.212953 73.492592)
		(end 100.0625 72.643044)
		(width 0.15)
		(layer "In7.Cu")
		(net 1259)
	)
	(segment
		(start 98.647266 74.058278)
		(end 98.343044 74.3625)
		(width 0.15)
		(layer "In7.Cu")
		(net 1259)
	)
	(segment
		(start 98.343212 73.301673)
		(end 98.39978 73.245106)
		(width 0.15)
		(layer "In7.Cu")
		(net 1259)
	)
	(segment
		(start 99.156386 73.549161)
		(end 99.212953 73.492592)
		(width 0.15)
		(layer "In7.Cu")
		(net 1259)
	)
	(segment
		(start 100.0625 71.856956)
		(end 100.0625 72.643044)
		(width 0.15)
		(layer "In7.Cu")
		(net 1259)
	)
	(segment
		(start 92.7625 84.943044)
		(end 91.0625 86.643044)
		(width 0.15)
		(layer "In7.Cu")
		(net 1259)
	)
	(segment
		(start 93.4125 92.856956)
		(end 93.4125 93.193044)
		(width 0.15)
		(layer "In7.Cu")
		(net 1259)
	)
	(segment
		(start 99.018032 72.4875)
		(end 99.018032 71.876424)
		(width 0.15)
		(layer "In7.Cu")
		(net 1259)
	)
	(segment
		(start 99.356956 71.5375)
		(end 99.743044 71.5375)
		(width 0.15)
		(layer "In7.Cu")
		(net 1259)
	)
	(segment
		(start 99.170532 72.64)
		(end 99.018032 72.4875)
		(width 0.15)
		(layer "In7.Cu")
		(net 1259)
	)
	(segment
		(start 92.7625 79.043044)
		(end 92.7625 84.943044)
		(width 0.15)
		(layer "In7.Cu")
		(net 1259)
	)
	(segment
		(start 99.743044 71.5375)
		(end 100.0625 71.856956)
		(width 0.15)
		(layer "In7.Cu")
		(net 1259)
	)
	(segment
		(start 99.180532 72.64)
		(end 99.170532 72.64)
		(width 0.15)
		(layer "In7.Cu")
		(net 1259)
	)
	(segment
		(start 98.626054 73.245106)
		(end 98.93011 73.549162)
		(width 0.15)
		(layer "In7.Cu")
		(net 1259)
	)
	(segment
		(start 91.527772 90.522228)
		(end 91.527772 90.777772)
		(width 0.15)
		(layer "In7.Cu")
		(net 1259)
	)
	(segment
		(start 93.143044 93.4625)
		(end 92.9625 93.4625)
		(width 0.15)
		(layer "In7.Cu")
		(net 1259)
	)
	(arc
		(start 98.39978 73.245106)
		(mid 98.512917 73.198243)
		(end 98.626054 73.245106)
		(width 0.15)
		(layer "In7.Cu")
		(net 1259)
	)
	(arc
		(start 98.647266 74.058278)
		(mid 98.694129 73.945141)
		(end 98.647266 73.832004)
		(width 0.15)
		(layer "In7.Cu")
		(net 1259)
	)
	(arc
		(start 98.343211 73.527949)
		(mid 98.296349 73.41481)
		(end 98.343212 73.301673)
		(width 0.15)
		(layer "In7.Cu")
		(net 1259)
	)
	(arc
		(start 98.93011 73.549162)
		(mid 99.043248 73.596025)
		(end 99.156386 73.549161)
		(width 0.15)
		(layer "In7.Cu")
		(net 1259)
	)
	(segment
		(start 89.92 96.215)
		(end 93.485 96.215)
		(width 0.19)
		(layer "F.Cu")
		(net 1260)
	)
	(segment
		(start 98.430532 82.65)
		(end 98.695532 82.385)
		(width 0.19)
		(layer "F.Cu")
		(net 1260)
	)
	(segment
		(start 98.695532 82.385)
		(end 98.695532 81.765)
		(width 0.19)
		(layer "F.Cu")
		(net 1260)
	)
	(segment
		(start 98.695532 81.765)
		(end 98.580532 81.65)
		(width 0.19)
		(layer "F.Cu")
		(net 1260)
	)
	(segment
		(start 89.605 95.9)
		(end 89.92 96.215)
		(width 0.19)
		(layer "F.Cu")
		(net 1260)
	)
	(segment
		(start 93.485 96.215)
		(end 93.6 96.1)
		(width 0.19)
		(layer "F.Cu")
		(net 1260)
	)
	(via
		(at 98.580532 81.65)
		(size 0.45)
		(drill 0.1)
		(layers "F.Cu" "B.Cu")
		(net 1260)
	)
	(via
		(at 93.6 96.1)
		(size 0.45)
		(drill 0.1)
		(layers "F.Cu" "B.Cu")
		(net 1260)
	)
	(segment
		(start 96.825313 94.974686)
		(end 97.749051 95.898423)
		(width 0.15)
		(layer "In7.Cu")
		(net 1260)
	)
	(segment
		(start 99.9025 91.24)
		(end 99.85735 91.24)
		(width 0.15)
		(layer "In7.Cu")
		(net 1260)
	)
	(segment
		(start 96.171237 95.62876)
		(end 96.741388 96.198911)
		(width 0.15)
		(layer "In7.Cu")
		(net 1260)
	)
	(segment
		(start 96.820847 93.13174)
		(end 97.744555 94.055448)
		(width 0.15)
		(layer "In7.Cu")
		(net 1260)
	)
	(segment
		(start 96.16677 93.785816)
		(end 97.090477 94.709524)
		(width 0.15)
		(layer "In7.Cu")
		(net 1260)
	)
	(segment
		(start 95.901624 94.050993)
		(end 96.825317 94.974686)
		(width 0.15)
		(layer "In7.Cu")
		(net 1260)
	)
	(segment
		(start 97.744551 94.055448)
		(end 98.668259 94.979155)
		(width 0.15)
		(layer "In7.Cu")
		(net 1260)
	)
	(segment
		(start 96.089923 96.077772)
		(end 96.476226 96.464075)
		(width 0.15)
		(layer "In7.Cu")
		(net 1260)
	)
	(segment
		(start 96.825317 94.974686)
		(end 96.825313 94.974686)
		(width 0.15)
		(layer "In7.Cu")
		(net 1260)
	)
	(segment
		(start 97.090476 94.709521)
		(end 98.014214 95.633259)
		(width 0.15)
		(layer "In7.Cu")
		(net 1260)
	)
	(segment
		(start 95.247547 94.705069)
		(end 96.171239 95.628762)
		(width 0.15)
		(layer "In7.Cu")
		(net 1260)
	)
	(segment
		(start 99.4625 86.656956)
		(end 99.4625 85.343044)
		(width 0.15)
		(layer "In7.Cu")
		(net 1260)
	)
	(segment
		(start 98.285487 93.320057)
		(end 100.0625 91.543044)
		(width 0.15)
		(layer "In7.Cu")
		(net 1260)
	)
	(segment
		(start 95.343044 96.2625)
		(end 95.527772 96.077772)
		(width 0.15)
		(layer "In7.Cu")
		(net 1260)
	)
	(segment
		(start 99.4625 85.343044)
		(end 100.0625 84.743044)
		(width 0.15)
		(layer "In7.Cu")
		(net 1260)
	)
	(segment
		(start 93.7625 96.2625)
		(end 95.343044 96.2625)
		(width 0.15)
		(layer "In7.Cu")
		(net 1260)
	)
	(segment
		(start 100.0625 90.68)
		(end 100.0625 87.256956)
		(width 0.15)
		(layer "In7.Cu")
		(net 1260)
	)
	(segment
		(start 98.841499 94.979155)
		(end 98.933422 94.887231)
		(width 0.15)
		(layer "In7.Cu")
		(net 1260)
	)
	(segment
		(start 96.649465 96.464075)
		(end 96.741388 96.372151)
		(width 0.15)
		(layer "In7.Cu")
		(net 1260)
	)
	(segment
		(start 98.193562 93.411979)
		(end 98.285487 93.320057)
		(width 0.15)
		(layer "In7.Cu")
		(net 1260)
	)
	(segment
		(start 99.69735 91.08)
		(end 99.69735 91)
		(width 0.15)
		(layer "In7.Cu")
		(net 1260)
	)
	(segment
		(start 98.933422 94.713991)
		(end 98.193562 93.974131)
		(width 0.15)
		(layer "In7.Cu")
		(net 1260)
	)
	(segment
		(start 97.090476 94.709521)
		(end 97.090477 94.709524)
		(width 0.15)
		(layer "In7.Cu")
		(net 1260)
	)
	(segment
		(start 99.85735 90.84)
		(end 99.9025 90.84)
		(width 0.15)
		(layer "In7.Cu")
		(net 1260)
	)
	(segment
		(start 100.0625 87.256956)
		(end 99.4625 86.656956)
		(width 0.15)
		(layer "In7.Cu")
		(net 1260)
	)
	(segment
		(start 97.744555 94.055448)
		(end 97.744551 94.055448)
		(width 0.15)
		(layer "In7.Cu")
		(net 1260)
	)
	(segment
		(start 98.743032 81.8125)
		(end 98.580532 81.65)
		(width 0.15)
		(layer "In7.Cu")
		(net 1260)
	)
	(segment
		(start 100.0625 84.056956)
		(end 98.743032 82.737488)
		(width 0.15)
		(layer "In7.Cu")
		(net 1260)
	)
	(segment
		(start 95.247547 94.142917)
		(end 95.339472 94.050993)
		(width 0.15)
		(layer "In7.Cu")
		(net 1260)
	)
	(segment
		(start 96.171237 95.62876)
		(end 96.171239 95.628762)
		(width 0.15)
		(layer "In7.Cu")
		(net 1260)
	)
	(segment
		(start 93.6 96.1)
		(end 93.7625 96.2625)
		(width 0.15)
		(layer "In7.Cu")
		(net 1260)
	)
	(segment
		(start 98.743032 82.737488)
		(end 98.743032 81.8125)
		(width 0.15)
		(layer "In7.Cu")
		(net 1260)
	)
	(segment
		(start 100.0625 84.743044)
		(end 100.0625 84.056956)
		(width 0.15)
		(layer "In7.Cu")
		(net 1260)
	)
	(segment
		(start 96.16677 93.223664)
		(end 96.258695 93.13174)
		(width 0.15)
		(layer "In7.Cu")
		(net 1260)
	)
	(segment
		(start 100.0625 91.543044)
		(end 100.0625 91.4)
		(width 0.15)
		(layer "In7.Cu")
		(net 1260)
	)
	(segment
		(start 97.922291 95.898423)
		(end 98.014214 95.806499)
		(width 0.15)
		(layer "In7.Cu")
		(net 1260)
	)
	(arc
		(start 99.9025 90.84)
		(mid 100.015637 90.793137)
		(end 100.0625 90.68)
		(width 0.15)
		(layer "In7.Cu")
		(net 1260)
	)
	(arc
		(start 96.476226 96.464075)
		(mid 96.562846 96.499953)
		(end 96.649465 96.464075)
		(width 0.15)
		(layer "In7.Cu")
		(net 1260)
	)
	(arc
		(start 97.749051 95.898423)
		(mid 97.835671 95.934302)
		(end 97.922291 95.898423)
		(width 0.15)
		(layer "In7.Cu")
		(net 1260)
	)
	(arc
		(start 98.193562 93.974131)
		(mid 98.077137 93.693055)
		(end 98.193562 93.411979)
		(width 0.15)
		(layer "In7.Cu")
		(net 1260)
	)
	(arc
		(start 99.85735 91.24)
		(mid 99.744213 91.193137)
		(end 99.69735 91.08)
		(width 0.15)
		(layer "In7.Cu")
		(net 1260)
	)
	(arc
		(start 95.527772 96.077772)
		(mid 95.808847 95.961347)
		(end 96.089923 96.077772)
		(width 0.15)
		(layer "In7.Cu")
		(net 1260)
	)
	(arc
		(start 98.668259 94.979155)
		(mid 98.754879 95.015034)
		(end 98.841499 94.979155)
		(width 0.15)
		(layer "In7.Cu")
		(net 1260)
	)
	(arc
		(start 95.339472 94.050993)
		(mid 95.620547 93.934569)
		(end 95.901624 94.050993)
		(width 0.15)
		(layer "In7.Cu")
		(net 1260)
	)
	(arc
		(start 98.933422 94.887231)
		(mid 98.969301 94.800611)
		(end 98.933422 94.713991)
		(width 0.15)
		(layer "In7.Cu")
		(net 1260)
	)
	(arc
		(start 99.69735 91)
		(mid 99.744213 90.886863)
		(end 99.85735 90.84)
		(width 0.15)
		(layer "In7.Cu")
		(net 1260)
	)
	(arc
		(start 98.014214 95.806499)
		(mid 98.050093 95.719879)
		(end 98.014214 95.633259)
		(width 0.15)
		(layer "In7.Cu")
		(net 1260)
	)
	(arc
		(start 96.16677 93.785816)
		(mid 96.050344 93.504741)
		(end 96.16677 93.223664)
		(width 0.15)
		(layer "In7.Cu")
		(net 1260)
	)
	(arc
		(start 100.0625 91.4)
		(mid 100.015637 91.286863)
		(end 99.9025 91.24)
		(width 0.15)
		(layer "In7.Cu")
		(net 1260)
	)
	(arc
		(start 96.258695 93.13174)
		(mid 96.53977 93.015316)
		(end 96.820847 93.13174)
		(width 0.15)
		(layer "In7.Cu")
		(net 1260)
	)
	(arc
		(start 96.741388 96.372151)
		(mid 96.777267 96.285531)
		(end 96.741388 96.198911)
		(width 0.15)
		(layer "In7.Cu")
		(net 1260)
	)
	(arc
		(start 95.247547 94.705069)
		(mid 95.131121 94.423994)
		(end 95.247547 94.142917)
		(width 0.15)
		(layer "In7.Cu")
		(net 1260)
	)
	(segment
		(start 89.92 99.115)
		(end 92.685 99.115)
		(width 0.19)
		(layer "F.Cu")
		(net 1261)
	)
	(segment
		(start 89.605 98.8)
		(end 89.92 99.115)
		(width 0.19)
		(layer "F.Cu")
		(net 1261)
	)
	(segment
		(start 98.695532 75.815)
		(end 98.580532 75.7)
		(width 0.19)
		(layer "F.Cu")
		(net 1261)
	)
	(segment
		(start 89.58 98.8)
		(end 89.605 98.8)
		(width 0.19)
		(layer "F.Cu")
		(net 1261)
	)
	(segment
		(start 98.430532 76.65)
		(end 98.695532 76.385)
		(width 0.19)
		(layer "F.Cu")
		(net 1261)
	)
	(segment
		(start 98.695532 76.385)
		(end 98.695532 75.815)
		(width 0.19)
		(layer "F.Cu")
		(net 1261)
	)
	(segment
		(start 92.685 99.115)
		(end 92.8 99)
		(width 0.19)
		(layer "F.Cu")
		(net 1261)
	)
	(via
		(at 92.8 99)
		(size 0.45)
		(drill 0.1)
		(layers "F.Cu" "B.Cu")
		(net 1261)
	)
	(via
		(at 98.580532 75.7)
		(size 0.45)
		(drill 0.1)
		(layers "F.Cu" "B.Cu")
		(net 1261)
	)
	(segment
		(start 93.954505 86.551036)
		(end 94.04643 86.459114)
		(width 0.15)
		(layer "In7.Cu")
		(net 1261)
	)
	(segment
		(start 94.04643 86.459114)
		(end 94.2625 86.243044)
		(width 0.15)
		(layer "In7.Cu")
		(net 1261)
	)
	(segment
		(start 94.2625 82.756956)
		(end 93.7625 82.256956)
		(width 0.15)
		(layer "In7.Cu")
		(net 1261)
	)
	(segment
		(start 93.2125 91.056956)
		(end 92.0625 89.906956)
		(width 0.15)
		(layer "In7.Cu")
		(net 1261)
	)
	(segment
		(start 98.743032 75.8625)
		(end 98.580532 75.7)
		(width 0.15)
		(layer "In7.Cu")
		(net 1261)
	)
	(segment
		(start 93.505494 87.194505)
		(end 93.973515 87.662525)
		(width 0.15)
		(layer "In7.Cu")
		(net 1261)
	)
	(segment
		(start 95.743044 78.5625)
		(end 96.743044 78.5625)
		(width 0.15)
		(layer "In7.Cu")
		(net 1261)
	)
	(segment
		(start 92.667572 87.837972)
		(end 92.667573 87.837973)
		(width 0.15)
		(layer "In7.Cu")
		(net 1261)
	)
	(segment
		(start 92.9625 99.1625)
		(end 92.8 99)
		(width 0.15)
		(layer "In7.Cu")
		(net 1261)
	)
	(segment
		(start 92.6625 96.604984)
		(end 92.6625 96.856956)
		(width 0.15)
		(layer "In7.Cu")
		(net 1261)
	)
	(segment
		(start 92.4825 95.974984)
		(end 92.460226 95.974984)
		(width 0.15)
		(layer "In7.Cu")
		(net 1261)
	)
	(segment
		(start 94.238678 87.397361)
		(end 93.954505 87.113188)
		(width 0.15)
		(layer "In7.Cu")
		(net 1261)
	)
	(segment
		(start 94.2625 92.656956)
		(end 93.943044 92.3375)
		(width 0.15)
		(layer "In7.Cu")
		(net 1261)
	)
	(segment
		(start 94.146755 87.662525)
		(end 94.238678 87.570601)
		(width 0.15)
		(layer "In7.Cu")
		(net 1261)
	)
	(segment
		(start 92.6625 95.743044)
		(end 94.2625 94.143044)
		(width 0.15)
		(layer "In7.Cu")
		(net 1261)
	)
	(segment
		(start 92.6625 96.856956)
		(end 93.6625 97.856956)
		(width 0.15)
		(layer "In7.Cu")
		(net 1261)
	)
	(segment
		(start 93.2125 91.906956)
		(end 93.2125 91.056956)
		(width 0.15)
		(layer "In7.Cu")
		(net 1261)
	)
	(segment
		(start 93.6625 97.856956)
		(end 93.6625 98.743044)
		(width 0.15)
		(layer "In7.Cu")
		(net 1261)
	)
	(segment
		(start 94.2625 94.143044)
		(end 94.2625 92.656956)
		(width 0.15)
		(layer "In7.Cu")
		(net 1261)
	)
	(segment
		(start 93.943044 92.3375)
		(end 93.643044 92.3375)
		(width 0.15)
		(layer "In7.Cu")
		(net 1261)
	)
	(segment
		(start 92.0625 89.906956)
		(end 92.0625 88.443044)
		(width 0.15)
		(layer "In7.Cu")
		(net 1261)
	)
	(segment
		(start 93.7625 80.543044)
		(end 95.743044 78.5625)
		(width 0.15)
		(layer "In7.Cu")
		(net 1261)
	)
	(segment
		(start 94.2625 86.243044)
		(end 94.2625 82.756956)
		(width 0.15)
		(layer "In7.Cu")
		(net 1261)
	)
	(segment
		(start 93.643044 92.3375)
		(end 93.2125 91.906956)
		(width 0.15)
		(layer "In7.Cu")
		(net 1261)
	)
	(segment
		(start 96.743044 78.5625)
		(end 98.743032 76.562512)
		(width 0.15)
		(layer "In7.Cu")
		(net 1261)
	)
	(segment
		(start 93.505499 87.194506)
		(end 93.505494 87.194505)
		(width 0.15)
		(layer "In7.Cu")
		(net 1261)
	)
	(segment
		(start 92.0625 88.443044)
		(end 92.667572 87.837972)
		(width 0.15)
		(layer "In7.Cu")
		(net 1261)
	)
	(segment
		(start 92.524867 86.959875)
		(end 92.616792 86.867951)
		(width 0.15)
		(layer "In7.Cu")
		(net 1261)
	)
	(segment
		(start 93.243044 99.1625)
		(end 92.9625 99.1625)
		(width 0.15)
		(layer "In7.Cu")
		(net 1261)
	)
	(segment
		(start 93.6625 98.743044)
		(end 93.243044 99.1625)
		(width 0.15)
		(layer "In7.Cu")
		(net 1261)
	)
	(segment
		(start 93.178944 86.867951)
		(end 93.505499 87.194506)
		(width 0.15)
		(layer "In7.Cu")
		(net 1261)
	)
	(segment
		(start 92.460226 96.424984)
		(end 92.4825 96.424984)
		(width 0.15)
		(layer "In7.Cu")
		(net 1261)
	)
	(segment
		(start 98.743032 76.562512)
		(end 98.743032 75.8625)
		(width 0.15)
		(layer "In7.Cu")
		(net 1261)
	)
	(segment
		(start 92.6625 95.794984)
		(end 92.6625 95.743044)
		(width 0.15)
		(layer "In7.Cu")
		(net 1261)
	)
	(segment
		(start 93.7625 82.256956)
		(end 93.7625 80.543044)
		(width 0.15)
		(layer "In7.Cu")
		(net 1261)
	)
	(segment
		(start 92.280226 96.154984)
		(end 92.280226 96.244984)
		(width 0.15)
		(layer "In7.Cu")
		(net 1261)
	)
	(segment
		(start 92.667573 87.664733)
		(end 92.524867 87.522027)
		(width 0.15)
		(layer "In7.Cu")
		(net 1261)
	)
	(arc
		(start 94.238678 87.570601)
		(mid 94.274557 87.483981)
		(end 94.238678 87.397361)
		(width 0.15)
		(layer "In7.Cu")
		(net 1261)
	)
	(arc
		(start 92.460226 95.974984)
		(mid 92.332947 96.027705)
		(end 92.280226 96.154984)
		(width 0.15)
		(layer "In7.Cu")
		(net 1261)
	)
	(arc
		(start 93.954505 87.113188)
		(mid 93.83808 86.832112)
		(end 93.954505 86.551036)
		(width 0.15)
		(layer "In7.Cu")
		(net 1261)
	)
	(arc
		(start 92.4825 96.424984)
		(mid 92.609779 96.477705)
		(end 92.6625 96.604984)
		(width 0.15)
		(layer "In7.Cu")
		(net 1261)
	)
	(arc
		(start 93.973515 87.662525)
		(mid 94.060135 87.698404)
		(end 94.146755 87.662525)
		(width 0.15)
		(layer "In7.Cu")
		(net 1261)
	)
	(arc
		(start 92.616792 86.867951)
		(mid 92.897867 86.751527)
		(end 93.178944 86.867951)
		(width 0.15)
		(layer "In7.Cu")
		(net 1261)
	)
	(arc
		(start 92.667573 87.837973)
		(mid 92.703453 87.751352)
		(end 92.667573 87.664733)
		(width 0.15)
		(layer "In7.Cu")
		(net 1261)
	)
	(arc
		(start 92.524867 87.522027)
		(mid 92.408443 87.24095)
		(end 92.524867 86.959875)
		(width 0.15)
		(layer "In7.Cu")
		(net 1261)
	)
	(arc
		(start 92.280226 96.244984)
		(mid 92.332947 96.372263)
		(end 92.460226 96.424984)
		(width 0.15)
		(layer "In7.Cu")
		(net 1261)
	)
	(arc
		(start 92.6625 95.794984)
		(mid 92.609779 95.922263)
		(end 92.4825 95.974984)
		(width 0.15)
		(layer "In7.Cu")
		(net 1261)
	)
	(segment
		(start 84.585 77.17337)
		(end 84.585 74.92337)
		(width 0.19)
		(layer "F.Cu")
		(net 1262)
	)
	(segment
		(start 103.065532 79.385)
		(end 103.065532 79.203902)
		(width 0.19)
		(layer "F.Cu")
		(net 1262)
	)
	(segment
		(start 81.415 74.62337)
		(end 81.415 74.98)
		(width 0.19)
		(layer "F.Cu")
		(net 1262)
	)
	(segment
		(start 103.065532 79.203902)
		(end 102.57663 78.715)
		(width 0.19)
		(layer "F.Cu")
		(net 1262)
	)
	(segment
		(start 81.415 74.98)
		(end 81.1 75.295)
		(width 0.19)
		(layer "F.Cu")
		(net 1262)
	)
	(segment
		(start 81.1 75.295)
		(end 81.1 75.32)
		(width 0.19)
		(layer "F.Cu")
		(net 1262)
	)
	(segment
		(start 83.52663 73.865)
		(end 82.17337 73.865)
		(width 0.19)
		(layer "F.Cu")
		(net 1262)
	)
	(segment
		(start 86.12663 78.715)
		(end 84.585 77.17337)
		(width 0.19)
		(layer "F.Cu")
		(net 1262)
	)
	(segment
		(start 103.330532 79.65)
		(end 103.065532 79.385)
		(width 0.19)
		(layer "F.Cu")
		(net 1262)
	)
	(segment
		(start 84.585 74.92337)
		(end 83.52663 73.865)
		(width 0.19)
		(layer "F.Cu")
		(net 1262)
	)
	(segment
		(start 82.17337 73.865)
		(end 81.415 74.62337)
		(width 0.19)
		(layer "F.Cu")
		(net 1262)
	)
	(segment
		(start 102.57663 78.715)
		(end 86.12663 78.715)
		(width 0.19)
		(layer "F.Cu")
		(net 1262)
	)
	(segment
		(start 102.695532 79.357162)
		(end 102.695532 79.385)
		(width 0.19)
		(layer "F.Cu")
		(net 1263)
	)
	(segment
		(start 85.39279 78.504419)
		(end 85.97337 79.085)
		(width 0.19)
		(layer "F.Cu")
		(net 1263)
	)
	(segment
		(start 85.97337 79.085)
		(end 102.42337 79.085)
		(width 0.19)
		(layer "F.Cu")
		(net 1263)
	)
	(segment
		(start 81.785 74.98)
		(end 81.785 74.77663)
		(width 0.19)
		(layer "F.Cu")
		(net 1263)
	)
	(segment
		(start 84.629116 78.080157)
		(end 84.389376 78.319896)
		(width 0.19)
		(layer "F.Cu")
		(net 1263)
	)
	(segment
		(start 84.389376 78.659307)
		(end 84.474228 78.744159)
		(width 0.19)
		(layer "F.Cu")
		(net 1263)
	)
	(segment
		(start 84.81364 78.744159)
		(end 85.053379 78.504419)
		(width 0.19)
		(layer "F.Cu")
		(net 1263)
	)
	(segment
		(start 81.785 74.77663)
		(end 82.32663 74.235)
		(width 0.19)
		(layer "F.Cu")
		(net 1263)
	)
	(segment
		(start 82.1 75.295)
		(end 81.785 74.98)
		(width 0.19)
		(layer "F.Cu")
		(net 1263)
	)
	(segment
		(start 82.32663 74.235)
		(end 83.37337 74.235)
		(width 0.19)
		(layer "F.Cu")
		(net 1263)
	)
	(segment
		(start 102.695532 79.385)
		(end 102.430532 79.65)
		(width 0.19)
		(layer "F.Cu")
		(net 1263)
	)
	(segment
		(start 102.42337 79.085)
		(end 102.695532 79.357162)
		(width 0.19)
		(layer "F.Cu")
		(net 1263)
	)
	(segment
		(start 82.1 75.32)
		(end 82.1 75.295)
		(width 0.19)
		(layer "F.Cu")
		(net 1263)
	)
	(segment
		(start 84.215 75.07663)
		(end 84.215 77.32663)
		(width 0.19)
		(layer "F.Cu")
		(net 1263)
	)
	(segment
		(start 83.37337 74.235)
		(end 84.215 75.07663)
		(width 0.19)
		(layer "F.Cu")
		(net 1263)
	)
	(segment
		(start 84.215 77.32663)
		(end 84.629116 77.740746)
		(width 0.19)
		(layer "F.Cu")
		(net 1263)
	)
	(arc
		(start 85.053379 78.504419)
		(mid 85.223084 78.434125)
		(end 85.39279 78.504419)
		(width 0.19)
		(layer "F.Cu")
		(net 1263)
	)
	(arc
		(start 84.629116 77.740746)
		(mid 84.69941 77.910452)
		(end 84.629116 78.080157)
		(width 0.19)
		(layer "F.Cu")
		(net 1263)
	)
	(arc
		(start 84.474228 78.744159)
		(mid 84.643934 78.814454)
		(end 84.81364 78.744159)
		(width 0.19)
		(layer "F.Cu")
		(net 1263)
	)
	(arc
		(start 84.389376 78.319896)
		(mid 84.319082 78.489601)
		(end 84.389376 78.659307)
		(width 0.19)
		(layer "F.Cu")
		(net 1263)
	)
	(segment
		(start 92.485 100.515)
		(end 92.6 100.4)
		(width 0.19)
		(layer "F.Cu")
		(net 1264)
	)
	(segment
		(start 117.065532 81.985)
		(end 117.180532 82.1)
		(width 0.19)
		(layer "F.Cu")
		(net 1264)
	)
	(segment
		(start 117.065532 81.415)
		(end 117.065532 81.985)
		(width 0.19)
		(layer "F.Cu")
		(net 1264)
	)
	(segment
		(start 117.330532 81.15)
		(end 117.065532 81.415)
		(width 0.19)
		(layer "F.Cu")
		(net 1264)
	)
	(segment
		(start 91.92 100.515)
		(end 92.485 100.515)
		(width 0.19)
		(layer "F.Cu")
		(net 1264)
	)
	(segment
		(start 91.605 100.2)
		(end 91.92 100.515)
		(width 0.19)
		(layer "F.Cu")
		(net 1264)
	)
	(segment
		(start 91.58 100.2)
		(end 91.605 100.2)
		(width 0.19)
		(layer "F.Cu")
		(net 1264)
	)
	(via
		(at 117.180532 82.1)
		(size 0.45)
		(drill 0.1)
		(layers "F.Cu" "B.Cu")
		(net 1264)
	)
	(via
		(at 92.6 100.4)
		(size 0.45)
		(drill 0.1)
		(layers "F.Cu" "B.Cu")
		(net 1264)
	)
	(segment
		(start 106.843044 90.1625)
		(end 103.7625 93.243044)
		(width 0.15)
		(layer "In7.Cu")
		(net 1264)
	)
	(segment
		(start 98.609416 101.33)
		(end 98.609416 101.2)
		(width 0.15)
		(layer "In7.Cu")
		(net 1264)
	)
	(segment
		(start 94.098261 100.407283)
		(end 93.943044 100.5625)
		(width 0.15)
		(layer "In7.Cu")
		(net 1264)
	)
	(segment
		(start 101.065579 100.68)
		(end 101.065579 100.55)
		(width 0.15)
		(layer "In7.Cu")
		(net 1264)
	)
	(segment
		(start 100.1125 101.4525)
		(end 98.731916 101.4525)
		(width 0.15)
		(layer "In7.Cu")
		(net 1264)
	)
	(segment
		(start 98.123044 100.040599)
		(end 97.993044 100.040599)
		(width 0.15)
		(layer "In7.Cu")
		(net 1264)
	)
	(segment
		(start 100.3875 102.3775)
		(end 100.668079 102.3775)
		(width 0.15)
		(layer "In7.Cu")
		(net 1264)
	)
	(segment
		(start 103.7625 93.243044)
		(end 103.7625 102.256956)
		(width 0.15)
		(layer "In7.Cu")
		(net 1264)
	)
	(segment
		(start 100.3875 103.6775)
		(end 100.668079 103.6775)
		(width 0.15)
		(layer "In7.Cu")
		(net 1264)
	)
	(segment
		(start 98.609416 106.53)
		(end 98.609416 106.4)
		(width 0.15)
		(layer "In7.Cu")
		(net 1264)
	)
	(segment
		(start 100.3875 106.2775)
		(end 100.668079 106.2775)
		(width 0.15)
		(layer "In7.Cu")
		(net 1264)
	)
	(segment
		(start 100.1125 102.7525)
		(end 98.731916 102.7525)
		(width 0.15)
		(layer "In7.Cu")
		(net 1264)
	)
	(segment
		(start 101.068084 106.6525)
		(end 100.51 106.6525)
		(width 0.15)
		(layer "In7.Cu")
		(net 1264)
	)
	(segment
		(start 100.668079 102.7525)
		(end 100.3875 102.7525)
		(width 0.15)
		(layer "In7.Cu")
		(net 1264)
	)
	(segment
		(start 100.1125 103.6775)
		(end 100.3875 103.6775)
		(width 0.15)
		(layer "In7.Cu")
		(net 1264)
	)
	(segment
		(start 101.465584 107.18)
		(end 101.465584 107.05)
		(width 0.15)
		(layer "In7.Cu")
		(net 1264)
	)
	(segment
		(start 99.059408 103.93)
		(end 99.059408 103.8)
		(width 0.15)
		(layer "In7.Cu")
		(net 1264)
	)
	(segment
		(start 97.870544 99.918099)
		(end 97.870544 98.7875)
		(width 0.15)
		(layer "In7.Cu")
		(net 1264)
	)
	(segment
		(start 98.245544 98.39)
		(end 98.245544 98.7875)
		(width 0.15)
		(layer "In7.Cu")
		(net 1264)
	)
	(segment
		(start 93.943044 100.5625)
		(end 92.7625 100.5625)
		(width 0.15)
		(layer "In7.Cu")
		(net 1264)
	)
	(segment
		(start 100.668079 105.3525)
		(end 100.3875 105.3525)
		(width 0.15)
		(layer "In7.Cu")
		(net 1264)
	)
	(segment
		(start 97.870544 98.7875)
		(end 97.870544 98.39)
		(width 0.15)
		(layer "In7.Cu")
		(net 1264)
	)
	(segment
		(start 98.609416 102.63)
		(end 98.609416 102.5)
		(width 0.15)
		(layer "In7.Cu")
		(net 1264)
	)
	(segment
		(start 98.731916 106.2775)
		(end 100.1125 106.2775)
		(width 0.15)
		(layer "In7.Cu")
		(net 1264)
	)
	(segment
		(start 104.7625 107.443044)
		(end 104.143044 108.0625)
		(width 0.15)
		(layer "In7.Cu")
		(net 1264)
	)
	(segment
		(start 100.3875 104.0525)
		(end 100.1125 104.0525)
		(width 0.15)
		(layer "In7.Cu")
		(net 1264)
	)
	(segment
		(start 100.668079 100.1525)
		(end 100.51 100.1525)
		(width 0.15)
		(layer "In7.Cu")
		(net 1264)
	)
	(segment
		(start 116.043044 81.2625)
		(end 114.6625 82.643044)
		(width 0.15)
		(layer "In7.Cu")
		(net 1264)
	)
	(segment
		(start 95.993044 98.5125)
		(end 94.098261 100.407283)
		(width 0.15)
		(layer "In7.Cu")
		(net 1264)
	)
	(segment
		(start 99.406956 98.5125)
		(end 99.293044 98.5125)
		(width 0.15)
		(layer "In7.Cu")
		(net 1264)
	)
	(segment
		(start 101.065579 104.58)
		(end 101.065579 104.45)
		(width 0.15)
		(layer "In7.Cu")
		(net 1264)
	)
	(segment
		(start 100.1125 105.3525)
		(end 98.731916 105.3525)
		(width 0.15)
		(layer "In7.Cu")
		(net 1264)
	)
	(segment
		(start 98.773044 96.734416)
		(end 98.643044 96.734416)
		(width 0.15)
		(layer "In7.Cu")
		(net 1264)
	)
	(segment
		(start 92.7625 100.5625)
		(end 92.6 100.4)
		(width 0.15)
		(layer "In7.Cu")
		(net 1264)
	)
	(segment
		(start 100.51 106.6525)
		(end 100.1125 106.6525)
		(width 0.15)
		(layer "In7.Cu")
		(net 1264)
	)
	(segment
		(start 98.245544 97.131916)
		(end 98.245544 98.39)
		(width 0.15)
		(layer "In7.Cu")
		(net 1264)
	)
	(segment
		(start 100.656956 108.0625)
		(end 100.3875 107.793044)
		(width 0.15)
		(layer "In7.Cu")
		(net 1264)
	)
	(segment
		(start 99.181908 103.6775)
		(end 100.1125 103.6775)
		(width 0.15)
		(layer "In7.Cu")
		(net 1264)
	)
	(segment
		(start 101.065579 103.28)
		(end 101.065579 103.15)
		(width 0.15)
		(layer "In7.Cu")
		(net 1264)
	)
	(segment
		(start 100.1125 104.9775)
		(end 100.3875 104.9775)
		(width 0.15)
		(layer "In7.Cu")
		(net 1264)
	)
	(segment
		(start 100.3875 101.4525)
		(end 100.1125 101.4525)
		(width 0.15)
		(layer "In7.Cu")
		(net 1264)
	)
	(segment
		(start 116.656956 81.2625)
		(end 116.043044 81.2625)
		(width 0.15)
		(layer "In7.Cu")
		(net 1264)
	)
	(segment
		(start 114.6625 82.643044)
		(end 114.6625 85.243044)
		(width 0.15)
		(layer "In7.Cu")
		(net 1264)
	)
	(segment
		(start 117.180532 82.1)
		(end 117.018032 81.9375)
		(width 0.15)
		(layer "In7.Cu")
		(net 1264)
	)
	(segment
		(start 117.018032 81.623576)
		(end 116.656956 81.2625)
		(width 0.15)
		(layer "In7.Cu")
		(net 1264)
	)
	(segment
		(start 100.1125 106.6525)
		(end 98.731916 106.6525)
		(width 0.15)
		(layer "In7.Cu")
		(net 1264)
	)
	(segment
		(start 100.3875 100.03)
		(end 100.3875 99.9)
		(width 0.15)
		(layer "In7.Cu")
		(net 1264)
	)
	(segment
		(start 100.51 107.5775)
		(end 101.068084 107.5775)
		(width 0.15)
		(layer "In7.Cu")
		(net 1264)
	)
	(segment
		(start 101.065579 105.88)
		(end 101.065579 105.75)
		(width 0.15)
		(layer "In7.Cu")
		(net 1264)
	)
	(segment
		(start 100.3875 99.493044)
		(end 99.406956 98.5125)
		(width 0.15)
		(layer "In7.Cu")
		(net 1264)
	)
	(segment
		(start 98.731916 101.0775)
		(end 100.1125 101.0775)
		(width 0.15)
		(layer "In7.Cu")
		(net 1264)
	)
	(segment
		(start 117.018032 81.9375)
		(end 117.018032 81.623576)
		(width 0.15)
		(layer "In7.Cu")
		(net 1264)
	)
	(segment
		(start 96.945544 97.131895)
		(end 96.945544 98.39)
		(width 0.15)
		(layer "In7.Cu")
		(net 1264)
	)
	(segment
		(start 100.668079 101.4525)
		(end 100.3875 101.4525)
		(width 0.15)
		(layer "In7.Cu")
		(net 1264)
	)
	(segment
		(start 100.3875 107.793044)
		(end 100.3875 107.7)
		(width 0.15)
		(layer "In7.Cu")
		(net 1264)
	)
	(segment
		(start 114.6625 85.243044)
		(end 111.043044 88.8625)
		(width 0.15)
		(layer "In7.Cu")
		(net 1264)
	)
	(segment
		(start 100.3875 105.3525)
		(end 100.1125 105.3525)
		(width 0.15)
		(layer "In7.Cu")
		(net 1264)
	)
	(segment
		(start 100.1125 106.2775)
		(end 100.3875 106.2775)
		(width 0.15)
		(layer "In7.Cu")
		(net 1264)
	)
	(segment
		(start 98.731916 104.9775)
		(end 100.1125 104.9775)
		(width 0.15)
		(layer "In7.Cu")
		(net 1264)
	)
	(segment
		(start 97.473044 96.734395)
		(end 97.343044 96.734395)
		(width 0.15)
		(layer "In7.Cu")
		(net 1264)
	)
	(segment
		(start 100.1125 101.0775)
		(end 100.51 101.0775)
		(width 0.15)
		(layer "In7.Cu")
		(net 1264)
	)
	(segment
		(start 100.3875 102.7525)
		(end 100.1125 102.7525)
		(width 0.15)
		(layer "In7.Cu")
		(net 1264)
	)
	(segment
		(start 100.668079 104.0525)
		(end 100.3875 104.0525)
		(width 0.15)
		(layer "In7.Cu")
		(net 1264)
	)
	(segment
		(start 96.823044 98.5125)
		(end 96.693044 98.5125)
		(width 0.15)
		(layer "In7.Cu")
		(net 1264)
	)
	(segment
		(start 98.731916 102.3775)
		(end 100.1125 102.3775)
		(width 0.15)
		(layer "In7.Cu")
		(net 1264)
	)
	(segment
		(start 100.1125 102.3775)
		(end 100.3875 102.3775)
		(width 0.15)
		(layer "In7.Cu")
		(net 1264)
	)
	(segment
		(start 109.243044 88.8625)
		(end 107.943044 90.1625)
		(width 0.15)
		(layer "In7.Cu")
		(net 1264)
	)
	(segment
		(start 111.043044 88.8625)
		(end 109.243044 88.8625)
		(width 0.15)
		(layer "In7.Cu")
		(net 1264)
	)
	(segment
		(start 100.1125 104.0525)
		(end 99.181908 104.0525)
		(width 0.15)
		(layer "In7.Cu")
		(net 1264)
	)
	(segment
		(start 104.143044 108.0625)
		(end 100.656956 108.0625)
		(width 0.15)
		(layer "In7.Cu")
		(net 1264)
	)
	(segment
		(start 100.51 101.0775)
		(end 100.668079 101.0775)
		(width 0.15)
		(layer "In7.Cu")
		(net 1264)
	)
	(segment
		(start 104.7625 103.256956)
		(end 104.7625 107.443044)
		(width 0.15)
		(layer "In7.Cu")
		(net 1264)
	)
	(segment
		(start 99.170544 98.39)
		(end 99.170544 97.131916)
		(width 0.15)
		(layer "In7.Cu")
		(net 1264)
	)
	(segment
		(start 100.3875 104.9775)
		(end 100.668079 104.9775)
		(width 0.15)
		(layer "In7.Cu")
		(net 1264)
	)
	(segment
		(start 98.245544 98.7875)
		(end 98.245544 99.918099)
		(width 0.15)
		(layer "In7.Cu")
		(net 1264)
	)
	(segment
		(start 103.7625 102.256956)
		(end 104.7625 103.256956)
		(width 0.15)
		(layer "In7.Cu")
		(net 1264)
	)
	(segment
		(start 100.3875 99.9)
		(end 100.3875 99.493044)
		(width 0.15)
		(layer "In7.Cu")
		(net 1264)
	)
	(segment
		(start 97.870544 98.39)
		(end 97.870544 97.131895)
		(width 0.15)
		(layer "In7.Cu")
		(net 1264)
	)
	(segment
		(start 96.693044 98.5125)
		(end 95.993044 98.5125)
		(width 0.15)
		(layer "In7.Cu")
		(net 1264)
	)
	(segment
		(start 107.943044 90.1625)
		(end 106.843044 90.1625)
		(width 0.15)
		(layer "In7.Cu")
		(net 1264)
	)
	(segment
		(start 101.065579 101.98)
		(end 101.065579 101.85)
		(width 0.15)
		(layer "In7.Cu")
		(net 1264)
	)
	(segment
		(start 98.609416 105.23)
		(end 98.609416 105.1)
		(width 0.15)
		(layer "In7.Cu")
		(net 1264)
	)
	(arc
		(start 100.668079 106.2775)
		(mid 100.949154 106.161075)
		(end 101.065579 105.88)
		(width 0.15)
		(layer "In7.Cu")
		(net 1264)
	)
	(arc
		(start 101.065579 103.15)
		(mid 100.949154 102.868925)
		(end 100.668079 102.7525)
		(width 0.15)
		(layer "In7.Cu")
		(net 1264)
	)
	(arc
		(start 101.065579 105.75)
		(mid 100.949154 105.468925)
		(end 100.668079 105.3525)
		(width 0.15)
		(layer "In7.Cu")
		(net 1264)
	)
	(arc
		(start 101.065579 100.55)
		(mid 100.949154 100.268925)
		(end 100.668079 100.1525)
		(width 0.15)
		(layer "In7.Cu")
		(net 1264)
	)
	(arc
		(start 99.059408 103.8)
		(mid 99.095287 103.713379)
		(end 99.181908 103.6775)
		(width 0.15)
		(layer "In7.Cu")
		(net 1264)
	)
	(arc
		(start 99.170544 97.131916)
		(mid 99.054119 96.850841)
		(end 98.773044 96.734416)
		(width 0.15)
		(layer "In7.Cu")
		(net 1264)
	)
	(arc
		(start 100.3875 107.7)
		(mid 100.423379 107.613379)
		(end 100.51 107.5775)
		(width 0.15)
		(layer "In7.Cu")
		(net 1264)
	)
	(arc
		(start 97.343044 96.734395)
		(mid 97.061969 96.85082)
		(end 96.945544 97.131895)
		(width 0.15)
		(layer "In7.Cu")
		(net 1264)
	)
	(arc
		(start 98.609416 105.1)
		(mid 98.645295 105.013379)
		(end 98.731916 104.9775)
		(width 0.15)
		(layer "In7.Cu")
		(net 1264)
	)
	(arc
		(start 100.668079 101.0775)
		(mid 100.949154 100.961075)
		(end 101.065579 100.68)
		(width 0.15)
		(layer "In7.Cu")
		(net 1264)
	)
	(arc
		(start 96.945544 98.39)
		(mid 96.909665 98.476621)
		(end 96.823044 98.5125)
		(width 0.15)
		(layer "In7.Cu")
		(net 1264)
	)
	(arc
		(start 101.068084 107.5775)
		(mid 101.349159 107.461075)
		(end 101.465584 107.18)
		(width 0.15)
		(layer "In7.Cu")
		(net 1264)
	)
	(arc
		(start 97.870544 97.131895)
		(mid 97.754119 96.85082)
		(end 97.473044 96.734395)
		(width 0.15)
		(layer "In7.Cu")
		(net 1264)
	)
	(arc
		(start 98.609416 101.2)
		(mid 98.645295 101.113379)
		(end 98.731916 101.0775)
		(width 0.15)
		(layer "In7.Cu")
		(net 1264)
	)
	(arc
		(start 98.731916 105.3525)
		(mid 98.645295 105.316621)
		(end 98.609416 105.23)
		(width 0.15)
		(layer "In7.Cu")
		(net 1264)
	)
	(arc
		(start 98.731916 106.6525)
		(mid 98.645295 106.616621)
		(end 98.609416 106.53)
		(width 0.15)
		(layer "In7.Cu")
		(net 1264)
	)
	(arc
		(start 99.293044 98.5125)
		(mid 99.206423 98.476621)
		(end 99.170544 98.39)
		(width 0.15)
		(layer "In7.Cu")
		(net 1264)
	)
	(arc
		(start 100.668079 103.6775)
		(mid 100.949154 103.561075)
		(end 101.065579 103.28)
		(width 0.15)
		(layer "In7.Cu")
		(net 1264)
	)
	(arc
		(start 98.731916 102.7525)
		(mid 98.645295 102.716621)
		(end 98.609416 102.63)
		(width 0.15)
		(layer "In7.Cu")
		(net 1264)
	)
	(arc
		(start 98.643044 96.734416)
		(mid 98.361969 96.850841)
		(end 98.245544 97.131916)
		(width 0.15)
		(layer "In7.Cu")
		(net 1264)
	)
	(arc
		(start 99.181908 104.0525)
		(mid 99.095287 104.016621)
		(end 99.059408 103.93)
		(width 0.15)
		(layer "In7.Cu")
		(net 1264)
	)
	(arc
		(start 98.731916 101.4525)
		(mid 98.645295 101.416621)
		(end 98.609416 101.33)
		(width 0.15)
		(layer "In7.Cu")
		(net 1264)
	)
	(arc
		(start 98.245544 99.918099)
		(mid 98.209665 100.00472)
		(end 98.123044 100.040599)
		(width 0.15)
		(layer "In7.Cu")
		(net 1264)
	)
	(arc
		(start 101.465584 107.05)
		(mid 101.349159 106.768925)
		(end 101.068084 106.6525)
		(width 0.15)
		(layer "In7.Cu")
		(net 1264)
	)
	(arc
		(start 97.993044 100.040599)
		(mid 97.906423 100.00472)
		(end 97.870544 99.918099)
		(width 0.15)
		(layer "In7.Cu")
		(net 1264)
	)
	(arc
		(start 101.065579 101.85)
		(mid 100.949154 101.568925)
		(end 100.668079 101.4525)
		(width 0.15)
		(layer "In7.Cu")
		(net 1264)
	)
	(arc
		(start 101.065579 104.45)
		(mid 100.949154 104.168925)
		(end 100.668079 104.0525)
		(width 0.15)
		(layer "In7.Cu")
		(net 1264)
	)
	(arc
		(start 100.51 100.1525)
		(mid 100.423379 100.116621)
		(end 100.3875 100.03)
		(width 0.15)
		(layer "In7.Cu")
		(net 1264)
	)
	(arc
		(start 100.668079 102.3775)
		(mid 100.949154 102.261075)
		(end 101.065579 101.98)
		(width 0.15)
		(layer "In7.Cu")
		(net 1264)
	)
	(arc
		(start 98.609416 106.4)
		(mid 98.645295 106.313379)
		(end 98.731916 106.2775)
		(width 0.15)
		(layer "In7.Cu")
		(net 1264)
	)
	(arc
		(start 100.668079 104.9775)
		(mid 100.949154 104.861075)
		(end 101.065579 104.58)
		(width 0.15)
		(layer "In7.Cu")
		(net 1264)
	)
	(arc
		(start 98.609416 102.5)
		(mid 98.645295 102.413379)
		(end 98.731916 102.3775)
		(width 0.15)
		(layer "In7.Cu")
		(net 1264)
	)
	(segment
		(start 91.58 98.3)
		(end 91.605 98.3)
		(width 0.19)
		(layer "F.Cu")
		(net 1265)
	)
	(segment
		(start 91.92 97.985)
		(end 92.285 97.985)
		(width 0.19)
		(layer "F.Cu")
		(net 1265)
	)
	(segment
		(start 119.065532 73.915)
		(end 119.065532 74.485)
		(width 0.19)
		(layer "F.Cu")
		(net 1265)
	)
	(segment
		(start 91.605 98.3)
		(end 91.92 97.985)
		(width 0.19)
		(layer "F.Cu")
		(net 1265)
	)
	(segment
		(start 92.285 97.985)
		(end 92.4 98.1)
		(width 0.19)
		(layer "F.Cu")
		(net 1265)
	)
	(segment
		(start 119.330532 73.65)
		(end 119.065532 73.915)
		(width 0.19)
		(layer "F.Cu")
		(net 1265)
	)
	(segment
		(start 119.065532 74.485)
		(end 119.180532 74.6)
		(width 0.19)
		(layer "F.Cu")
		(net 1265)
	)
	(via
		(at 119.180532 74.6)
		(size 0.45)
		(drill 0.1)
		(layers "F.Cu" "B.Cu")
		(net 1265)
	)
	(via
		(at 92.4 98.1)
		(size 0.45)
		(drill 0.1)
		(layers "F.Cu" "B.Cu")
		(net 1265)
	)
	(segment
		(start 107.843044 91.1625)
		(end 108.443044 91.1625)
		(width 0.15)
		(layer "In7.Cu")
		(net 1265)
	)
	(segment
		(start 105.3625 101.156956)
		(end 105.3625 93.643044)
		(width 0.15)
		(layer "In7.Cu")
		(net 1265)
	)
	(segment
		(start 97.699739 102.96975)
		(end 95.931971 104.737515)
		(width 0.15)
		(layer "In7.Cu")
		(net 1265)
	)
	(segment
		(start 95.099352 103.731658)
		(end 94.818278 104.012733)
		(width 0.15)
		(layer "In7.Cu")
		(net 1265)
	)
	(segment
		(start 96.688578 101.396437)
		(end 96.780501 101.48836)
		(width 0.15)
		(layer "In7.Cu")
		(net 1265)
	)
	(segment
		(start 94.75729 104.195696)
		(end 94.900479 104.338885)
		(width 0.15)
		(layer "In7.Cu")
		(net 1265)
	)
	(segment
		(start 98.244209 103.517753)
		(end 98.336132 103.609676)
		(width 0.15)
		(layer "In7.Cu")
		(net 1265)
	)
	(segment
		(start 120.7125 80.328695)
		(end 120.7125 76.356956)
		(width 0.15)
		(layer "In7.Cu")
		(net 1265)
	)
	(segment
		(start 95.834743 104.834743)
		(end 95.834742 104.834742)
		(width 0.15)
		(layer "In7.Cu")
		(net 1265)
	)
	(segment
		(start 115.8625 87.143044)
		(end 116.843044 86.1625)
		(width 0.15)
		(layer "In7.Cu")
		(net 1265)
	)
	(segment
		(start 96.780501 102.050512)
		(end 95.099352 103.731658)
		(width 0.15)
		(layer "In7.Cu")
		(net 1265)
	)
	(segment
		(start 104.543044 108.8625)
		(end 105.5625 107.843044)
		(width 0.15)
		(layer "In7.Cu")
		(net 1265)
	)
	(segment
		(start 96.75398 105.75398)
		(end 96.692993 105.814968)
		(width 0.15)
		(layer "In7.Cu")
		(net 1265)
	)
	(segment
		(start 96.197134 105.002678)
		(end 97.682057 103.517752)
		(width 0.15)
		(layer "In7.Cu")
		(net 1265)
	)
	(segment
		(start 97.515004 106.320548)
		(end 98.061584 106.867128)
		(width 0.15)
		(layer "In7.Cu")
		(net 1265)
	)
	(segment
		(start 115.8625 88.143044)
		(end 115.8625 87.143044)
		(width 0.15)
		(layer "In7.Cu")
		(net 1265)
	)
	(segment
		(start 91.3775 99.74)
		(end 91.577308 99.74)
		(width 0.15)
		(layer "In7.Cu")
		(net 1265)
	)
	(segment
		(start 91.2375 101.943044)
		(end 91.856956 102.5625)
		(width 0.15)
		(layer "In7.Cu")
		(net 1265)
	)
	(segment
		(start 109.643044 89.9625)
		(end 114.043044 89.9625)
		(width 0.15)
		(layer "In7.Cu")
		(net 1265)
	)
	(segment
		(start 93.756956 102.5625)
		(end 94.27204 103.077584)
		(width 0.15)
		(layer "In7.Cu")
		(net 1265)
	)
	(segment
		(start 96.002677 105.197134)
		(end 96.197134 105.002678)
		(width 0.15)
		(layer "In7.Cu")
		(net 1265)
	)
	(segment
		(start 96.692993 105.814968)
		(end 96.595765 105.912196)
		(width 0.15)
		(layer "In7.Cu")
		(net 1265)
	)
	(segment
		(start 94.818278 104.012733)
		(end 94.75729 104.073721)
		(width 0.15)
		(layer "In7.Cu")
		(net 1265)
	)
	(segment
		(start 97.607816 102.315675)
		(end 97.699739 102.407598)
		(width 0.15)
		(layer "In7.Cu")
		(net 1265)
	)
	(segment
		(start 105.5625 101.356956)
		(end 105.3625 101.156956)
		(width 0.15)
		(layer "In7.Cu")
		(net 1265)
	)
	(segment
		(start 96.75398 105.753981)
		(end 96.75398 105.75398)
		(width 0.15)
		(layer "In7.Cu")
		(net 1265)
	)
	(segment
		(start 119.9625 75.606956)
		(end 119.9625 74.456956)
		(width 0.15)
		(layer "In7.Cu")
		(net 1265)
	)
	(segment
		(start 120.5525 80.888695)
		(end 120.295396 80.888695)
		(width 0.15)
		(layer "In7.Cu")
		(net 1265)
	)
	(segment
		(start 95.834742 104.834742)
		(end 95.737515 104.93197)
		(width 0.15)
		(layer "In7.Cu")
		(net 1265)
	)
	(segment
		(start 120.135396 80.728695)
		(end 120.135396 80.648695)
		(width 0.15)
		(layer "In7.Cu")
		(net 1265)
	)
	(segment
		(start 120.295396 80.488695)
		(end 120.5525 80.488695)
		(width 0.15)
		(layer "In7.Cu")
		(net 1265)
	)
	(segment
		(start 120.5525 81.688695)
		(end 120.395407 81.688695)
		(width 0.15)
		(layer "In7.Cu")
		(net 1265)
	)
	(segment
		(start 116.843044 86.1625)
		(end 118.493044 86.1625)
		(width 0.15)
		(layer "In7.Cu")
		(net 1265)
	)
	(segment
		(start 98.061584 106.867128)
		(end 100.056956 108.8625)
		(width 0.15)
		(layer "In7.Cu")
		(net 1265)
	)
	(segment
		(start 105.5625 107.843044)
		(end 105.5625 101.356956)
		(width 0.15)
		(layer "In7.Cu")
		(net 1265)
	)
	(segment
		(start 119.643044 74.1375)
		(end 119.256956 74.1375)
		(width 0.15)
		(layer "In7.Cu")
		(net 1265)
	)
	(segment
		(start 94.44528 103.077585)
		(end 96.126426 101.396436)
		(width 0.15)
		(layer "In7.Cu")
		(net 1265)
	)
	(segment
		(start 120.7125 83.943044)
		(end 120.7125 81.848695)
		(width 0.15)
		(layer "In7.Cu")
		(net 1265)
	)
	(segment
		(start 119.9625 74.456956)
		(end 119.643044 74.1375)
		(width 0.15)
		(layer "In7.Cu")
		(net 1265)
	)
	(segment
		(start 95.931971 104.737515)
		(end 95.834743 104.834743)
		(width 0.15)
		(layer "In7.Cu")
		(net 1265)
	)
	(segment
		(start 100.056956 108.8625)
		(end 104.543044 108.8625)
		(width 0.15)
		(layer "In7.Cu")
		(net 1265)
	)
	(segment
		(start 95.08344 104.277897)
		(end 95.277897 104.083441)
		(width 0.15)
		(layer "In7.Cu")
		(net 1265)
	)
	(segment
		(start 95.676527 105.114933)
		(end 95.819716 105.258122)
		(width 0.15)
		(layer "In7.Cu")
		(net 1265)
	)
	(segment
		(start 114.043044 89.9625)
		(end 115.8625 88.143044)
		(width 0.15)
		(layer "In7.Cu")
		(net 1265)
	)
	(segment
		(start 95.022453 104.338885)
		(end 95.08344 104.277897)
		(width 0.15)
		(layer "In7.Cu")
		(net 1265)
	)
	(segment
		(start 98.336132 104.171828)
		(end 96.851208 105.656753)
		(width 0.15)
		(layer "In7.Cu")
		(net 1265)
	)
	(segment
		(start 118.493044 86.1625)
		(end 120.7125 83.943044)
		(width 0.15)
		(layer "In7.Cu")
		(net 1265)
	)
	(segment
		(start 91.2375 100.3)
		(end 91.2375 101.943044)
		(width 0.15)
		(layer "In7.Cu")
		(net 1265)
	)
	(segment
		(start 119.256956 74.1375)
		(end 119.018032 74.376424)
		(width 0.15)
		(layer "In7.Cu")
		(net 1265)
	)
	(segment
		(start 120.7125 76.356956)
		(end 119.9625 75.606956)
		(width 0.15)
		(layer "In7.Cu")
		(net 1265)
	)
	(segment
		(start 92.4 98.1)
		(end 92.2375 97.9375)
		(width 0.15)
		(layer "In7.Cu")
		(net 1265)
	)
	(segment
		(start 96.851208 105.656753)
		(end 96.75398 105.753981)
		(width 0.15)
		(layer "In7.Cu")
		(net 1265)
	)
	(segment
		(start 91.577308 100.09)
		(end 91.3775 100.09)
		(width 0.15)
		(layer "In7.Cu")
		(net 1265)
	)
	(segment
		(start 91.2375 98.556956)
		(end 91.2375 99.6)
		(width 0.15)
		(layer "In7.Cu")
		(net 1265)
	)
	(segment
		(start 120.395407 81.288695)
		(end 120.5525 81.288695)
		(width 0.15)
		(layer "In7.Cu")
		(net 1265)
	)
	(segment
		(start 120.7125 81.128695)
		(end 120.7125 81.048695)
		(width 0.15)
		(layer "In7.Cu")
		(net 1265)
	)
	(segment
		(start 91.856956 97.9375)
		(end 91.2375 98.556956)
		(width 0.15)
		(layer "In7.Cu")
		(net 1265)
	)
	(segment
		(start 119.018032 74.4375)
		(end 119.180532 74.6)
		(width 0.15)
		(layer "In7.Cu")
		(net 1265)
	)
	(segment
		(start 91.717308 99.88)
		(end 91.717308 99.95)
		(width 0.15)
		(layer "In7.Cu")
		(net 1265)
	)
	(segment
		(start 95.94169 105.258122)
		(end 96.002677 105.197134)
		(width 0.15)
		(layer "In7.Cu")
		(net 1265)
	)
	(segment
		(start 105.3625 93.643044)
		(end 107.843044 91.1625)
		(width 0.15)
		(layer "In7.Cu")
		(net 1265)
	)
	(segment
		(start 108.443044 91.1625)
		(end 109.643044 89.9625)
		(width 0.15)
		(layer "In7.Cu")
		(net 1265)
	)
	(segment
		(start 95.277897 104.083441)
		(end 97.045662 102.315673)
		(width 0.15)
		(layer "In7.Cu")
		(net 1265)
	)
	(segment
		(start 119.018032 74.376424)
		(end 119.018032 74.4375)
		(width 0.15)
		(layer "In7.Cu")
		(net 1265)
	)
	(segment
		(start 96.595765 106.03417)
		(end 96.738954 106.177359)
		(width 0.15)
		(layer "In7.Cu")
		(net 1265)
	)
	(segment
		(start 97.371814 106.177359)
		(end 97.515004 106.320548)
		(width 0.15)
		(layer "In7.Cu")
		(net 1265)
	)
	(segment
		(start 91.856956 102.5625)
		(end 93.756956 102.5625)
		(width 0.15)
		(layer "In7.Cu")
		(net 1265)
	)
	(segment
		(start 94.27204 103.077584)
		(end 94.272038 103.077583)
		(width 0.15)
		(layer "In7.Cu")
		(net 1265)
	)
	(segment
		(start 92.2375 97.9375)
		(end 91.856956 97.9375)
		(width 0.15)
		(layer "In7.Cu")
		(net 1265)
	)
	(segment
		(start 120.235407 81.528695)
		(end 120.235407 81.448695)
		(width 0.15)
		(layer "In7.Cu")
		(net 1265)
	)
	(segment
		(start 91.2375 100.23)
		(end 91.2375 100.3)
		(width 0.15)
		(layer "In7.Cu")
		(net 1265)
	)
	(segment
		(start 95.737515 104.93197)
		(end 95.676527 104.992958)
		(width 0.15)
		(layer "In7.Cu")
		(net 1265)
	)
	(arc
		(start 120.5525 80.488695)
		(mid 120.665637 80.441832)
		(end 120.7125 80.328695)
		(width 0.15)
		(layer "In7.Cu")
		(net 1265)
	)
	(arc
		(start 120.135396 80.648695)
		(mid 120.182259 80.535558)
		(end 120.295396 80.488695)
		(width 0.15)
		(layer "In7.Cu")
		(net 1265)
	)
	(arc
		(start 120.295396 80.888695)
		(mid 120.182259 80.841832)
		(end 120.135396 80.728695)
		(width 0.15)
		(layer "In7.Cu")
		(net 1265)
	)
	(arc
		(start 120.5525 81.288695)
		(mid 120.665637 81.241832)
		(end 120.7125 81.128695)
		(width 0.15)
		(layer "In7.Cu")
		(net 1265)
	)
	(arc
		(start 91.2375 99.6)
		(mid 91.278505 99.698995)
		(end 91.3775 99.74)
		(width 0.15)
		(layer "In7.Cu")
		(net 1265)
	)
	(arc
		(start 120.7125 81.848695)
		(mid 120.665637 81.735558)
		(end 120.5525 81.688695)
		(width 0.15)
		(layer "In7.Cu")
		(net 1265)
	)
	(arc
		(start 95.676527 104.992958)
		(mid 95.651265 105.053945)
		(end 95.676527 105.114933)
		(width 0.15)
		(layer "In7.Cu")
		(net 1265)
	)
	(arc
		(start 94.75729 104.073721)
		(mid 94.732028 104.134708)
		(end 94.75729 104.195696)
		(width 0.15)
		(layer "In7.Cu")
		(net 1265)
	)
	(arc
		(start 96.595765 105.912196)
		(mid 96.570503 105.973183)
		(end 96.595765 106.03417)
		(width 0.15)
		(layer "In7.Cu")
		(net 1265)
	)
	(arc
		(start 120.235407 81.448695)
		(mid 120.28227 81.335558)
		(end 120.395407 81.288695)
		(width 0.15)
		(layer "In7.Cu")
		(net 1265)
	)
	(arc
		(start 95.819716 105.258122)
		(mid 95.880703 105.283384)
		(end 95.94169 105.258122)
		(width 0.15)
		(layer "In7.Cu")
		(net 1265)
	)
	(arc
		(start 96.780501 101.48836)
		(mid 96.896925 101.769435)
		(end 96.780501 102.050512)
		(width 0.15)
		(layer "In7.Cu")
		(net 1265)
	)
	(arc
		(start 94.272038 103.077583)
		(mid 94.358659 103.113463)
		(end 94.44528 103.077585)
		(width 0.15)
		(layer "In7.Cu")
		(net 1265)
	)
	(arc
		(start 120.7125 81.048695)
		(mid 120.665637 80.935558)
		(end 120.5525 80.888695)
		(width 0.15)
		(layer "In7.Cu")
		(net 1265)
	)
	(arc
		(start 91.717308 99.95)
		(mid 91.676303 100.048995)
		(end 91.577308 100.09)
		(width 0.15)
		(layer "In7.Cu")
		(net 1265)
	)
	(arc
		(start 96.860928 106.177359)
		(mid 97.116371 106.071551)
		(end 97.371814 106.177359)
		(width 0.15)
		(layer "In7.Cu")
		(net 1265)
	)
	(arc
		(start 98.336132 103.609676)
		(mid 98.452558 103.890753)
		(end 98.336132 104.171828)
		(width 0.15)
		(layer "In7.Cu")
		(net 1265)
	)
	(arc
		(start 91.3775 100.09)
		(mid 91.278505 100.131005)
		(end 91.2375 100.23)
		(width 0.15)
		(layer "In7.Cu")
		(net 1265)
	)
	(arc
		(start 96.738954 106.177359)
		(mid 96.799941 106.202621)
		(end 96.860928 106.177359)
		(width 0.15)
		(layer "In7.Cu")
		(net 1265)
	)
	(arc
		(start 96.126426 101.396436)
		(mid 96.407501 101.280011)
		(end 96.688578 101.396437)
		(width 0.15)
		(layer "In7.Cu")
		(net 1265)
	)
	(arc
		(start 97.699739 102.407598)
		(mid 97.816163 102.688673)
		(end 97.699739 102.96975)
		(width 0.15)
		(layer "In7.Cu")
		(net 1265)
	)
	(arc
		(start 94.900479 104.338885)
		(mid 94.961466 104.364147)
		(end 95.022453 104.338885)
		(width 0.15)
		(layer "In7.Cu")
		(net 1265)
	)
	(arc
		(start 91.577308 99.74)
		(mid 91.676303 99.781005)
		(end 91.717308 99.88)
		(width 0.15)
		(layer "In7.Cu")
		(net 1265)
	)
	(arc
		(start 97.045662 102.315673)
		(mid 97.326739 102.199249)
		(end 97.607816 102.315675)
		(width 0.15)
		(layer "In7.Cu")
		(net 1265)
	)
	(arc
		(start 97.682057 103.517752)
		(mid 97.963132 103.401327)
		(end 98.244209 103.517753)
		(width 0.15)
		(layer "In7.Cu")
		(net 1265)
	)
	(arc
		(start 120.395407 81.688695)
		(mid 120.28227 81.641832)
		(end 120.235407 81.528695)
		(width 0.15)
		(layer "In7.Cu")
		(net 1265)
	)
	(segment
		(start 119.015 86.821)
		(end 119.015 86.71326)
		(width 0.19)
		(layer "F.Cu")
		(net 1266)
	)
	(segment
		(start 117.785 88.72337)
		(end 118.07663 89.015)
		(width 0.19)
		(layer "F.Cu")
		(net 1266)
	)
	(segment
		(start 118.52337 89.015)
		(end 119.015 88.52337)
		(width 0.19)
		(layer "F.Cu")
		(net 1266)
	)
	(segment
		(start 92.285 94.815)
		(end 92.4 94.7)
		(width 0.19)
		(layer "F.Cu")
		(net 1266)
	)
	(segment
		(start 119.015 88.52337)
		(end 119.015 87.775)
		(width 0.19)
		(layer "F.Cu")
		(net 1266)
	)
	(segment
		(start 118.803 87.563)
		(end 118.440392 87.563)
		(width 0.19)
		(layer "F.Cu")
		(net 1266)
	)
	(segment
		(start 119.015 86.71326)
		(end 118.695532 86.393792)
		(width 0.19)
		(layer "F.Cu")
		(net 1266)
	)
	(segment
		(start 91.605 94.5)
		(end 91.92 94.815)
		(width 0.19)
		(layer "F.Cu")
		(net 1266)
	)
	(segment
		(start 117.9 88.2)
		(end 117.785 88.315)
		(width 0.19)
		(layer "F.Cu")
		(net 1266)
	)
	(segment
		(start 118.228392 87.351)
		(end 118.228392 87.245)
		(width 0.19)
		(layer "F.Cu")
		(net 1266)
	)
	(segment
		(start 118.695532 86.393792)
		(end 118.695532 85.915)
		(width 0.19)
		(layer "F.Cu")
		(net 1266)
	)
	(segment
		(start 118.695532 85.915)
		(end 118.430532 85.65)
		(width 0.19)
		(layer "F.Cu")
		(net 1266)
	)
	(segment
		(start 91.92 94.815)
		(end 92.285 94.815)
		(width 0.19)
		(layer "F.Cu")
		(net 1266)
	)
	(segment
		(start 117.785 88.315)
		(end 117.785 88.72337)
		(width 0.19)
		(layer "F.Cu")
		(net 1266)
	)
	(segment
		(start 91.58 94.5)
		(end 91.605 94.5)
		(width 0.19)
		(layer "F.Cu")
		(net 1266)
	)
	(segment
		(start 118.440392 87.033)
		(end 118.803 87.033)
		(width 0.19)
		(layer "F.Cu")
		(net 1266)
	)
	(segment
		(start 118.07663 89.015)
		(end 118.52337 89.015)
		(width 0.19)
		(layer "F.Cu")
		(net 1266)
	)
	(via
		(at 92.4 94.7)
		(size 0.45)
		(drill 0.1)
		(layers "F.Cu" "B.Cu")
		(net 1266)
	)
	(via
		(at 117.9 88.2)
		(size 0.45)
		(drill 0.1)
		(layers "F.Cu" "B.Cu")
		(net 1266)
	)
	(arc
		(start 119.015 87.775)
		(mid 118.952907 87.625093)
		(end 118.803 87.563)
		(width 0.19)
		(layer "F.Cu")
		(net 1266)
	)
	(arc
		(start 118.803 87.033)
		(mid 118.952907 86.970907)
		(end 119.015 86.821)
		(width 0.19)
		(layer "F.Cu")
		(net 1266)
	)
	(arc
		(start 118.228392 87.245)
		(mid 118.290485 87.095093)
		(end 118.440392 87.033)
		(width 0.19)
		(layer "F.Cu")
		(net 1266)
	)
	(arc
		(start 118.440392 87.563)
		(mid 118.290485 87.500907)
		(end 118.228392 87.351)
		(width 0.19)
		(layer "F.Cu")
		(net 1266)
	)
	(segment
		(start 106.7375 94.92)
		(end 106.7375 94.8)
		(width 0.15)
		(layer "In7.Cu")
		(net 1266)
	)
	(segment
		(start 110.18 93.375)
		(end 110.3 93.375)
		(width 0.15)
		(layer "In7.Cu")
		(net 1266)
	)
	(segment
		(start 106.337081 97.0975)
		(end 106.4625 97.0975)
		(width 0.15)
		(layer "In7.Cu")
		(net 1266)
	)
	(segment
		(start 109.8025 91.86)
		(end 109.8025 92.2375)
		(width 0.15)
		(layer "In7.Cu")
		(net 1266)
	)
	(segment
		(start 89.8625 102.556956)
		(end 90.943044 103.6375)
		(width 0.15)
		(layer "In7.Cu")
		(net 1266)
	)
	(segment
		(start 106.84 95.8975)
		(end 107.862937 95.8975)
		(width 0.15)
		(layer "In7.Cu")
		(net 1266)
	)
	(segment
		(start 116.647228 91.447228)
		(end 117.7375 90.356956)
		(width 0.15)
		(layer "In7.Cu")
		(net 1266)
	)
	(segment
		(start 106.234581 96.12)
		(end 106.234581 96)
		(width 0.15)
		(layer "In7.Cu")
		(net 1266)
	)
	(segment
		(start 115.1 92.2375)
		(end 115.856956 92.2375)
		(width 0.15)
		(layer "In7.Cu")
		(net 1266)
	)
	(segment
		(start 92.4 94.7)
		(end 92.2375 94.8625)
		(width 0.15)
		(layer "In7.Cu")
		(net 1266)
	)
	(segment
		(start 106.84 101.0225)
		(end 106.4625 101.0225)
		(width 0.15)
		(layer "In7.Cu")
		(net 1266)
	)
	(segment
		(start 106.865391 101.0225)
		(end 106.84 101.0225)
		(width 0.15)
		(layer "In7.Cu")
		(net 1266)
	)
	(segment
		(start 114.2775 91.86)
		(end 114.2775 91.7025)
		(width 0.15)
		(layer "In7.Cu")
		(net 1266)
	)
	(segment
		(start 115.856956 92.2375)
		(end 116.647228 91.447228)
		(width 0.15)
		(layer "In7.Cu")
		(net 1266)
	)
	(segment
		(start 114.2775 92.6975)
		(end 114.2775 92.2375)
		(width 0.15)
		(layer "In7.Cu")
		(net 1266)
	)
	(segment
		(start 106.84 104.2975)
		(end 106.865391 104.2975)
		(width 0.15)
		(layer "In7.Cu")
		(net 1266)
	)
	(segment
		(start 106.7375 98.6225)
		(end 106.4625 98.6225)
		(width 0.15)
		(layer "In7.Cu")
		(net 1266)
	)
	(segment
		(start 113.0775 91.9625)
		(end 113.0775 91.6525)
		(width 0.15)
		(layer "In7.Cu")
		(net 1266)
	)
	(segment
		(start 106.7375 96.2225)
		(end 106.4625 96.2225)
		(width 0.15)
		(layer "In7.Cu")
		(net 1266)
	)
	(segment
		(start 106.337081 99.4975)
		(end 106.4625 99.4975)
		(width 0.15)
		(layer "In7.Cu")
		(net 1266)
	)
	(segment
		(start 111.0025 91.9625)
		(end 111.0025 92.2375)
		(width 0.15)
		(layer "In7.Cu")
		(net 1266)
	)
	(segment
		(start 111.0025 91.5025)
		(end 111.0025 91.9625)
		(width 0.15)
		(layer "In7.Cu")
		(net 1266)
	)
	(segment
		(start 111.98 91.65)
		(end 112.1 91.65)
		(width 0.15)
		(layer "In7.Cu")
		(net 1266)
	)
	(segment
		(start 112.58 93.075)
		(end 112.7 93.075)
		(width 0.15)
		(layer "In7.Cu")
		(net 1266)
	)
	(segment
		(start 107.240419 99.12)
		(end 107.240419 99)
		(width 0.15)
		(layer "In7.Cu")
		(net 1266)
	)
	(segment
		(start 106.7375 94.456956)
		(end 106.997228 94.197228)
		(width 0.15)
		(layer "In7.Cu")
		(net 1266)
	)
	(segment
		(start 106.84 103.0975)
		(end 106.865391 103.0975)
		(width 0.15)
		(layer "In7.Cu")
		(net 1266)
	)
	(segment
		(start 99.343044 109.9375)
		(end 105.056956 109.9375)
		(width 0.15)
		(layer "In7.Cu")
		(net 1266)
	)
	(segment
		(start 109.8025 92.2375)
		(end 109.8025 92.9975)
		(width 0.15)
		(layer "In7.Cu")
		(net 1266)
	)
	(segment
		(start 106.3125 100.9475)
		(end 106.3125 100.7725)
		(width 0.15)
		(layer "In7.Cu")
		(net 1266)
	)
	(segment
		(start 106.84 101.8975)
		(end 106.865391 101.8975)
		(width 0.15)
		(layer "In7.Cu")
		(net 1266)
	)
	(segment
		(start 106.7375 98.2975)
		(end 106.862919 98.2975)
		(width 0.15)
		(layer "In7.Cu")
		(net 1266)
	)
	(segment
		(start 113.0775 92.6975)
		(end 113.0775 92.2375)
		(width 0.15)
		(layer "In7.Cu")
		(net 1266)
	)
	(segment
		(start 110.6775 92.2375)
		(end 110.6775 91.9625)
		(width 0.15)
		(layer "In7.Cu")
		(net 1266)
	)
	(segment
		(start 114.2775 92.2375)
		(end 114.2775 91.86)
		(width 0.15)
		(layer "In7.Cu")
		(net 1266)
	)
	(segment
		(start 106.4625 95.8975)
		(end 106.84 95.8975)
		(width 0.15)
		(layer "In7.Cu")
		(net 1266)
	)
	(segment
		(start 113.0775 92.2375)
		(end 113.0775 91.9625)
		(width 0.15)
		(layer "In7.Cu")
		(net 1266)
	)
	(segment
		(start 106.997228 94.197228)
		(end 108.956956 92.2375)
		(width 0.15)
		(layer "In7.Cu")
		(net 1266)
	)
	(segment
		(start 106.7375 97.4225)
		(end 106.4625 97.4225)
		(width 0.15)
		(layer "In7.Cu")
		(net 1266)
	)
	(segment
		(start 106.7375 108.256956)
		(end 106.7375 105.6)
		(width 0.15)
		(layer "In7.Cu")
		(net 1266)
	)
	(segment
		(start 110.78 91.4)
		(end 110.9 91.4)
		(width 0.15)
		(layer "In7.Cu")
		(net 1266)
	)
	(segment
		(start 107.242891 105.12)
		(end 107.242891 105)
		(width 0.15)
		(layer "In7.Cu")
		(net 1266)
	)
	(segment
		(start 106.7375 100.6975)
		(end 106.862919 100.6975)
		(width 0.15)
		(layer "In7.Cu")
		(net 1266)
	)
	(segment
		(start 107.242891 101.52)
		(end 107.242891 101.4)
		(width 0.15)
		(layer "In7.Cu")
		(net 1266)
	)
	(segment
		(start 106.7375 103.32)
		(end 106.7375 103.2)
		(width 0.15)
		(layer "In7.Cu")
		(net 1266)
	)
	(segment
		(start 106.84 105.4975)
		(end 106.865391 105.4975)
		(width 0.15)
		(layer "In7.Cu")
		(net 1266)
	)
	(segment
		(start 106.4625 101.0225)
		(end 106.3875 101.0225)
		(width 0.15)
		(layer "In7.Cu")
		(net 1266)
	)
	(segment
		(start 106.865391 104.6225)
		(end 106.84 104.6225)
		(width 0.15)
		(layer "In7.Cu")
		(net 1266)
	)
	(segment
		(start 108.240437 95.52)
		(end 108.240437 95.4)
		(width 0.15)
		(layer "In7.Cu")
		(net 1266)
	)
	(segment
		(start 106.4625 97.0975)
		(end 106.7375 97.0975)
		(width 0.15)
		(layer "In7.Cu")
		(net 1266)
	)
	(segment
		(start 106.862919 97.4225)
		(end 106.7375 97.4225)
		(width 0.15)
		(layer "In7.Cu")
		(net 1266)
	)
	(segment
		(start 106.865391 102.2225)
		(end 106.84 102.2225)
		(width 0.15)
		(layer "In7.Cu")
		(net 1266)
	)
	(segment
		(start 106.337081 95.8975)
		(end 106.4625 95.8975)
		(width 0.15)
		(layer "In7.Cu")
		(net 1266)
	)
	(segment
		(start 105.056956 109.9375)
		(end 106.7375 108.256956)
		(width 0.15)
		(layer "In7.Cu")
		(net 1266)
	)
	(segment
		(start 106.337081 98.2975)
		(end 106.4625 98.2975)
		(width 0.15)
		(layer "In7.Cu")
		(net 1266)
	)
	(segment
		(start 106.4625 96.2225)
		(end 106.337081 96.2225)
		(width 0.15)
		(layer "In7.Cu")
		(net 1266)
	)
	(segment
		(start 110.6775 91.9625)
		(end 110.6775 91.5025)
		(width 0.15)
		(layer "In7.Cu")
		(net 1266)
	)
	(segment
		(start 90.943044 103.6375)
		(end 93.043044 103.6375)
		(width 0.15)
		(layer "In7.Cu")
		(net 1266)
	)
	(segment
		(start 106.865391 103.4225)
		(end 106.84 103.4225)
		(width 0.15)
		(layer "In7.Cu")
		(net 1266)
	)
	(segment
		(start 111.0025 92.2375)
		(end 111.0025 92.6975)
		(width 0.15)
		(layer "In7.Cu")
		(net 1266)
	)
	(segment
		(start 112.2025 91.9625)
		(end 112.2025 92.2375)
		(width 0.15)
		(layer "In7.Cu")
		(net 1266)
	)
	(segment
		(start 107.862937 95.0225)
		(end 106.84 95.0225)
		(width 0.15)
		(layer "In7.Cu")
		(net 1266)
	)
	(segment
		(start 108.956956 92.2375)
		(end 109.1 92.2375)
		(width 0.15)
		(layer "In7.Cu")
		(net 1266)
	)
	(segment
		(start 114.98 92.2375)
		(end 115.1 92.2375)
		(width 0.15)
		(layer "In7.Cu")
		(net 1266)
	)
	(segment
		(start 106.4625 97.4225)
		(end 106.337081 97.4225)
		(width 0.15)
		(layer "In7.Cu")
		(net 1266)
	)
	(segment
		(start 112.2025 91.7525)
		(end 112.2025 91.9625)
		(width 0.15)
		(layer "In7.Cu")
		(net 1266)
	)
	(segment
		(start 107.240419 97.92)
		(end 107.240419 97.8)
		(width 0.15)
		(layer "In7.Cu")
		(net 1266)
	)
	(segment
		(start 109.4775 91.86)
		(end 109.4775 91.8025)
		(width 0.15)
		(layer "In7.Cu")
		(net 1266)
	)
	(segment
		(start 107.242891 102.72)
		(end 107.242891 102.6)
		(width 0.15)
		(layer "In7.Cu")
		(net 1266)
	)
	(segment
		(start 113.4025 92.2375)
		(end 113.4025 92.6975)
		(width 0.15)
		(layer "In7.Cu")
		(net 1266)
	)
	(segment
		(start 113.78 93.075)
		(end 113.9 93.075)
		(width 0.15)
		(layer "In7.Cu")
		(net 1266)
	)
	(segment
		(start 107.240419 100.32)
		(end 107.240419 100.2)
		(width 0.15)
		(layer "In7.Cu")
		(net 1266)
	)
	(segment
		(start 91.143044 94.8625)
		(end 89.8625 96.143044)
		(width 0.15)
		(layer "In7.Cu")
		(net 1266)
	)
	(segment
		(start 113.4025 91.9625)
		(end 113.4025 92.2375)
		(width 0.15)
		(layer "In7.Cu")
		(net 1266)
	)
	(segment
		(start 106.234581 99.72)
		(end 106.234581 99.6)
		(width 0.15)
		(layer "In7.Cu")
		(net 1266)
	)
	(segment
		(start 114.6025 91.7025)
		(end 114.6025 91.86)
		(width 0.15)
		(layer "In7.Cu")
		(net 1266)
	)
	(segment
		(start 106.862919 96.2225)
		(end 106.7375 96.2225)
		(width 0.15)
		(layer "In7.Cu")
		(net 1266)
	)
	(segment
		(start 114.38 91.6)
		(end 114.5 91.6)
		(width 0.15)
		(layer "In7.Cu")
		(net 1266)
	)
	(segment
		(start 106.7375 104.52)
		(end 106.7375 104.4)
		(width 0.15)
		(layer "In7.Cu")
		(net 1266)
	)
	(segment
		(start 110.6775 92.9975)
		(end 110.6775 92.2375)
		(width 0.15)
		(layer "In7.Cu")
		(net 1266)
	)
	(segment
		(start 106.7375 99.8225)
		(end 106.4625 99.8225)
		(width 0.15)
		(layer "In7.Cu")
		(net 1266)
	)
	(segment
		(start 107.242891 103.92)
		(end 107.242891 103.8)
		(width 0.15)
		(layer "In7.Cu")
		(net 1266)
	)
	(segment
		(start 106.4625 98.2975)
		(end 106.7375 98.2975)
		(width 0.15)
		(layer "In7.Cu")
		(net 1266)
	)
	(segment
		(start 106.862919 98.6225)
		(end 106.7375 98.6225)
		(width 0.15)
		(layer "In7.Cu")
		(net 1266)
	)
	(segment
		(start 113.4025 91.6525)
		(end 113.4025 91.9625)
		(width 0.15)
		(layer "In7.Cu")
		(net 1266)
	)
	(segment
		(start 93.043044 103.6375)
		(end 99.343044 109.9375)
		(width 0.15)
		(layer "In7.Cu")
		(net 1266)
	)
	(segment
		(start 106.7375 99.4975)
		(end 106.862919 99.4975)
		(width 0.15)
		(layer "In7.Cu")
		(net 1266)
	)
	(segment
		(start 106.4625 99.8225)
		(end 106.337081 99.8225)
		(width 0.15)
		(layer "In7.Cu")
		(net 1266)
	)
	(segment
		(start 112.2025 92.2375)
		(end 112.2025 92.6975)
		(width 0.15)
		(layer "In7.Cu")
		(net 1266)
	)
	(segment
		(start 106.7375 97.0975)
		(end 106.862919 97.0975)
		(width 0.15)
		(layer "In7.Cu")
		(net 1266)
	)
	(segment
		(start 106.7375 102.12)
		(end 106.7375 102)
		(width 0.15)
		(layer "In7.Cu")
		(net 1266)
	)
	(segment
		(start 106.4625 99.4975)
		(end 106.7375 99.4975)
		(width 0.15)
		(layer "In7.Cu")
		(net 1266)
	)
	(segment
		(start 106.234581 98.52)
		(end 106.234581 98.4)
		(width 0.15)
		(layer "In7.Cu")
		(net 1266)
	)
	(segment
		(start 106.234581 97.32)
		(end 106.234581 97.2)
		(width 0.15)
		(layer "In7.Cu")
		(net 1266)
	)
	(segment
		(start 113.18 91.55)
		(end 113.3 91.55)
		(width 0.15)
		(layer "In7.Cu")
		(net 1266)
	)
	(segment
		(start 111.8775 91.9625)
		(end 111.8775 91.7525)
		(width 0.15)
		(layer "In7.Cu")
		(net 1266)
	)
	(segment
		(start 106.3875 100.6975)
		(end 106.4625 100.6975)
		(width 0.15)
		(layer "In7.Cu")
		(net 1266)
	)
	(segment
		(start 117.7375 90.356956)
		(end 117.7375 88.3625)
		(width 0.15)
		(layer "In7.Cu")
		(net 1266)
	)
	(segment
		(start 106.4625 98.6225)
		(end 106.337081 98.6225)
		(width 0.15)
		(layer "In7.Cu")
		(net 1266)
	)
	(segment
		(start 106.862919 99.8225)
		(end 106.7375 99.8225)
		(width 0.15)
		(layer "In7.Cu")
		(net 1266)
	)
	(segment
		(start 106.7375 94.8)
		(end 106.7375 94.456956)
		(width 0.15)
		(layer "In7.Cu")
		(net 1266)
	)
	(segment
		(start 117.7375 88.3625)
		(end 117.9 88.2)
		(width 0.15)
		(layer "In7.Cu")
		(net 1266)
	)
	(segment
		(start 109.58 91.7)
		(end 109.7 91.7)
		(width 0.15)
		(layer "In7.Cu")
		(net 1266)
	)
	(segment
		(start 107.240419 96.72)
		(end 107.240419 96.6)
		(width 0.15)
		(layer "In7.Cu")
		(net 1266)
	)
	(segment
		(start 111.8775 92.6975)
		(end 111.8775 92.2375)
		(width 0.15)
		(layer "In7.Cu")
		(net 1266)
	)
	(segment
		(start 111.38 93.075)
		(end 111.5 93.075)
		(width 0.15)
		(layer "In7.Cu")
		(net 1266)
	)
	(segment
		(start 92.2375 94.8625)
		(end 91.143044 94.8625)
		(width 0.15)
		(layer "In7.Cu")
		(net 1266)
	)
	(segment
		(start 106.4625 100.6975)
		(end 106.7375 100.6975)
		(width 0.15)
		(layer "In7.Cu")
		(net 1266)
	)
	(segment
		(start 111.8775 92.2375)
		(end 111.8775 91.9625)
		(width 0.15)
		(layer "In7.Cu")
		(net 1266)
	)
	(segment
		(start 89.8625 96.143044)
		(end 89.8625 102.556956)
		(width 0.15)
		(layer "In7.Cu")
		(net 1266)
	)
	(segment
		(start 109.8025 91.8025)
		(end 109.8025 91.86)
		(width 0.15)
		(layer "In7.Cu")
		(net 1266)
	)
	(arc
		(start 111.0025 92.6975)
		(mid 111.113067 92.964433)
		(end 111.38 93.075)
		(width 0.15)
		(layer "In7.Cu")
		(net 1266)
	)
	(arc
		(start 109.4775 91.8025)
		(mid 109.507522 91.730022)
		(end 109.58 91.7)
		(width 0.15)
		(layer "In7.Cu")
		(net 1266)
	)
	(arc
		(start 113.3 91.55)
		(mid 113.372478 91.580022)
		(end 113.4025 91.6525)
		(width 0.15)
		(layer "In7.Cu")
		(net 1266)
	)
	(arc
		(start 114.5 91.6)
		(mid 114.572478 91.630022)
		(end 114.6025 91.7025)
		(width 0.15)
		(layer "In7.Cu")
		(net 1266)
	)
	(arc
		(start 111.8775 91.7525)
		(mid 111.907522 91.680022)
		(end 111.98 91.65)
		(width 0.15)
		(layer "In7.Cu")
		(net 1266)
	)
	(arc
		(start 108.240437 95.4)
		(mid 108.12987 95.133067)
		(end 107.862937 95.0225)
		(width 0.15)
		(layer "In7.Cu")
		(net 1266)
	)
	(arc
		(start 106.3875 101.0225)
		(mid 106.334467 101.000533)
		(end 106.3125 100.9475)
		(width 0.15)
		(layer "In7.Cu")
		(net 1266)
	)
	(arc
		(start 106.865391 104.2975)
		(mid 107.132324 104.186933)
		(end 107.242891 103.92)
		(width 0.15)
		(layer "In7.Cu")
		(net 1266)
	)
	(arc
		(start 107.242891 105)
		(mid 107.132324 104.733067)
		(end 106.865391 104.6225)
		(width 0.15)
		(layer "In7.Cu")
		(net 1266)
	)
	(arc
		(start 106.865391 103.0975)
		(mid 107.132324 102.986933)
		(end 107.242891 102.72)
		(width 0.15)
		(layer "In7.Cu")
		(net 1266)
	)
	(arc
		(start 106.337081 97.4225)
		(mid 106.264603 97.392478)
		(end 106.234581 97.32)
		(width 0.15)
		(layer "In7.Cu")
		(net 1266)
	)
	(arc
		(start 106.3125 100.7725)
		(mid 106.334467 100.719467)
		(end 106.3875 100.6975)
		(width 0.15)
		(layer "In7.Cu")
		(net 1266)
	)
	(arc
		(start 106.7375 102)
		(mid 106.767522 101.927522)
		(end 106.84 101.8975)
		(width 0.15)
		(layer "In7.Cu")
		(net 1266)
	)
	(arc
		(start 106.865391 101.8975)
		(mid 107.132324 101.786933)
		(end 107.242891 101.52)
		(width 0.15)
		(layer "In7.Cu")
		(net 1266)
	)
	(arc
		(start 107.240419 99)
		(mid 107.129852 98.733067)
		(end 106.862919 98.6225)
		(width 0.15)
		(layer "In7.Cu")
		(net 1266)
	)
	(arc
		(start 106.234581 98.4)
		(mid 106.264603 98.327522)
		(end 106.337081 98.2975)
		(width 0.15)
		(layer "In7.Cu")
		(net 1266)
	)
	(arc
		(start 106.337081 99.8225)
		(mid 106.264603 99.792478)
		(end 106.234581 99.72)
		(width 0.15)
		(layer "In7.Cu")
		(net 1266)
	)
	(arc
		(start 112.7 93.075)
		(mid 112.966933 92.964433)
		(end 113.0775 92.6975)
		(width 0.15)
		(layer "In7.Cu")
		(net 1266)
	)
	(arc
		(start 106.862919 100.6975)
		(mid 107.129852 100.586933)
		(end 107.240419 100.32)
		(width 0.15)
		(layer "In7.Cu")
		(net 1266)
	)
	(arc
		(start 106.84 102.2225)
		(mid 106.767522 102.192478)
		(end 106.7375 102.12)
		(width 0.15)
		(layer "In7.Cu")
		(net 1266)
	)
	(arc
		(start 107.242891 102.6)
		(mid 107.132324 102.333067)
		(end 106.865391 102.2225)
		(width 0.15)
		(layer "In7.Cu")
		(net 1266)
	)
	(arc
		(start 106.84 103.4225)
		(mid 106.767522 103.392478)
		(end 106.7375 103.32)
		(width 0.15)
		(layer "In7.Cu")
		(net 1266)
	)
	(arc
		(start 106.234581 99.6)
		(mid 106.264603 99.527522)
		(end 106.337081 99.4975)
		(width 0.15)
		(layer "In7.Cu")
		(net 1266)
	)
	(arc
		(start 106.234581 97.2)
		(mid 106.264603 97.127522)
		(end 106.337081 97.0975)
		(width 0.15)
		(layer "In7.Cu")
		(net 1266)
	)
	(arc
		(start 107.240419 100.2)
		(mid 107.129852 99.933067)
		(end 106.862919 99.8225)
		(width 0.15)
		(layer "In7.Cu")
		(net 1266)
	)
	(arc
		(start 109.7 91.7)
		(mid 109.772478 91.730022)
		(end 109.8025 91.8025)
		(width 0.15)
		(layer "In7.Cu")
		(net 1266)
	)
	(arc
		(start 106.7375 104.4)
		(mid 106.767522 104.327522)
		(end 106.84 104.2975)
		(width 0.15)
		(layer "In7.Cu")
		(net 1266)
	)
	(arc
		(start 113.9 93.075)
		(mid 114.166933 92.964433)
		(end 114.2775 92.6975)
		(width 0.15)
		(layer "In7.Cu")
		(net 1266)
	)
	(arc
		(start 112.1 91.65)
		(mid 112.172478 91.680022)
		(end 112.2025 91.7525)
		(width 0.15)
		(layer "In7.Cu")
		(net 1266)
	)
	(arc
		(start 106.7375 105.6)
		(mid 106.767522 105.527522)
		(end 106.84 105.4975)
		(width 0.15)
		(layer "In7.Cu")
		(net 1266)
	)
	(arc
		(start 106.7375 103.2)
		(mid 106.767522 103.127522)
		(end 106.84 103.0975)
		(width 0.15)
		(layer "In7.Cu")
		(net 1266)
	)
	(arc
		(start 109.8025 92.9975)
		(mid 109.913067 93.264433)
		(end 110.18 93.375)
		(width 0.15)
		(layer "In7.Cu")
		(net 1266)
	)
	(arc
		(start 107.862937 95.8975)
		(mid 108.12987 95.786933)
		(end 108.240437 95.52)
		(width 0.15)
		(layer "In7.Cu")
		(net 1266)
	)
	(arc
		(start 106.337081 96.2225)
		(mid 106.264603 96.192478)
		(end 106.234581 96.12)
		(width 0.15)
		(layer "In7.Cu")
		(net 1266)
	)
	(arc
		(start 106.337081 98.6225)
		(mid 106.264603 98.592478)
		(end 106.234581 98.52)
		(width 0.15)
		(layer "In7.Cu")
		(net 1266)
	)
	(arc
		(start 106.862919 99.4975)
		(mid 107.129852 99.386933)
		(end 107.240419 99.12)
		(width 0.15)
		(layer "In7.Cu")
		(net 1266)
	)
	(arc
		(start 110.6775 91.5025)
		(mid 110.707522 91.430022)
		(end 110.78 91.4)
		(width 0.15)
		(layer "In7.Cu")
		(net 1266)
	)
	(arc
		(start 110.9 91.4)
		(mid 110.972478 91.430022)
		(end 111.0025 91.5025)
		(width 0.15)
		(layer "In7.Cu")
		(net 1266)
	)
	(arc
		(start 106.84 104.6225)
		(mid 106.767522 104.592478)
		(end 106.7375 104.52)
		(width 0.15)
		(layer "In7.Cu")
		(net 1266)
	)
	(arc
		(start 111.5 93.075)
		(mid 111.766933 92.964433)
		(end 111.8775 92.6975)
		(width 0.15)
		(layer "In7.Cu")
		(net 1266)
	)
	(arc
		(start 106.865391 105.4975)
		(mid 107.132324 105.386933)
		(end 107.242891 105.12)
		(width 0.15)
		(layer "In7.Cu")
		(net 1266)
	)
	(arc
		(start 107.240419 96.6)
		(mid 107.129852 96.333067)
		(end 106.862919 96.2225)
		(width 0.15)
		(layer "In7.Cu")
		(net 1266)
	)
	(arc
		(start 106.84 95.0225)
		(mid 106.767522 94.992478)
		(end 106.7375 94.92)
		(width 0.15)
		(layer "In7.Cu")
		(net 1266)
	)
	(arc
		(start 113.4025 92.6975)
		(mid 113.513067 92.964433)
		(end 113.78 93.075)
		(width 0.15)
		(layer "In7.Cu")
		(net 1266)
	)
	(arc
		(start 106.862919 98.2975)
		(mid 107.129852 98.186933)
		(end 107.240419 97.92)
		(width 0.15)
		(layer "In7.Cu")
		(net 1266)
	)
	(arc
		(start 107.240419 97.8)
		(mid 107.129852 97.533067)
		(end 106.862919 97.4225)
		(width 0.15)
		(layer "In7.Cu")
		(net 1266)
	)
	(arc
		(start 106.234581 96)
		(mid 106.264603 95.927522)
		(end 106.337081 95.8975)
		(width 0.15)
		(layer "In7.Cu")
		(net 1266)
	)
	(arc
		(start 107.242891 101.4)
		(mid 107.132324 101.133067)
		(end 106.865391 101.0225)
		(width 0.15)
		(layer "In7.Cu")
		(net 1266)
	)
	(arc
		(start 112.2025 92.6975)
		(mid 112.313067 92.964433)
		(end 112.58 93.075)
		(width 0.15)
		(layer "In7.Cu")
		(net 1266)
	)
	(arc
		(start 113.0775 91.6525)
		(mid 113.107522 91.580022)
		(end 113.18 91.55)
		(width 0.15)
		(layer "In7.Cu")
		(net 1266)
	)
	(arc
		(start 106.862919 97.0975)
		(mid 107.129852 96.986933)
		(end 107.240419 96.72)
		(width 0.15)
		(layer "In7.Cu")
		(net 1266)
	)
	(arc
		(start 110.3 93.375)
		(mid 110.566933 93.264433)
		(end 110.6775 92.9975)
		(width 0.15)
		(layer "In7.Cu")
		(net 1266)
	)
	(arc
		(start 114.6025 91.86)
		(mid 114.713067 92.126933)
		(end 114.98 92.2375)
		(width 0.15)
		(layer "In7.Cu")
		(net 1266)
	)
	(arc
		(start 107.242891 103.8)
		(mid 107.132324 103.533067)
		(end 106.865391 103.4225)
		(width 0.15)
		(layer "In7.Cu")
		(net 1266)
	)
	(arc
		(start 109.1 92.2375)
		(mid 109.366933 92.126933)
		(end 109.4775 91.86)
		(width 0.15)
		(layer "In7.Cu")
		(net 1266)
	)
	(arc
		(start 114.2775 91.7025)
		(mid 114.307522 91.630022)
		(end 114.38 91.6)
		(width 0.15)
		(layer "In7.Cu")
		(net 1266)
	)
	(segment
		(start 91.605 91.7)
		(end 91.92 92.015)
		(width 0.19)
		(layer "F.Cu")
		(net 1267)
	)
	(segment
		(start 91.58 91.7)
		(end 91.605 91.7)
		(width 0.19)
		(layer "F.Cu")
		(net 1267)
	)
	(segment
		(start 92.085 92.015)
		(end 92.2 91.9)
		(width 0.19)
		(layer "F.Cu")
		(net 1267)
	)
	(segment
		(start 116.695532 74.715)
		(end 116.580532 74.6)
		(width 0.19)
		(layer "F.Cu")
		(net 1267)
	)
	(segment
		(start 116.695532 74.885)
		(end 116.695532 74.715)
		(width 0.19)
		(layer "F.Cu")
		(net 1267)
	)
	(segment
		(start 116.430532 75.15)
		(end 116.695532 74.885)
		(width 0.19)
		(layer "F.Cu")
		(net 1267)
	)
	(segment
		(start 91.92 92.015)
		(end 92.085 92.015)
		(width 0.19)
		(layer "F.Cu")
		(net 1267)
	)
	(via
		(at 92.2 91.9)
		(size 0.45)
		(drill 0.1)
		(layers "F.Cu" "B.Cu")
		(net 1267)
	)
	(via
		(at 116.580532 74.6)
		(size 0.45)
		(drill 0.1)
		(layers "F.Cu" "B.Cu")
		(net 1267)
	)
	(segment
		(start 91.443044 92.0625)
		(end 92.0375 92.0625)
		(width 0.15)
		(layer "In7.Cu")
		(net 1267)
	)
	(segment
		(start 121.6375 75.393044)
		(end 122.2375 75.993044)
		(width 0.15)
		(layer "In7.Cu")
		(net 1267)
	)
	(segment
		(start 121.8375 78.493044)
		(end 122.2375 78.893044)
		(width 0.15)
		(layer "In7.Cu")
		(net 1267)
	)
	(segment
		(start 92.743044 104.7375)
		(end 90.843044 104.7375)
		(width 0.15)
		(layer "In7.Cu")
		(net 1267)
	)
	(segment
		(start 98.743044 110.7375)
		(end 92.743044 104.7375)
		(width 0.15)
		(layer "In7.Cu")
		(net 1267)
	)
	(segment
		(start 122.2375 80.056956)
		(end 121.6875 80.606956)
		(width 0.15)
		(layer "In7.Cu")
		(net 1267)
	)
	(segment
		(start 111.056956 93.6375)
		(end 107.8375 96.856956)
		(width 0.15)
		(layer "In7.Cu")
		(net 1267)
	)
	(segment
		(start 122.2375 77.306956)
		(end 121.8375 77.706956)
		(width 0.15)
		(layer "In7.Cu")
		(net 1267)
	)
	(segment
		(start 90.843044 104.7375)
		(end 88.9625 102.856956)
		(width 0.15)
		(layer "In7.Cu")
		(net 1267)
	)
	(segment
		(start 117.243044 72.8625)
		(end 120.456956 72.8625)
		(width 0.15)
		(layer "In7.Cu")
		(net 1267)
	)
	(segment
		(start 116.743032 74.4375)
		(end 116.743032 73.362512)
		(width 0.15)
		(layer "In7.Cu")
		(net 1267)
	)
	(segment
		(start 107.8375 108.356956)
		(end 105.456956 110.7375)
		(width 0.15)
		(layer "In7.Cu")
		(net 1267)
	)
	(segment
		(start 107.8375 96.856956)
		(end 107.8375 108.356956)
		(width 0.15)
		(layer "In7.Cu")
		(net 1267)
	)
	(segment
		(start 90.8625 92.643044)
		(end 91.443044 92.0625)
		(width 0.15)
		(layer "In7.Cu")
		(net 1267)
	)
	(segment
		(start 121.7375 84.493044)
		(end 122.2875 85.043044)
		(width 0.15)
		(layer "In7.Cu")
		(net 1267)
	)
	(segment
		(start 122.2375 78.893044)
		(end 122.2375 80.056956)
		(width 0.15)
		(layer "In7.Cu")
		(net 1267)
	)
	(segment
		(start 121.8375 77.706956)
		(end 121.8375 78.493044)
		(width 0.15)
		(layer "In7.Cu")
		(net 1267)
	)
	(segment
		(start 120.456956 72.8625)
		(end 120.9375 73.343044)
		(width 0.15)
		(layer "In7.Cu")
		(net 1267)
	)
	(segment
		(start 88.9625 102.856956)
		(end 88.9625 95.343044)
		(width 0.15)
		(layer "In7.Cu")
		(net 1267)
	)
	(segment
		(start 121.6875 81.293044)
		(end 122.3375 81.943044)
		(width 0.15)
		(layer "In7.Cu")
		(net 1267)
	)
	(segment
		(start 121.6875 80.606956)
		(end 121.6875 81.293044)
		(width 0.15)
		(layer "In7.Cu")
		(net 1267)
	)
	(segment
		(start 122.3375 81.943044)
		(end 122.3375 83.256956)
		(width 0.15)
		(layer "In7.Cu")
		(net 1267)
	)
	(segment
		(start 120.9375 73.693044)
		(end 121.6375 74.393044)
		(width 0.15)
		(layer "In7.Cu")
		(net 1267)
	)
	(segment
		(start 116.743032 73.362512)
		(end 117.243044 72.8625)
		(width 0.15)
		(layer "In7.Cu")
		(net 1267)
	)
	(segment
		(start 122.2875 85.043044)
		(end 122.2875 87.406956)
		(width 0.15)
		(layer "In7.Cu")
		(net 1267)
	)
	(segment
		(start 121.7375 83.856956)
		(end 121.7375 84.493044)
		(width 0.15)
		(layer "In7.Cu")
		(net 1267)
	)
	(segment
		(start 120.9375 73.343044)
		(end 120.9375 73.693044)
		(width 0.15)
		(layer "In7.Cu")
		(net 1267)
	)
	(segment
		(start 105.456956 110.7375)
		(end 98.743044 110.7375)
		(width 0.15)
		(layer "In7.Cu")
		(net 1267)
	)
	(segment
		(start 116.580532 74.6)
		(end 116.743032 74.4375)
		(width 0.15)
		(layer "In7.Cu")
		(net 1267)
	)
	(segment
		(start 122.2375 75.993044)
		(end 122.2375 77.306956)
		(width 0.15)
		(layer "In7.Cu")
		(net 1267)
	)
	(segment
		(start 90.8625 93.443044)
		(end 90.8625 92.643044)
		(width 0.15)
		(layer "In7.Cu")
		(net 1267)
	)
	(segment
		(start 122.2875 87.406956)
		(end 116.056956 93.6375)
		(width 0.15)
		(layer "In7.Cu")
		(net 1267)
	)
	(segment
		(start 92.0375 92.0625)
		(end 92.2 91.9)
		(width 0.15)
		(layer "In7.Cu")
		(net 1267)
	)
	(segment
		(start 122.3375 83.256956)
		(end 121.7375 83.856956)
		(width 0.15)
		(layer "In7.Cu")
		(net 1267)
	)
	(segment
		(start 88.9625 95.343044)
		(end 90.8625 93.443044)
		(width 0.15)
		(layer "In7.Cu")
		(net 1267)
	)
	(segment
		(start 116.056956 93.6375)
		(end 111.056956 93.6375)
		(width 0.15)
		(layer "In7.Cu")
		(net 1267)
	)
	(segment
		(start 121.6375 74.393044)
		(end 121.6375 75.393044)
		(width 0.15)
		(layer "In7.Cu")
		(net 1267)
	)
	(segment
		(start 116.695532 81.985)
		(end 116.580532 82.1)
		(width 0.19)
		(layer "F.Cu")
		(net 1268)
	)
	(segment
		(start 91.605 101.2)
		(end 91.92 100.885)
		(width 0.19)
		(layer "F.Cu")
		(net 1268)
	)
	(segment
		(start 116.430532 81.15)
		(end 116.695532 81.415)
		(width 0.19)
		(layer "F.Cu")
		(net 1268)
	)
	(segment
		(start 91.92 100.885)
		(end 92.485 100.885)
		(width 0.19)
		(layer "F.Cu")
		(net 1268)
	)
	(segment
		(start 92.485 100.885)
		(end 92.6 101)
		(width 0.19)
		(layer "F.Cu")
		(net 1268)
	)
	(segment
		(start 116.695532 81.415)
		(end 116.695532 81.985)
		(width 0.19)
		(layer "F.Cu")
		(net 1268)
	)
	(segment
		(start 91.58 101.2)
		(end 91.605 101.2)
		(width 0.19)
		(layer "F.Cu")
		(net 1268)
	)
	(via
		(at 92.6 101)
		(size 0.45)
		(drill 0.1)
		(layers "F.Cu" "B.Cu")
		(net 1268)
	)
	(via
		(at 116.580532 82.1)
		(size 0.45)
		(drill 0.1)
		(layers "F.Cu" "B.Cu")
		(net 1268)
	)
	(segment
		(start 94.056956 100.8375)
		(end 92.7625 100.8375)
		(width 0.15)
		(layer "In7.Cu")
		(net 1268)
	)
	(segment
		(start 115.585317 82.601792)
		(end 115.634814 82.552294)
		(width 0.15)
		(layer "In7.Cu")
		(net 1268)
	)
	(segment
		(start 98.731916 102.1025)
		(end 100.1125 102.1025)
		(width 0.15)
		(layer "In7.Cu")
		(net 1268)
	)
	(segment
		(start 100.1125 100.8025)
		(end 100.51 100.8025)
		(width 0.15)
		(layer "In7.Cu")
		(net 1268)
	)
	(segment
		(start 98.731916 106.0025)
		(end 100.1125 106.0025)
		(width 0.15)
		(layer "In7.Cu")
		(net 1268)
	)
	(segment
		(start 94.292717 100.601739)
		(end 94.056956 100.8375)
		(width 0.15)
		(layer "In7.Cu")
		(net 1268)
	)
	(segment
		(start 106.956956 90.4375)
		(end 104.0375 93.356956)
		(width 0.15)
		(layer "In7.Cu")
		(net 1268)
	)
	(segment
		(start 100.3875 106.0025)
		(end 100.668079 106.0025)
		(width 0.15)
		(layer "In7.Cu")
		(net 1268)
	)
	(segment
		(start 100.668079 103.0275)
		(end 100.3875 103.0275)
		(width 0.15)
		(layer "In7.Cu")
		(net 1268)
	)
	(segment
		(start 98.784408 103.93)
		(end 98.784408 103.8)
		(width 0.15)
		(layer "In7.Cu")
		(net 1268)
	)
	(segment
		(start 100.790579 101.98)
		(end 100.790579 101.85)
		(width 0.15)
		(layer "In7.Cu")
		(net 1268)
	)
	(segment
		(start 98.773044 97.009416)
		(end 98.643044 97.009416)
		(width 0.15)
		(layer "In7.Cu")
		(net 1268)
	)
	(segment
		(start 98.520544 97.131916)
		(end 98.520544 98.39)
		(width 0.15)
		(layer "In7.Cu")
		(net 1268)
	)
	(segment
		(start 100.1125 106.0025)
		(end 100.3875 106.0025)
		(width 0.15)
		(layer "In7.Cu")
		(net 1268)
	)
	(segment
		(start 115.635975 82.05848)
		(end 116.156956 81.5375)
		(width 0.15)
		(layer "In7.Cu")
		(net 1268)
	)
	(segment
		(start 100.790579 104.58)
		(end 100.790579 104.45)
		(width 0.15)
		(layer "In7.Cu")
		(net 1268)
	)
	(segment
		(start 101.068084 106.9275)
		(end 100.51 106.9275)
		(width 0.15)
		(layer "In7.Cu")
		(net 1268)
	)
	(segment
		(start 100.668079 100.4275)
		(end 100.51 100.4275)
		(width 0.15)
		(layer "In7.Cu")
		(net 1268)
	)
	(segment
		(start 109.356956 89.1375)
		(end 108.056956 90.4375)
		(width 0.15)
		(layer "In7.Cu")
		(net 1268)
	)
	(segment
		(start 116.743032 81.737488)
		(end 116.743032 81.9375)
		(width 0.15)
		(layer "In7.Cu")
		(net 1268)
	)
	(segment
		(start 98.731916 104.7025)
		(end 100.1125 104.7025)
		(width 0.15)
		(layer "In7.Cu")
		(net 1268)
	)
	(segment
		(start 100.790579 100.68)
		(end 100.790579 100.55)
		(width 0.15)
		(layer "In7.Cu")
		(net 1268)
	)
	(segment
		(start 97.595544 98.7875)
		(end 97.595544 98.39)
		(width 0.15)
		(layer "In7.Cu")
		(net 1268)
	)
	(segment
		(start 100.790579 105.88)
		(end 100.790579 105.75)
		(width 0.15)
		(layer "In7.Cu")
		(net 1268)
	)
	(segment
		(start 115.33899 82.553455)
		(end 115.387327 82.601792)
		(width 0.15)
		(layer "In7.Cu")
		(net 1268)
	)
	(segment
		(start 96.106956 98.7875)
		(end 94.292717 100.601739)
		(width 0.15)
		(layer "In7.Cu")
		(net 1268)
	)
	(segment
		(start 108.056956 90.4375)
		(end 106.956956 90.4375)
		(width 0.15)
		(layer "In7.Cu")
		(net 1268)
	)
	(segment
		(start 97.473044 97.009395)
		(end 97.343044 97.009395)
		(width 0.15)
		(layer "In7.Cu")
		(net 1268)
	)
	(segment
		(start 100.3875 104.7025)
		(end 100.668079 104.7025)
		(width 0.15)
		(layer "In7.Cu")
		(net 1268)
	)
	(segment
		(start 100.3875 102.1025)
		(end 100.668079 102.1025)
		(width 0.15)
		(layer "In7.Cu")
		(net 1268)
	)
	(segment
		(start 105.0375 107.556956)
		(end 104.256956 108.3375)
		(width 0.15)
		(layer "In7.Cu")
		(net 1268)
	)
	(segment
		(start 115.141001 82.553455)
		(end 114.9375 82.756956)
		(width 0.15)
		(layer "In7.Cu")
		(net 1268)
	)
	(segment
		(start 100.668079 101.7275)
		(end 100.3875 101.7275)
		(width 0.15)
		(layer "In7.Cu")
		(net 1268)
	)
	(segment
		(start 100.3875 104.3275)
		(end 100.1125 104.3275)
		(width 0.15)
		(layer "In7.Cu")
		(net 1268)
	)
	(segment
		(start 98.334416 101.33)
		(end 98.334416 101.2)
		(width 0.15)
		(layer "In7.Cu")
		(net 1268)
	)
	(segment
		(start 100.51 100.8025)
		(end 100.668079 100.8025)
		(width 0.15)
		(layer "In7.Cu")
		(net 1268)
	)
	(segment
		(start 98.123044 100.315599)
		(end 97.993044 100.315599)
		(width 0.15)
		(layer "In7.Cu")
		(net 1268)
	)
	(segment
		(start 97.220544 97.131895)
		(end 97.220544 98.39)
		(width 0.15)
		(layer "In7.Cu")
		(net 1268)
	)
	(segment
		(start 100.543044 108.3375)
		(end 100.1125 107.906956)
		(width 0.15)
		(layer "In7.Cu")
		(net 1268)
	)
	(segment
		(start 115.634814 82.354304)
		(end 115.586476 82.305966)
		(width 0.15)
		(layer "In7.Cu")
		(net 1268)
	)
	(segment
		(start 100.1125 102.1025)
		(end 100.3875 102.1025)
		(width 0.15)
		(layer "In7.Cu")
		(net 1268)
	)
	(segment
		(start 97.595544 99.918099)
		(end 97.595544 98.7875)
		(width 0.15)
		(layer "In7.Cu")
		(net 1268)
	)
	(segment
		(start 96.693044 98.7875)
		(end 96.106956 98.7875)
		(width 0.15)
		(layer "In7.Cu")
		(net 1268)
	)
	(segment
		(start 100.1125 104.3275)
		(end 99.181908 104.3275)
		(width 0.15)
		(layer "In7.Cu")
		(net 1268)
	)
	(segment
		(start 100.51 107.3025)
		(end 101.068084 107.3025)
		(width 0.15)
		(layer "In7.Cu")
		(net 1268)
	)
	(segment
		(start 114.9375 85.356956)
		(end 111.156956 89.1375)
		(width 0.15)
		(layer "In7.Cu")
		(net 1268)
	)
	(segment
		(start 100.1125 99.606956)
		(end 99.293044 98.7875)
		(width 0.15)
		(layer "In7.Cu")
		(net 1268)
	)
	(segment
		(start 100.1125 103.0275)
		(end 98.731916 103.0275)
		(width 0.15)
		(layer "In7.Cu")
		(net 1268)
	)
	(segment
		(start 100.1125 100.03)
		(end 100.1125 99.9)
		(width 0.15)
		(layer "In7.Cu")
		(net 1268)
	)
	(segment
		(start 100.1125 105.6275)
		(end 98.731916 105.6275)
		(width 0.15)
		(layer "In7.Cu")
		(net 1268)
	)
	(segment
		(start 98.334416 105.23)
		(end 98.334416 105.1)
		(width 0.15)
		(layer "In7.Cu")
		(net 1268)
	)
	(segment
		(start 100.3875 105.6275)
		(end 100.1125 105.6275)
		(width 0.15)
		(layer "In7.Cu")
		(net 1268)
	)
	(segment
		(start 100.3875 101.7275)
		(end 100.1125 101.7275)
		(width 0.15)
		(layer "In7.Cu")
		(net 1268)
	)
	(segment
		(start 100.51 106.9275)
		(end 100.1125 106.9275)
		(width 0.15)
		(layer "In7.Cu")
		(net 1268)
	)
	(segment
		(start 105.0375 103.143044)
		(end 105.0375 107.556956)
		(width 0.15)
		(layer "In7.Cu")
		(net 1268)
	)
	(segment
		(start 114.9375 82.756956)
		(end 114.9375 85.356956)
		(width 0.15)
		(layer "In7.Cu")
		(net 1268)
	)
	(segment
		(start 104.256956 108.3375)
		(end 100.543044 108.3375)
		(width 0.15)
		(layer "In7.Cu")
		(net 1268)
	)
	(segment
		(start 111.156956 89.1375)
		(end 109.356956 89.1375)
		(width 0.15)
		(layer "In7.Cu")
		(net 1268)
	)
	(segment
		(start 100.668079 104.3275)
		(end 100.3875 104.3275)
		(width 0.15)
		(layer "In7.Cu")
		(net 1268)
	)
	(segment
		(start 104.0375 102.143044)
		(end 105.0375 103.143044)
		(width 0.15)
		(layer "In7.Cu")
		(net 1268)
	)
	(segment
		(start 100.1125 103.4025)
		(end 100.3875 103.4025)
		(width 0.15)
		(layer "In7.Cu")
		(net 1268)
	)
	(segment
		(start 100.3875 103.0275)
		(end 100.1125 103.0275)
		(width 0.15)
		(layer "In7.Cu")
		(net 1268)
	)
	(segment
		(start 96.823044 98.7875)
		(end 96.693044 98.7875)
		(width 0.15)
		(layer "In7.Cu")
		(net 1268)
	)
	(segment
		(start 100.1125 106.9275)
		(end 98.731916 106.9275)
		(width 0.15)
		(layer "In7.Cu")
		(net 1268)
	)
	(segment
		(start 100.790579 103.28)
		(end 100.790579 103.15)
		(width 0.15)
		(layer "In7.Cu")
		(net 1268)
	)
	(segment
		(start 101.190584 107.18)
		(end 101.190584 107.05)
		(width 0.15)
		(layer "In7.Cu")
		(net 1268)
	)
	(segment
		(start 98.334416 106.53)
		(end 98.334416 106.4)
		(width 0.15)
		(layer "In7.Cu")
		(net 1268)
	)
	(segment
		(start 98.520544 98.7875)
		(end 98.520544 99.918099)
		(width 0.15)
		(layer "In7.Cu")
		(net 1268)
	)
	(segment
		(start 100.1125 101.7275)
		(end 98.731916 101.7275)
		(width 0.15)
		(layer "In7.Cu")
		(net 1268)
	)
	(segment
		(start 116.743032 81.9375)
		(end 116.580532 82.1)
		(width 0.15)
		(layer "In7.Cu")
		(net 1268)
	)
	(segment
		(start 100.1125 107.906956)
		(end 100.1125 107.7)
		(width 0.15)
		(layer "In7.Cu")
		(net 1268)
	)
	(segment
		(start 99.181908 103.4025)
		(end 100.1125 103.4025)
		(width 0.15)
		(layer "In7.Cu")
		(net 1268)
	)
	(segment
		(start 116.156956 81.5375)
		(end 116.543044 81.5375)
		(width 0.15)
		(layer "In7.Cu")
		(net 1268)
	)
	(segment
		(start 98.731916 100.8025)
		(end 100.1125 100.8025)
		(width 0.15)
		(layer "In7.Cu")
		(net 1268)
	)
	(segment
		(start 116.543044 81.5375)
		(end 116.743032 81.737488)
		(width 0.15)
		(layer "In7.Cu")
		(net 1268)
	)
	(segment
		(start 104.0375 93.356956)
		(end 104.0375 102.143044)
		(width 0.15)
		(layer "In7.Cu")
		(net 1268)
	)
	(segment
		(start 100.1125 104.7025)
		(end 100.3875 104.7025)
		(width 0.15)
		(layer "In7.Cu")
		(net 1268)
	)
	(segment
		(start 100.668079 105.6275)
		(end 100.3875 105.6275)
		(width 0.15)
		(layer "In7.Cu")
		(net 1268)
	)
	(segment
		(start 98.520544 98.39)
		(end 98.520544 98.7875)
		(width 0.15)
		(layer "In7.Cu")
		(net 1268)
	)
	(segment
		(start 98.895544 98.39)
		(end 98.895544 97.131916)
		(width 0.15)
		(layer "In7.Cu")
		(net 1268)
	)
	(segment
		(start 115.586476 82.107976)
		(end 115.635975 82.05848)
		(width 0.15)
		(layer "In7.Cu")
		(net 1268)
	)
	(segment
		(start 92.7625 100.8375)
		(end 92.6 101)
		(width 0.15)
		(layer "In7.Cu")
		(net 1268)
	)
	(segment
		(start 100.1125 99.9)
		(end 100.1125 99.606956)
		(width 0.15)
		(layer "In7.Cu")
		(net 1268)
	)
	(segment
		(start 97.595544 98.39)
		(end 97.595544 97.131895)
		(width 0.15)
		(layer "In7.Cu")
		(net 1268)
	)
	(segment
		(start 98.334416 102.63)
		(end 98.334416 102.5)
		(width 0.15)
		(layer "In7.Cu")
		(net 1268)
	)
	(segment
		(start 100.3875 103.4025)
		(end 100.668079 103.4025)
		(width 0.15)
		(layer "In7.Cu")
		(net 1268)
	)
	(arc
		(start 115.387327 82.601792)
		(mid 115.486322 82.642797)
		(end 115.585317 82.601792)
		(width 0.15)
		(layer "In7.Cu")
		(net 1268)
	)
	(arc
		(start 98.895544 97.131916)
		(mid 98.859665 97.045295)
		(end 98.773044 97.009416)
		(width 0.15)
		(layer "In7.Cu")
		(net 1268)
	)
	(arc
		(start 98.731916 106.9275)
		(mid 98.450841 106.811075)
		(end 98.334416 106.53)
		(width 0.15)
		(layer "In7.Cu")
		(net 1268)
	)
	(arc
		(start 100.668079 106.0025)
		(mid 100.7547 105.966621)
		(end 100.790579 105.88)
		(width 0.15)
		(layer "In7.Cu")
		(net 1268)
	)
	(arc
		(start 98.731916 105.6275)
		(mid 98.450841 105.511075)
		(end 98.334416 105.23)
		(width 0.15)
		(layer "In7.Cu")
		(net 1268)
	)
	(arc
		(start 100.668079 104.7025)
		(mid 100.7547 104.666621)
		(end 100.790579 104.58)
		(width 0.15)
		(layer "In7.Cu")
		(net 1268)
	)
	(arc
		(start 98.784408 103.8)
		(mid 98.900833 103.518925)
		(end 99.181908 103.4025)
		(width 0.15)
		(layer "In7.Cu")
		(net 1268)
	)
	(arc
		(start 99.293044 98.7875)
		(mid 99.011969 98.671075)
		(end 98.895544 98.39)
		(width 0.15)
		(layer "In7.Cu")
		(net 1268)
	)
	(arc
		(start 98.334416 102.5)
		(mid 98.450841 102.218925)
		(end 98.731916 102.1025)
		(width 0.15)
		(layer "In7.Cu")
		(net 1268)
	)
	(arc
		(start 98.731916 101.7275)
		(mid 98.450841 101.611075)
		(end 98.334416 101.33)
		(width 0.15)
		(layer "In7.Cu")
		(net 1268)
	)
	(arc
		(start 101.190584 107.05)
		(mid 101.154705 106.963379)
		(end 101.068084 106.9275)
		(width 0.15)
		(layer "In7.Cu")
		(net 1268)
	)
	(arc
		(start 100.790579 100.55)
		(mid 100.7547 100.463379)
		(end 100.668079 100.4275)
		(width 0.15)
		(layer "In7.Cu")
		(net 1268)
	)
	(arc
		(start 97.993044 100.315599)
		(mid 97.711969 100.199174)
		(end 97.595544 99.918099)
		(width 0.15)
		(layer "In7.Cu")
		(net 1268)
	)
	(arc
		(start 100.51 100.4275)
		(mid 100.228925 100.311075)
		(end 100.1125 100.03)
		(width 0.15)
		(layer "In7.Cu")
		(net 1268)
	)
	(arc
		(start 115.141001 82.553455)
		(mid 115.239995 82.51245)
		(end 115.33899 82.553455)
		(width 0.15)
		(layer "In7.Cu")
		(net 1268)
	)
	(arc
		(start 100.1125 107.7)
		(mid 100.228925 107.418925)
		(end 100.51 107.3025)
		(width 0.15)
		(layer "In7.Cu")
		(net 1268)
	)
	(arc
		(start 98.643044 97.009416)
		(mid 98.556423 97.045295)
		(end 98.520544 97.131916)
		(width 0.15)
		(layer "In7.Cu")
		(net 1268)
	)
	(arc
		(start 100.790579 105.75)
		(mid 100.7547 105.663379)
		(end 100.668079 105.6275)
		(width 0.15)
		(layer "In7.Cu")
		(net 1268)
	)
	(arc
		(start 97.343044 97.009395)
		(mid 97.256423 97.045274)
		(end 97.220544 97.131895)
		(width 0.15)
		(layer "In7.Cu")
		(net 1268)
	)
	(arc
		(start 99.181908 104.3275)
		(mid 98.900833 104.211075)
		(end 98.784408 103.93)
		(width 0.15)
		(layer "In7.Cu")
		(net 1268)
	)
	(arc
		(start 98.520544 99.918099)
		(mid 98.404119 100.199174)
		(end 98.123044 100.315599)
		(width 0.15)
		(layer "In7.Cu")
		(net 1268)
	)
	(arc
		(start 101.068084 107.3025)
		(mid 101.154705 107.266621)
		(end 101.190584 107.18)
		(width 0.15)
		(layer "In7.Cu")
		(net 1268)
	)
	(arc
		(start 100.668079 102.1025)
		(mid 100.7547 102.066621)
		(end 100.790579 101.98)
		(width 0.15)
		(layer "In7.Cu")
		(net 1268)
	)
	(arc
		(start 100.668079 103.4025)
		(mid 100.7547 103.366621)
		(end 100.790579 103.28)
		(width 0.15)
		(layer "In7.Cu")
		(net 1268)
	)
	(arc
		(start 115.634814 82.552294)
		(mid 115.675819 82.453299)
		(end 115.634814 82.354304)
		(width 0.15)
		(layer "In7.Cu")
		(net 1268)
	)
	(arc
		(start 98.334416 101.2)
		(mid 98.450841 100.918925)
		(end 98.731916 100.8025)
		(width 0.15)
		(layer "In7.Cu")
		(net 1268)
	)
	(arc
		(start 100.790579 104.45)
		(mid 100.7547 104.363379)
		(end 100.668079 104.3275)
		(width 0.15)
		(layer "In7.Cu")
		(net 1268)
	)
	(arc
		(start 98.334416 105.1)
		(mid 98.450841 104.818925)
		(end 98.731916 104.7025)
		(width 0.15)
		(layer "In7.Cu")
		(net 1268)
	)
	(arc
		(start 100.790579 103.15)
		(mid 100.7547 103.063379)
		(end 100.668079 103.0275)
		(width 0.15)
		(layer "In7.Cu")
		(net 1268)
	)
	(arc
		(start 115.586476 82.305966)
		(mid 115.545471 82.206971)
		(end 115.586476 82.107976)
		(width 0.15)
		(layer "In7.Cu")
		(net 1268)
	)
	(arc
		(start 98.731916 103.0275)
		(mid 98.450841 102.911075)
		(end 98.334416 102.63)
		(width 0.15)
		(layer "In7.Cu")
		(net 1268)
	)
	(arc
		(start 97.595544 97.131895)
		(mid 97.559665 97.045274)
		(end 97.473044 97.009395)
		(width 0.15)
		(layer "In7.Cu")
		(net 1268)
	)
	(arc
		(start 97.220544 98.39)
		(mid 97.104119 98.671075)
		(end 96.823044 98.7875)
		(width 0.15)
		(layer "In7.Cu")
		(net 1268)
	)
	(arc
		(start 100.790579 101.85)
		(mid 100.7547 101.763379)
		(end 100.668079 101.7275)
		(width 0.15)
		(layer "In7.Cu")
		(net 1268)
	)
	(arc
		(start 98.334416 106.4)
		(mid 98.450841 106.118925)
		(end 98.731916 106.0025)
		(width 0.15)
		(layer "In7.Cu")
		(net 1268)
	)
	(arc
		(start 100.668079 100.8025)
		(mid 100.7547 100.766621)
		(end 100.790579 100.68)
		(width 0.15)
		(layer "In7.Cu")
		(net 1268)
	)
	(segment
		(start 118.430532 73.65)
		(end 118.695532 73.915)
		(width 0.19)
		(layer "F.Cu")
		(net 1269)
	)
	(segment
		(start 91.605 97.3)
		(end 91.92 97.615)
		(width 0.19)
		(layer "F.Cu")
		(net 1269)
	)
	(segment
		(start 118.695532 74.485)
		(end 118.580532 74.6)
		(width 0.19)
		(layer "F.Cu")
		(net 1269)
	)
	(segment
		(start 92.285 97.615)
		(end 92.4 97.5)
		(width 0.19)
		(layer "F.Cu")
		(net 1269)
	)
	(segment
		(start 91.92 97.615)
		(end 92.285 97.615)
		(width 0.19)
		(layer "F.Cu")
		(net 1269)
	)
	(segment
		(start 91.58 97.3)
		(end 91.605 97.3)
		(width 0.19)
		(layer "F.Cu")
		(net 1269)
	)
	(segment
		(start 118.695532 73.915)
		(end 118.695532 74.485)
		(width 0.19)
		(layer "F.Cu")
		(net 1269)
	)
	(via
		(at 118.580532 74.6)
		(size 0.45)
		(drill 0.1)
		(layers "F.Cu" "B.Cu")
		(net 1269)
	)
	(via
		(at 92.4 97.5)
		(size 0.45)
		(drill 0.1)
		(layers "F.Cu" "B.Cu")
		(net 1269)
	)
	(segment
		(start 98.141676 103.977372)
		(end 96.656752 105.462297)
		(width 0.15)
		(layer "In7.Cu")
		(net 1269)
	)
	(segment
		(start 97.320548 106.515004)
		(end 97.867128 107.061584)
		(width 0.15)
		(layer "In7.Cu")
		(net 1269)
	)
	(segment
		(start 97.177358 106.371815)
		(end 97.320548 106.515004)
		(width 0.15)
		(layer "In7.Cu")
		(net 1269)
	)
	(segment
		(start 118.743032 74.262512)
		(end 118.743032 74.4375)
		(width 0.15)
		(layer "In7.Cu")
		(net 1269)
	)
	(segment
		(start 99.943044 109.1375)
		(end 104.656956 109.1375)
		(width 0.15)
		(layer "In7.Cu")
		(net 1269)
	)
	(segment
		(start 96.656752 105.462297)
		(end 96.559524 105.559525)
		(width 0.15)
		(layer "In7.Cu")
		(net 1269)
	)
	(segment
		(start 118.743032 74.4375)
		(end 118.580532 74.6)
		(width 0.15)
		(layer "In7.Cu")
		(net 1269)
	)
	(segment
		(start 119.143044 73.8625)
		(end 118.743032 74.262512)
		(width 0.15)
		(layer "In7.Cu")
		(net 1269)
	)
	(segment
		(start 95.482071 105.309389)
		(end 95.62526 105.452578)
		(width 0.15)
		(layer "In7.Cu")
		(net 1269)
	)
	(segment
		(start 119.756956 73.8625)
		(end 119.143044 73.8625)
		(width 0.15)
		(layer "In7.Cu")
		(net 1269)
	)
	(segment
		(start 92.2375 97.6625)
		(end 91.743044 97.6625)
		(width 0.15)
		(layer "In7.Cu")
		(net 1269)
	)
	(segment
		(start 96.401309 106.228626)
		(end 96.544498 106.371815)
		(width 0.15)
		(layer "In7.Cu")
		(net 1269)
	)
	(segment
		(start 94.904897 103.537202)
		(end 94.72105 103.721049)
		(width 0.15)
		(layer "In7.Cu")
		(net 1269)
	)
	(segment
		(start 97.505283 102.775294)
		(end 95.737515 104.543059)
		(width 0.15)
		(layer "In7.Cu")
		(net 1269)
	)
	(segment
		(start 107.956956 91.4375)
		(end 108.556956 91.4375)
		(width 0.15)
		(layer "In7.Cu")
		(net 1269)
	)
	(segment
		(start 116.1375 88.256956)
		(end 116.1375 87.256956)
		(width 0.15)
		(layer "In7.Cu")
		(net 1269)
	)
	(segment
		(start 96.559524 105.559525)
		(end 96.559525 105.559525)
		(width 0.15)
		(layer "In7.Cu")
		(net 1269)
	)
	(segment
		(start 95.216909 104.533341)
		(end 95.277896 104.472353)
		(width 0.15)
		(layer "In7.Cu")
		(net 1269)
	)
	(segment
		(start 97.41336 102.510131)
		(end 97.505283 102.602054)
		(width 0.15)
		(layer "In7.Cu")
		(net 1269)
	)
	(segment
		(start 104.656956 109.1375)
		(end 105.8375 107.956956)
		(width 0.15)
		(layer "In7.Cu")
		(net 1269)
	)
	(segment
		(start 105.8375 107.956956)
		(end 105.8375 101.243044)
		(width 0.15)
		(layer "In7.Cu")
		(net 1269)
	)
	(segment
		(start 116.1375 87.256956)
		(end 116.956956 86.4375)
		(width 0.15)
		(layer "In7.Cu")
		(net 1269)
	)
	(segment
		(start 95.737515 104.543059)
		(end 95.543059 104.737515)
		(width 0.15)
		(layer "In7.Cu")
		(net 1269)
	)
	(segment
		(start 96.494121 101.590891)
		(end 96.586044 101.682814)
		(width 0.15)
		(layer "In7.Cu")
		(net 1269)
	)
	(segment
		(start 91.743044 102.8375)
		(end 93.643044 102.8375)
		(width 0.15)
		(layer "In7.Cu")
		(net 1269)
	)
	(segment
		(start 96.559525 105.559525)
		(end 96.498537 105.620512)
		(width 0.15)
		(layer "In7.Cu")
		(net 1269)
	)
	(segment
		(start 95.375124 104.375124)
		(end 95.472353 104.277898)
		(width 0.15)
		(layer "In7.Cu")
		(net 1269)
	)
	(segment
		(start 98.049753 103.712209)
		(end 98.141676 103.804132)
		(width 0.15)
		(layer "In7.Cu")
		(net 1269)
	)
	(segment
		(start 120.9875 76.243044)
		(end 120.2375 75.493044)
		(width 0.15)
		(layer "In7.Cu")
		(net 1269)
	)
	(segment
		(start 94.077584 103.27204)
		(end 94.077583 103.272038)
		(width 0.15)
		(layer "In7.Cu")
		(net 1269)
	)
	(segment
		(start 96.197133 105.39159)
		(end 96.294361 105.294361)
		(width 0.15)
		(layer "In7.Cu")
		(net 1269)
	)
	(segment
		(start 96.294361 105.294361)
		(end 96.39159 105.197135)
		(width 0.15)
		(layer "In7.Cu")
		(net 1269)
	)
	(segment
		(start 118.606956 86.4375)
		(end 120.9875 84.056956)
		(width 0.15)
		(layer "In7.Cu")
		(net 1269)
	)
	(segment
		(start 94.72105 103.721049)
		(end 94.623822 103.818278)
		(width 0.15)
		(layer "In7.Cu")
		(net 1269)
	)
	(segment
		(start 90.9625 98.443044)
		(end 90.9625 102.056956)
		(width 0.15)
		(layer "In7.Cu")
		(net 1269)
	)
	(segment
		(start 90.9625 102.056956)
		(end 91.743044 102.8375)
		(width 0.15)
		(layer "In7.Cu")
		(net 1269)
	)
	(segment
		(start 105.6375 93.756956)
		(end 107.956956 91.4375)
		(width 0.15)
		(layer "In7.Cu")
		(net 1269)
	)
	(segment
		(start 96.586044 101.856054)
		(end 94.904897 103.537202)
		(width 0.15)
		(layer "In7.Cu")
		(net 1269)
	)
	(segment
		(start 91.743044 97.6625)
		(end 90.9625 98.443044)
		(width 0.15)
		(layer "In7.Cu")
		(net 1269)
	)
	(segment
		(start 105.8375 101.243044)
		(end 105.6375 101.043044)
		(width 0.15)
		(layer "In7.Cu")
		(net 1269)
	)
	(segment
		(start 120.2375 75.493044)
		(end 120.2375 74.343044)
		(width 0.15)
		(layer "In7.Cu")
		(net 1269)
	)
	(segment
		(start 93.643044 102.8375)
		(end 94.077584 103.27204)
		(width 0.15)
		(layer "In7.Cu")
		(net 1269)
	)
	(segment
		(start 92.4 97.5)
		(end 92.2375 97.6625)
		(width 0.15)
		(layer "In7.Cu")
		(net 1269)
	)
	(segment
		(start 108.556956 91.4375)
		(end 109.756956 90.2375)
		(width 0.15)
		(layer "In7.Cu")
		(net 1269)
	)
	(segment
		(start 95.277896 104.472353)
		(end 95.375124 104.375124)
		(width 0.15)
		(layer "In7.Cu")
		(net 1269)
	)
	(segment
		(start 96.498537 105.620512)
		(end 96.401309 105.71774)
		(width 0.15)
		(layer "In7.Cu")
		(net 1269)
	)
	(segment
		(start 116.956956 86.4375)
		(end 118.606956 86.4375)
		(width 0.15)
		(layer "In7.Cu")
		(net 1269)
	)
	(segment
		(start 114.156956 90.2375)
		(end 116.1375 88.256956)
		(width 0.15)
		(layer "In7.Cu")
		(net 1269)
	)
	(segment
		(start 96.39159 105.197135)
		(end 97.876515 103.71221)
		(width 0.15)
		(layer "In7.Cu")
		(net 1269)
	)
	(segment
		(start 94.562834 104.390152)
		(end 94.706023 104.533341)
		(width 0.15)
		(layer "In7.Cu")
		(net 1269)
	)
	(segment
		(start 95.472353 104.277898)
		(end 97.24012 102.510131)
		(width 0.15)
		(layer "In7.Cu")
		(net 1269)
	)
	(segment
		(start 96.136146 105.452578)
		(end 96.197133 105.39159)
		(width 0.15)
		(layer "In7.Cu")
		(net 1269)
	)
	(segment
		(start 105.6375 101.043044)
		(end 105.6375 93.756956)
		(width 0.15)
		(layer "In7.Cu")
		(net 1269)
	)
	(segment
		(start 95.543059 104.737515)
		(end 95.482071 104.798502)
		(width 0.15)
		(layer "In7.Cu")
		(net 1269)
	)
	(segment
		(start 109.756956 90.2375)
		(end 114.156956 90.2375)
		(width 0.15)
		(layer "In7.Cu")
		(net 1269)
	)
	(segment
		(start 94.639735 103.272039)
		(end 96.320883 101.590892)
		(width 0.15)
		(layer "In7.Cu")
		(net 1269)
	)
	(segment
		(start 120.9875 84.056956)
		(end 120.9875 76.243044)
		(width 0.15)
		(layer "In7.Cu")
		(net 1269)
	)
	(segment
		(start 94.623822 103.818278)
		(end 94.562834 103.879265)
		(width 0.15)
		(layer "In7.Cu")
		(net 1269)
	)
	(segment
		(start 97.867128 107.061584)
		(end 99.943044 109.1375)
		(width 0.15)
		(layer "In7.Cu")
		(net 1269)
	)
	(segment
		(start 120.2375 74.343044)
		(end 119.756956 73.8625)
		(width 0.15)
		(layer "In7.Cu")
		(net 1269)
	)
	(arc
		(start 97.24012 102.510131)
		(mid 97.326739 102.474251)
		(end 97.41336 102.510131)
		(width 0.15)
		(layer "In7.Cu")
		(net 1269)
	)
	(arc
		(start 94.706023 104.533341)
		(mid 94.961466 104.639149)
		(end 95.216909 104.533341)
		(width 0.15)
		(layer "In7.Cu")
		(net 1269)
	)
	(arc
		(start 96.586044 101.682814)
		(mid 96.621924 101.769435)
		(end 96.586044 101.856054)
		(width 0.15)
		(layer "In7.Cu")
		(net 1269)
	)
	(arc
		(start 97.055384 106.371815)
		(mid 97.116371 106.346553)
		(end 97.177358 106.371815)
		(width 0.15)
		(layer "In7.Cu")
		(net 1269)
	)
	(arc
		(start 95.482071 104.798502)
		(mid 95.376263 105.053945)
		(end 95.482071 105.309389)
		(width 0.15)
		(layer "In7.Cu")
		(net 1269)
	)
	(arc
		(start 98.141676 103.804132)
		(mid 98.177556 103.890753)
		(end 98.141676 103.977372)
		(width 0.15)
		(layer "In7.Cu")
		(net 1269)
	)
	(arc
		(start 97.505283 102.602054)
		(mid 97.541161 102.688673)
		(end 97.505283 102.775294)
		(width 0.15)
		(layer "In7.Cu")
		(net 1269)
	)
	(arc
		(start 96.544498 106.371815)
		(mid 96.799941 106.477623)
		(end 97.055384 106.371815)
		(width 0.15)
		(layer "In7.Cu")
		(net 1269)
	)
	(arc
		(start 96.320883 101.590892)
		(mid 96.407502 101.555013)
		(end 96.494121 101.590891)
		(width 0.15)
		(layer "In7.Cu")
		(net 1269)
	)
	(arc
		(start 94.562834 103.879265)
		(mid 94.457026 104.134708)
		(end 94.562834 104.390152)
		(width 0.15)
		(layer "In7.Cu")
		(net 1269)
	)
	(arc
		(start 96.401309 105.71774)
		(mid 96.295501 105.973183)
		(end 96.401309 106.228626)
		(width 0.15)
		(layer "In7.Cu")
		(net 1269)
	)
	(arc
		(start 95.62526 105.452578)
		(mid 95.880703 105.558386)
		(end 96.136146 105.452578)
		(width 0.15)
		(layer "In7.Cu")
		(net 1269)
	)
	(arc
		(start 94.077583 103.272038)
		(mid 94.35866 103.388464)
		(end 94.639735 103.272039)
		(width 0.15)
		(layer "In7.Cu")
		(net 1269)
	)
	(arc
		(start 97.876515 103.71221)
		(mid 97.963134 103.676331)
		(end 98.049753 103.712209)
		(width 0.15)
		(layer "In7.Cu")
		(net 1269)
	)
	(segment
		(start 119.385 86.56)
		(end 119.385 88.67663)
		(width 0.19)
		(layer "F.Cu")
		(net 1270)
	)
	(segment
		(start 92.285 95.185)
		(end 92.4 95.3)
		(width 0.19)
		(layer "F.Cu")
		(net 1270)
	)
	(segment
		(start 91.92 95.185)
		(end 92.285 95.185)
		(width 0.19)
		(layer "F.Cu")
		(net 1270)
	)
	(segment
		(start 91.605 95.5)
		(end 91.92 95.185)
		(width 0.19)
		(layer "F.Cu")
		(net 1270)
	)
	(segment
		(start 117.415 88.315)
		(end 117.3 88.2)
		(width 0.19)
		(layer "F.Cu")
		(net 1270)
	)
	(segment
		(start 119.385 88.67663)
		(end 118.67663 89.385)
		(width 0.19)
		(layer "F.Cu")
		(net 1270)
	)
	(segment
		(start 91.58 95.5)
		(end 91.605 95.5)
		(width 0.19)
		(layer "F.Cu")
		(net 1270)
	)
	(segment
		(start 117.415 88.87663)
		(end 117.415 88.315)
		(width 0.19)
		(layer "F.Cu")
		(net 1270)
	)
	(segment
		(start 117.92337 89.385)
		(end 117.415 88.87663)
		(width 0.19)
		(layer "F.Cu")
		(net 1270)
	)
	(segment
		(start 119.065532 85.915)
		(end 119.065532 86.240532)
		(width 0.19)
		(layer "F.Cu")
		(net 1270)
	)
	(segment
		(start 118.67663 89.385)
		(end 117.92337 89.385)
		(width 0.19)
		(layer "F.Cu")
		(net 1270)
	)
	(segment
		(start 119.330532 85.65)
		(end 119.065532 85.915)
		(width 0.19)
		(layer "F.Cu")
		(net 1270)
	)
	(segment
		(start 119.065532 86.240532)
		(end 119.385 86.56)
		(width 0.19)
		(layer "F.Cu")
		(net 1270)
	)
	(via
		(at 117.3 88.2)
		(size 0.45)
		(drill 0.1)
		(layers "F.Cu" "B.Cu")
		(net 1270)
	)
	(via
		(at 92.4 95.3)
		(size 0.45)
		(drill 0.1)
		(layers "F.Cu" "B.Cu")
		(net 1270)
	)
	(segment
		(start 112.8025 92.6975)
		(end 112.8025 92.2375)
		(width 0.15)
		(layer "In7.Cu")
		(net 1270)
	)
	(segment
		(start 111.6025 92.6975)
		(end 111.6025 92.2375)
		(width 0.15)
		(layer "In7.Cu")
		(net 1270)
	)
	(segment
		(start 113.78 92.8)
		(end 113.9 92.8)
		(width 0.15)
		(layer "In7.Cu")
		(net 1270)
	)
	(segment
		(start 114.0025 92.2375)
		(end 114.0025 91.86)
		(width 0.15)
		(layer "In7.Cu")
		(net 1270)
	)
	(segment
		(start 106.7375 98.0225)
		(end 106.862919 98.0225)
		(width 0.15)
		(layer "In7.Cu")
		(net 1270)
	)
	(segment
		(start 111.2775 91.9625)
		(end 111.2775 92.2375)
		(width 0.15)
		(layer "In7.Cu")
		(net 1270)
	)
	(segment
		(start 111.2775 91.5025)
		(end 111.2775 91.9625)
		(width 0.15)
		(layer "In7.Cu")
		(net 1270)
	)
	(segment
		(start 92.2375 95.1375)
		(end 91.256956 95.1375)
		(width 0.15)
		(layer "In7.Cu")
		(net 1270)
	)
	(segment
		(start 106.3875 100.4225)
		(end 106.4625 100.4225)
		(width 0.15)
		(layer "In7.Cu")
		(net 1270)
	)
	(segment
		(start 106.865391 104.8975)
		(end 106.84 104.8975)
		(width 0.15)
		(layer "In7.Cu")
		(net 1270)
	)
	(segment
		(start 114.0025 92.6975)
		(end 114.0025 92.2375)
		(width 0.15)
		(layer "In7.Cu")
		(net 1270)
	)
	(segment
		(start 106.4625 101.2975)
		(end 106.3875 101.2975)
		(width 0.15)
		(layer "In7.Cu")
		(net 1270)
	)
	(segment
		(start 106.84 95.6225)
		(end 107.862937 95.6225)
		(width 0.15)
		(layer "In7.Cu")
		(net 1270)
	)
	(segment
		(start 112.4775 92.2375)
		(end 112.4775 92.6975)
		(width 0.15)
		(layer "In7.Cu")
		(net 1270)
	)
	(segment
		(start 106.965419 96.72)
		(end 106.965419 96.6)
		(width 0.15)
		(layer "In7.Cu")
		(net 1270)
	)
	(segment
		(start 105.959581 99.72)
		(end 105.959581 99.6)
		(width 0.15)
		(layer "In7.Cu")
		(net 1270)
	)
	(segment
		(start 90.1375 96.256956)
		(end 90.1375 102.443044)
		(width 0.15)
		(layer "In7.Cu")
		(net 1270)
	)
	(segment
		(start 114.38 91.325)
		(end 114.5 91.325)
		(width 0.15)
		(layer "In7.Cu")
		(net 1270)
	)
	(segment
		(start 113.6775 91.9625)
		(end 113.6775 92.2375)
		(width 0.15)
		(layer "In7.Cu")
		(net 1270)
	)
	(segment
		(start 106.862919 98.8975)
		(end 106.7375 98.8975)
		(width 0.15)
		(layer "In7.Cu")
		(net 1270)
	)
	(segment
		(start 106.967891 105.12)
		(end 106.967891 105)
		(width 0.15)
		(layer "In7.Cu")
		(net 1270)
	)
	(segment
		(start 106.967891 103.92)
		(end 106.967891 103.8)
		(width 0.15)
		(layer "In7.Cu")
		(net 1270)
	)
	(segment
		(start 110.0775 91.8025)
		(end 110.0775 91.86)
		(width 0.15)
		(layer "In7.Cu")
		(net 1270)
	)
	(segment
		(start 110.4025 92.9975)
		(end 110.4025 92.2375)
		(width 0.15)
		(layer "In7.Cu")
		(net 1270)
	)
	(segment
		(start 106.84 102.8225)
		(end 106.865391 102.8225)
		(width 0.15)
		(layer "In7.Cu")
		(net 1270)
	)
	(segment
		(start 106.337081 99.2225)
		(end 106.4625 99.2225)
		(width 0.15)
		(layer "In7.Cu")
		(net 1270)
	)
	(segment
		(start 110.4025 91.9625)
		(end 110.4025 91.5025)
		(width 0.15)
		(layer "In7.Cu")
		(net 1270)
	)
	(segment
		(start 106.4625 94.8)
		(end 106.4625 94.343044)
		(width 0.15)
		(layer "In7.Cu")
		(net 1270)
	)
	(segment
		(start 90.312548 96.081912)
		(end 90.227693 96.166764)
		(width 0.15)
		(layer "In7.Cu")
		(net 1270)
	)
	(segment
		(start 106.4625 100.4225)
		(end 106.7375 100.4225)
		(width 0.15)
		(layer "In7.Cu")
		(net 1270)
	)
	(segment
		(start 106.84 105.2225)
		(end 106.865391 105.2225)
		(width 0.15)
		(layer "In7.Cu")
		(net 1270)
	)
	(segment
		(start 106.4625 97.6975)
		(end 106.337081 97.6975)
		(width 0.15)
		(layer "In7.Cu")
		(net 1270)
	)
	(segment
		(start 106.4625 98.0225)
		(end 106.7375 98.0225)
		(width 0.15)
		(layer "In7.Cu")
		(net 1270)
	)
	(segment
		(start 106.7375 96.4975)
		(end 106.4625 96.4975)
		(width 0.15)
		(layer "In7.Cu")
		(net 1270)
	)
	(segment
		(start 107.965437 95.52)
		(end 107.965437 95.4)
		(width 0.15)
		(layer "In7.Cu")
		(net 1270)
	)
	(segment
		(start 106.4625 94.343044)
		(end 106.802772 94.002772)
		(width 0.15)
		(layer "In7.Cu")
		(net 1270)
	)
	(segment
		(start 93.156956 103.3625)
		(end 99.456956 109.6625)
		(width 0.15)
		(layer "In7.Cu")
		(net 1270)
	)
	(segment
		(start 106.337081 96.8225)
		(end 106.4625 96.8225)
		(width 0.15)
		(layer "In7.Cu")
		(net 1270)
	)
	(segment
		(start 106.4625 102.12)
		(end 106.4625 102)
		(width 0.15)
		(layer "In7.Cu")
		(net 1270)
	)
	(segment
		(start 106.7375 99.2225)
		(end 106.862919 99.2225)
		(width 0.15)
		(layer "In7.Cu")
		(net 1270)
	)
	(segment
		(start 106.7375 100.4225)
		(end 106.862919 100.4225)
		(width 0.15)
		(layer "In7.Cu")
		(net 1270)
	)
	(segment
		(start 114.0025 91.86)
		(end 114.0025 91.7025)
		(width 0.15)
		(layer "In7.Cu")
		(net 1270)
	)
	(segment
		(start 111.6025 92.2375)
		(end 111.6025 91.9625)
		(width 0.15)
		(layer "In7.Cu")
		(net 1270)
	)
	(segment
		(start 117.4625 90.243044)
		(end 117.4625 88.3625)
		(width 0.15)
		(layer "In7.Cu")
		(net 1270)
	)
	(segment
		(start 106.965419 99.12)
		(end 106.965419 99)
		(width 0.15)
		(layer "In7.Cu")
		(net 1270)
	)
	(segment
		(start 106.7375 97.6975)
		(end 106.4625 97.6975)
		(width 0.15)
		(layer "In7.Cu")
		(net 1270)
	)
	(segment
		(start 106.4625 108.143044)
		(end 106.4625 105.6)
		(width 0.15)
		(layer "In7.Cu")
		(net 1270)
	)
	(segment
		(start 105.959581 97.32)
		(end 105.959581 97.2)
		(width 0.15)
		(layer "In7.Cu")
		(net 1270)
	)
	(segment
		(start 111.6025 91.9625)
		(end 111.6025 91.7525)
		(width 0.15)
		(layer "In7.Cu")
		(net 1270)
	)
	(segment
		(start 107.862937 95.2975)
		(end 106.84 95.2975)
		(width 0.15)
		(layer "In7.Cu")
		(net 1270)
	)
	(segment
		(start 106.84 101.2975)
		(end 106.4625 101.2975)
		(width 0.15)
		(layer "In7.Cu")
		(net 1270)
	)
	(segment
		(start 112.58 92.8)
		(end 112.7 92.8)
		(width 0.15)
		(layer "In7.Cu")
		(net 1270)
	)
	(segment
		(start 111.2775 92.2375)
		(end 111.2775 92.6975)
		(width 0.15)
		(layer "In7.Cu")
		(net 1270)
	)
	(segment
		(start 112.8025 91.9625)
		(end 112.8025 91.6525)
		(width 0.15)
		(layer "In7.Cu")
		(net 1270)
	)
	(segment
		(start 105.959581 98.52)
		(end 105.959581 98.4)
		(width 0.15)
		(layer "In7.Cu")
		(net 1270)
	)
	(segment
		(start 117.4625 88.3625)
		(end 117.3 88.2)
		(width 0.15)
		(layer "In7.Cu")
		(net 1270)
	)
	(segment
		(start 99.456956 109.6625)
		(end 104.943044 109.6625)
		(width 0.15)
		(layer "In7.Cu")
		(net 1270)
	)
	(segment
		(start 106.862919 97.6975)
		(end 106.7375 97.6975)
		(width 0.15)
		(layer "In7.Cu")
		(net 1270)
	)
	(segment
		(start 106.337081 98.0225)
		(end 106.4625 98.0225)
		(width 0.15)
		(layer "In7.Cu")
		(net 1270)
	)
	(segment
		(start 106.4625 94.92)
		(end 106.4625 94.8)
		(width 0.15)
		(layer "In7.Cu")
		(net 1270)
	)
	(segment
		(start 106.862919 100.0975)
		(end 106.7375 100.0975)
		(width 0.15)
		(layer "In7.Cu")
		(net 1270)
	)
	(segment
		(start 106.4625 103.32)
		(end 106.4625 103.2)
		(width 0.15)
		(layer "In7.Cu")
		(net 1270)
	)
	(segment
		(start 105.959581 96.12)
		(end 105.959581 96)
		(width 0.15)
		(layer "In7.Cu")
		(net 1270)
	)
	(segment
		(start 109.2025 91.86)
		(end 109.2025 91.8025)
		(width 0.15)
		(layer "In7.Cu")
		(net 1270)
	)
	(segment
		(start 113.18 91.275)
		(end 113.3 91.275)
		(width 0.15)
		(layer "In7.Cu")
		(net 1270)
	)
	(segment
		(start 90.1375 102.443044)
		(end 91.056956 103.3625)
		(width 0.15)
		(layer "In7.Cu")
		(net 1270)
	)
	(segment
		(start 113.6775 91.6525)
		(end 113.6775 91.9625)
		(width 0.15)
		(layer "In7.Cu")
		(net 1270)
	)
	(segment
		(start 111.98 91.375)
		(end 112.1 91.375)
		(width 0.15)
		(layer "In7.Cu")
		(net 1270)
	)
	(segment
		(start 106.7375 98.8975)
		(end 106.4625 98.8975)
		(width 0.15)
		(layer "In7.Cu")
		(net 1270)
	)
	(segment
		(start 110.78 91.125)
		(end 110.9 91.125)
		(width 0.15)
		(layer "In7.Cu")
		(net 1270)
	)
	(segment
		(start 90.935555 96.36551)
		(end 90.651958 96.081913)
		(width 0.15)
		(layer "In7.Cu")
		(net 1270)
	)
	(segment
		(start 106.7375 100.0975)
		(end 106.4625 100.0975)
		(width 0.15)
		(layer "In7.Cu")
		(net 1270)
	)
	(segment
		(start 114.98 91.9625)
		(end 115.1 91.9625)
		(width 0.15)
		(layer "In7.Cu")
		(net 1270)
	)
	(segment
		(start 110.4025 92.2375)
		(end 110.4025 91.9625)
		(width 0.15)
		(layer "In7.Cu")
		(net 1270)
	)
	(segment
		(start 114.8775 91.7025)
		(end 114.8775 91.86)
		(width 0.15)
		(layer "In7.Cu")
		(net 1270)
	)
	(segment
		(start 106.4625 100.0975)
		(end 106.337081 100.0975)
		(width 0.15)
		(layer "In7.Cu")
		(net 1270)
	)
	(segment
		(start 110.18 93.1)
		(end 110.3 93.1)
		(width 0.15)
		(layer "In7.Cu")
		(net 1270)
	)
	(segment
		(start 112.4775 91.9625)
		(end 112.4775 92.2375)
		(width 0.15)
		(layer "In7.Cu")
		(net 1270)
	)
	(segment
		(start 116.452772 91.252772)
		(end 117.4625 90.243044)
		(width 0.15)
		(layer "In7.Cu")
		(net 1270)
	)
	(segment
		(start 106.965419 100.32)
		(end 106.965419 100.2)
		(width 0.15)
		(layer "In7.Cu")
		(net 1270)
	)
	(segment
		(start 108.843044 91.9625)
		(end 109.1 91.9625)
		(width 0.15)
		(layer "In7.Cu")
		(net 1270)
	)
	(segment
		(start 91.256956 95.1375)
		(end 91.076222 95.318234)
		(width 0.15)
		(layer "In7.Cu")
		(net 1270)
	)
	(segment
		(start 106.4625 95.6225)
		(end 106.84 95.6225)
		(width 0.15)
		(layer "In7.Cu")
		(net 1270)
	)
	(segment
		(start 106.967891 102.72)
		(end 106.967891 102.6)
		(width 0.15)
		(layer "In7.Cu")
		(net 1270)
	)
	(segment
		(start 113.6775 92.2375)
		(end 113.6775 92.6975)
		(width 0.15)
		(layer "In7.Cu")
		(net 1270)
	)
	(segment
		(start 115.1 91.9625)
		(end 115.743044 91.9625)
		(width 0.15)
		(layer "In7.Cu")
		(net 1270)
	)
	(segment
		(start 106.0375 100.9475)
		(end 106.0375 100.7725)
		(width 0.15)
		(layer "In7.Cu")
		(net 1270)
	)
	(segment
		(start 106.4625 99.2225)
		(end 106.7375 99.2225)
		(width 0.15)
		(layer "In7.Cu")
		(net 1270)
	)
	(segment
		(start 115.743044 91.9625)
		(end 116.452772 91.252772)
		(width 0.15)
		(layer "In7.Cu")
		(net 1270)
	)
	(segment
		(start 106.7375 96.8225)
		(end 106.862919 96.8225)
		(width 0.15)
		(layer "In7.Cu")
		(net 1270)
	)
	(segment
		(start 106.862919 96.4975)
		(end 106.7375 96.4975)
		(width 0.15)
		(layer "In7.Cu")
		(net 1270)
	)
	(segment
		(start 106.865391 101.2975)
		(end 106.84 101.2975)
		(width 0.15)
		(layer "In7.Cu")
		(net 1270)
	)
	(segment
		(start 106.4625 96.8225)
		(end 106.7375 96.8225)
		(width 0.15)
		(layer "In7.Cu")
		(net 1270)
	)
	(segment
		(start 110.0775 92.2375)
		(end 110.0775 92.9975)
		(width 0.15)
		(layer "In7.Cu")
		(net 1270)
	)
	(segment
		(start 106.865391 103.6975)
		(end 106.84 103.6975)
		(width 0.15)
		(layer "In7.Cu")
		(net 1270)
	)
	(segment
		(start 112.8025 92.2375)
		(end 112.8025 91.9625)
		(width 0.15)
		(layer "In7.Cu")
		(net 1270)
	)
	(segment
		(start 91.076222 95.657646)
		(end 91.35982 95.941244)
		(width 0.15)
		(layer "In7.Cu")
		(net 1270)
	)
	(segment
		(start 106.84 104.0225)
		(end 106.865391 104.0225)
		(width 0.15)
		(layer "In7.Cu")
		(net 1270)
	)
	(segment
		(start 106.4625 98.8975)
		(end 106.337081 98.8975)
		(width 0.15)
		(layer "In7.Cu")
		(net 1270)
	)
	(segment
		(start 91.056956 103.3625)
		(end 93.156956 103.3625)
		(width 0.15)
		(layer "In7.Cu")
		(net 1270)
	)
	(segment
		(start 111.38 92.8)
		(end 111.5 92.8)
		(width 0.15)
		(layer "In7.Cu")
		(net 1270)
	)
	(segment
		(start 91.359819 96.280656)
		(end 91.274967 96.365509)
		(width 0.15)
		(layer "In7.Cu")
		(net 1270)
	)
	(segment
		(start 90.227693 96.166764)
		(end 90.1375 96.256956)
		(width 0.15)
		(layer "In7.Cu")
		(net 1270)
	)
	(segment
		(start 110.0775 91.86)
		(end 110.0775 92.2375)
		(width 0.15)
		(layer "In7.Cu")
		(net 1270)
	)
	(segment
		(start 106.965419 97.92)
		(end 106.965419 97.8)
		(width 0.15)
		(layer "In7.Cu")
		(net 1270)
	)
	(segment
		(start 106.967891 101.52)
		(end 106.967891 101.4)
		(width 0.15)
		(layer "In7.Cu")
		(net 1270)
	)
	(segment
		(start 104.943044 109.6625)
		(end 106.4625 108.143044)
		(width 0.15)
		(layer "In7.Cu")
		(net 1270)
	)
	(segment
		(start 92.4 95.3)
		(end 92.2375 95.1375)
		(width 0.15)
		(layer "In7.Cu")
		(net 1270)
	)
	(segment
		(start 112.4775 91.7525)
		(end 112.4775 91.9625)
		(width 0.15)
		(layer "In7.Cu")
		(net 1270)
	)
	(segment
		(start 106.337081 95.6225)
		(end 106.4625 95.6225)
		(width 0.15)
		(layer "In7.Cu")
		(net 1270)
	)
	(segment
		(start 109.58 91.425)
		(end 109.7 91.425)
		(width 0.15)
		(layer "In7.Cu")
		(net 1270)
	)
	(segment
		(start 106.84 101.6225)
		(end 106.865391 101.6225)
		(width 0.15)
		(layer "In7.Cu")
		(net 1270)
	)
	(segment
		(start 106.802772 94.002772)
		(end 108.843044 91.9625)
		(width 0.15)
		(layer "In7.Cu")
		(net 1270)
	)
	(segment
		(start 106.865391 102.4975)
		(end 106.84 102.4975)
		(width 0.15)
		(layer "In7.Cu")
		(net 1270)
	)
	(segment
		(start 106.4625 96.4975)
		(end 106.337081 96.4975)
		(width 0.15)
		(layer "In7.Cu")
		(net 1270)
	)
	(segment
		(start 106.4625 104.52)
		(end 106.4625 104.4)
		(width 0.15)
		(layer "In7.Cu")
		(net 1270)
	)
	(arc
		(start 106.865391 104.0225)
		(mid 106.937869 103.992478)
		(end 106.967891 103.92)
		(width 0.15)
		(layer "In7.Cu")
		(net 1270)
	)
	(arc
		(start 114.5 91.325)
		(mid 114.766933 91.435567)
		(end 114.8775 91.7025)
		(width 0.15)
		(layer "In7.Cu")
		(net 1270)
	)
	(arc
		(start 106.337081 100.0975)
		(mid 106.070148 99.986933)
		(end 105.959581 99.72)
		(width 0.15)
		(layer "In7.Cu")
		(net 1270)
	)
	(arc
		(start 110.9 91.125)
		(mid 111.166933 91.235567)
		(end 111.2775 91.5025)
		(width 0.15)
		(layer "In7.Cu")
		(net 1270)
	)
	(arc
		(start 114.0025 91.7025)
		(mid 114.113067 91.435567)
		(end 114.38 91.325)
		(width 0.15)
		(layer "In7.Cu")
		(net 1270)
	)
	(arc
		(start 106.84 95.2975)
		(mid 106.573067 95.186933)
		(end 106.4625 94.92)
		(width 0.15)
		(layer "In7.Cu")
		(net 1270)
	)
	(arc
		(start 109.7 91.425)
		(mid 109.966933 91.535567)
		(end 110.0775 91.8025)
		(width 0.15)
		(layer "In7.Cu")
		(net 1270)
	)
	(arc
		(start 106.4625 105.6)
		(mid 106.573067 105.333067)
		(end 106.84 105.2225)
		(width 0.15)
		(layer "In7.Cu")
		(net 1270)
	)
	(arc
		(start 106.4625 102)
		(mid 106.573067 101.733067)
		(end 106.84 101.6225)
		(width 0.15)
		(layer "In7.Cu")
		(net 1270)
	)
	(arc
		(start 106.4625 103.2)
		(mid 106.573067 102.933067)
		(end 106.84 102.8225)
		(width 0.15)
		(layer "In7.Cu")
		(net 1270)
	)
	(arc
		(start 106.862919 98.0225)
		(mid 106.935397 97.992478)
		(end 106.965419 97.92)
		(width 0.15)
		(layer "In7.Cu")
		(net 1270)
	)
	(arc
		(start 106.84 104.8975)
		(mid 106.573067 104.786933)
		(end 106.4625 104.52)
		(width 0.15)
		(layer "In7.Cu")
		(net 1270)
	)
	(arc
		(start 106.965419 100.2)
		(mid 106.935397 100.127522)
		(end 106.862919 100.0975)
		(width 0.15)
		(layer "In7.Cu")
		(net 1270)
	)
	(arc
		(start 107.965437 95.4)
		(mid 107.935415 95.327522)
		(end 107.862937 95.2975)
		(width 0.15)
		(layer "In7.Cu")
		(net 1270)
	)
	(arc
		(start 113.3 91.275)
		(mid 113.566933 91.385567)
		(end 113.6775 91.6525)
		(width 0.15)
		(layer "In7.Cu")
		(net 1270)
	)
	(arc
		(start 106.4625 104.4)
		(mid 106.573067 104.133067)
		(end 106.84 104.0225)
		(width 0.15)
		(layer "In7.Cu")
		(net 1270)
	)
	(arc
		(start 106.337081 96.4975)
		(mid 106.070148 96.386933)
		(end 105.959581 96.12)
		(width 0.15)
		(layer "In7.Cu")
		(net 1270)
	)
	(arc
		(start 106.865391 101.6225)
		(mid 106.937869 101.592478)
		(end 106.967891 101.52)
		(width 0.15)
		(layer "In7.Cu")
		(net 1270)
	)
	(arc
		(start 91.35982 95.941244)
		(mid 91.430115 96.110949)
		(end 91.359819 96.280656)
		(width 0.15)
		(layer "In7.Cu")
		(net 1270)
	)
	(arc
		(start 91.076222 95.318234)
		(mid 91.005926 95.487941)
		(end 91.076222 95.657646)
		(width 0.15)
		(layer "In7.Cu")
		(net 1270)
	)
	(arc
		(start 114.8775 91.86)
		(mid 114.907522 91.932478)
		(end 114.98 91.9625)
		(width 0.15)
		(layer "In7.Cu")
		(net 1270)
	)
	(arc
		(start 106.965419 96.6)
		(mid 106.935397 96.527522)
		(end 106.862919 96.4975)
		(width 0.15)
		(layer "In7.Cu")
		(net 1270)
	)
	(arc
		(start 112.7 92.8)
		(mid 112.772478 92.769978)
		(end 112.8025 92.6975)
		(width 0.15)
		(layer "In7.Cu")
		(net 1270)
	)
	(arc
		(start 91.274967 96.365509)
		(mid 91.105261 96.435804)
		(end 90.935555 96.36551)
		(width 0.15)
		(layer "In7.Cu")
		(net 1270)
	)
	(arc
		(start 110.0775 92.9975)
		(mid 110.107522 93.069978)
		(end 110.18 93.1)
		(width 0.15)
		(layer "In7.Cu")
		(net 1270)
	)
	(arc
		(start 109.2025 91.8025)
		(mid 109.313067 91.535567)
		(end 109.58 91.425)
		(width 0.15)
		(layer "In7.Cu")
		(net 1270)
	)
	(arc
		(start 111.2775 92.6975)
		(mid 111.307522 92.769978)
		(end 111.38 92.8)
		(width 0.15)
		(layer "In7.Cu")
		(net 1270)
	)
	(arc
		(start 105.959581 98.4)
		(mid 106.070148 98.133067)
		(end 106.337081 98.0225)
		(width 0.15)
		(layer "In7.Cu")
		(net 1270)
	)
	(arc
		(start 109.1 91.9625)
		(mid 109.172478 91.932478)
		(end 109.2025 91.86)
		(width 0.15)
		(layer "In7.Cu")
		(net 1270)
	)
	(arc
		(start 113.9 92.8)
		(mid 113.972478 92.769978)
		(end 114.0025 92.6975)
		(width 0.15)
		(layer "In7.Cu")
		(net 1270)
	)
	(arc
		(start 110.3 93.1)
		(mid 110.372478 93.069978)
		(end 110.4025 92.9975)
		(width 0.15)
		(layer "In7.Cu")
		(net 1270)
	)
	(arc
		(start 106.3875 101.2975)
		(mid 106.140013 101.194987)
		(end 106.0375 100.9475)
		(width 0.15)
		(layer "In7.Cu")
		(net 1270)
	)
	(arc
		(start 105.959581 96)
		(mid 106.070148 95.733067)
		(end 106.337081 95.6225)
		(width 0.15)
		(layer "In7.Cu")
		(net 1270)
	)
	(arc
		(start 106.967891 103.8)
		(mid 106.937869 103.727522)
		(end 106.865391 103.6975)
		(width 0.15)
		(layer "In7.Cu")
		(net 1270)
	)
	(arc
		(start 106.862919 100.4225)
		(mid 106.935397 100.392478)
		(end 106.965419 100.32)
		(width 0.15)
		(layer "In7.Cu")
		(net 1270)
	)
	(arc
		(start 111.6025 91.7525)
		(mid 111.713067 91.485567)
		(end 111.98 91.375)
		(width 0.15)
		(layer "In7.Cu")
		(net 1270)
	)
	(arc
		(start 106.862919 99.2225)
		(mid 106.935397 99.192478)
		(end 106.965419 99.12)
		(width 0.15)
		(layer "In7.Cu")
		(net 1270)
	)
	(arc
		(start 106.84 102.4975)
		(mid 106.573067 102.386933)
		(end 106.4625 102.12)
		(width 0.15)
		(layer "In7.Cu")
		(net 1270)
	)
	(arc
		(start 106.0375 100.7725)
		(mid 106.140013 100.525013)
		(end 106.3875 100.4225)
		(width 0.15)
		(layer "In7.Cu")
		(net 1270)
	)
	(arc
		(start 106.965419 97.8)
		(mid 106.935397 97.727522)
		(end 106.862919 97.6975)
		(width 0.15)
		(layer "In7.Cu")
		(net 1270)
	)
	(arc
		(start 105.959581 99.6)
		(mid 106.070148 99.333067)
		(end 106.337081 99.2225)
		(width 0.15)
		(layer "In7.Cu")
		(net 1270)
	)
	(arc
		(start 106.865391 105.2225)
		(mid 106.937869 105.192478)
		(end 106.967891 105.12)
		(width 0.15)
		(layer "In7.Cu")
		(net 1270)
	)
	(arc
		(start 106.967891 101.4)
		(mid 106.937869 101.327522)
		(end 106.865391 101.2975)
		(width 0.15)
		(layer "In7.Cu")
		(net 1270)
	)
	(arc
		(start 107.862937 95.6225)
		(mid 107.935415 95.592478)
		(end 107.965437 95.52)
		(width 0.15)
		(layer "In7.Cu")
		(net 1270)
	)
	(arc
		(start 113.6775 92.6975)
		(mid 113.707522 92.769978)
		(end 113.78 92.8)
		(width 0.15)
		(layer "In7.Cu")
		(net 1270)
	)
	(arc
		(start 106.84 103.6975)
		(mid 106.573067 103.586933)
		(end 106.4625 103.32)
		(width 0.15)
		(layer "In7.Cu")
		(net 1270)
	)
	(arc
		(start 110.4025 91.5025)
		(mid 110.513067 91.235567)
		(end 110.78 91.125)
		(width 0.15)
		(layer "In7.Cu")
		(net 1270)
	)
	(arc
		(start 106.865391 102.8225)
		(mid 106.937869 102.792478)
		(end 106.967891 102.72)
		(width 0.15)
		(layer "In7.Cu")
		(net 1270)
	)
	(arc
		(start 112.1 91.375)
		(mid 112.366933 91.485567)
		(end 112.4775 91.7525)
		(width 0.15)
		(layer "In7.Cu")
		(net 1270)
	)
	(arc
		(start 106.967891 102.6)
		(mid 106.937869 102.527522)
		(end 106.865391 102.4975)
		(width 0.15)
		(layer "In7.Cu")
		(net 1270)
	)
	(arc
		(start 112.4775 92.6975)
		(mid 112.507522 92.769978)
		(end 112.58 92.8)
		(width 0.15)
		(layer "In7.Cu")
		(net 1270)
	)
	(arc
		(start 106.337081 97.6975)
		(mid 106.070148 97.586933)
		(end 105.959581 97.32)
		(width 0.15)
		(layer "In7.Cu")
		(net 1270)
	)
	(arc
		(start 106.337081 98.8975)
		(mid 106.070148 98.786933)
		(end 105.959581 98.52)
		(width 0.15)
		(layer "In7.Cu")
		(net 1270)
	)
	(arc
		(start 105.959581 97.2)
		(mid 106.070148 96.933067)
		(end 106.337081 96.8225)
		(width 0.15)
		(layer "In7.Cu")
		(net 1270)
	)
	(arc
		(start 106.862919 96.8225)
		(mid 106.935397 96.792478)
		(end 106.965419 96.72)
		(width 0.15)
		(layer "In7.Cu")
		(net 1270)
	)
	(arc
		(start 90.651958 96.081913)
		(mid 90.482252 96.011619)
		(end 90.312548 96.081912)
		(width 0.15)
		(layer "In7.Cu")
		(net 1270)
	)
	(arc
		(start 106.965419 99)
		(mid 106.935397 98.927522)
		(end 106.862919 98.8975)
		(width 0.15)
		(layer "In7.Cu")
		(net 1270)
	)
	(arc
		(start 112.8025 91.6525)
		(mid 112.913067 91.385567)
		(end 113.18 91.275)
		(width 0.15)
		(layer "In7.Cu")
		(net 1270)
	)
	(arc
		(start 111.5 92.8)
		(mid 111.572478 92.769978)
		(end 111.6025 92.6975)
		(width 0.15)
		(layer "In7.Cu")
		(net 1270)
	)
	(arc
		(start 106.967891 105)
		(mid 106.937869 104.927522)
		(end 106.865391 104.8975)
		(width 0.15)
		(layer "In7.Cu")
		(net 1270)
	)
	(segment
		(start 91.92 92.385)
		(end 92.085 92.385)
		(width 0.19)
		(layer "F.Cu")
		(net 1271)
	)
	(segment
		(start 91.605 92.7)
		(end 91.92 92.385)
		(width 0.19)
		(layer "F.Cu")
		(net 1271)
	)
	(segment
		(start 117.065532 74.715)
		(end 117.180532 74.6)
		(width 0.19)
		(layer "F.Cu")
		(net 1271)
	)
	(segment
		(start 92.085 92.385)
		(end 92.2 92.5)
		(width 0.19)
		(layer "F.Cu")
		(net 1271)
	)
	(segment
		(start 91.58 92.7)
		(end 91.605 92.7)
		(width 0.19)
		(layer "F.Cu")
		(net 1271)
	)
	(segment
		(start 117.330532 75.15)
		(end 117.065532 74.885)
		(width 0.19)
		(layer "F.Cu")
		(net 1271)
	)
	(segment
		(start 117.065532 74.885)
		(end 117.065532 74.715)
		(width 0.19)
		(layer "F.Cu")
		(net 1271)
	)
	(via
		(at 92.2 92.5)
		(size 0.45)
		(drill 0.1)
		(layers "F.Cu" "B.Cu")
		(net 1271)
	)
	(via
		(at 117.180532 74.6)
		(size 0.45)
		(drill 0.1)
		(layers "F.Cu" "B.Cu")
		(net 1271)
	)
	(segment
		(start 90.410107 94.284352)
		(end 90.36061 94.333847)
		(width 0.15)
		(layer "In7.Cu")
		(net 1271)
	)
	(segment
		(start 117.979579 73.2975)
		(end 117.979579 73.7775)
		(width 0.15)
		(layer "In7.Cu")
		(net 1271)
	)
	(segment
		(start 121.3625 75.506956)
		(end 121.3625 74.506956)
		(width 0.15)
		(layer "In7.Cu")
		(net 1271)
	)
	(segment
		(start 121.5625 77.593044)
		(end 121.9625 77.193044)
		(width 0.15)
		(layer "In7.Cu")
		(net 1271)
	)
	(segment
		(start 107.5625 96.743044)
		(end 110.943044 93.3625)
		(width 0.15)
		(layer "In7.Cu")
		(net 1271)
	)
	(segment
		(start 117.018032 73.476424)
		(end 117.356956 73.1375)
		(width 0.15)
		(layer "In7.Cu")
		(net 1271)
	)
	(segment
		(start 90.36061 94.333847)
		(end 89.2375 95.456956)
		(width 0.15)
		(layer "In7.Cu")
		(net 1271)
	)
	(segment
		(start 122.0125 87.293044)
		(end 122.0125 85.156956)
		(width 0.15)
		(layer "In7.Cu")
		(net 1271)
	)
	(segment
		(start 118.379579 73.7775)
		(end 118.379579 73.2975)
		(width 0.15)
		(layer "In7.Cu")
		(net 1271)
	)
	(segment
		(start 90.855585 94.036861)
		(end 91.079478 94.260754)
		(width 0.15)
		(layer "In7.Cu")
		(net 1271)
	)
	(segment
		(start 92.856956 104.4625)
		(end 98.856956 110.4625)
		(width 0.15)
		(layer "In7.Cu")
		(net 1271)
	)
	(segment
		(start 118.539579 73.1375)
		(end 120.343044 73.1375)
		(width 0.15)
		(layer "In7.Cu")
		(net 1271)
	)
	(segment
		(start 115.943044 93.3625)
		(end 122.0125 87.293044)
		(width 0.15)
		(layer "In7.Cu")
		(net 1271)
	)
	(segment
		(start 91.079478 94.458744)
		(end 91.029979 94.508244)
		(width 0.15)
		(layer "In7.Cu")
		(net 1271)
	)
	(segment
		(start 121.4625 84.606956)
		(end 121.4625 83.743044)
		(width 0.15)
		(layer "In7.Cu")
		(net 1271)
	)
	(segment
		(start 110.943044 93.3625)
		(end 115.943044 93.3625)
		(width 0.15)
		(layer "In7.Cu")
		(net 1271)
	)
	(segment
		(start 121.5625 78.606956)
		(end 121.5625 77.593044)
		(width 0.15)
		(layer "In7.Cu")
		(net 1271)
	)
	(segment
		(start 121.4125 81.406956)
		(end 121.4125 80.493044)
		(width 0.15)
		(layer "In7.Cu")
		(net 1271)
	)
	(segment
		(start 92.0375 92.3375)
		(end 91.556956 92.3375)
		(width 0.15)
		(layer "In7.Cu")
		(net 1271)
	)
	(segment
		(start 117.180532 74.6)
		(end 117.018032 74.4375)
		(width 0.15)
		(layer "In7.Cu")
		(net 1271)
	)
	(segment
		(start 122.0125 85.156956)
		(end 121.4625 84.606956)
		(width 0.15)
		(layer "In7.Cu")
		(net 1271)
	)
	(segment
		(start 98.856956 110.4625)
		(end 105.343044 110.4625)
		(width 0.15)
		(layer "In7.Cu")
		(net 1271)
	)
	(segment
		(start 121.4625 83.743044)
		(end 122.0625 83.143044)
		(width 0.15)
		(layer "In7.Cu")
		(net 1271)
	)
	(segment
		(start 121.4125 80.493044)
		(end 121.9625 79.943044)
		(width 0.15)
		(layer "In7.Cu")
		(net 1271)
	)
	(segment
		(start 105.343044 110.4625)
		(end 107.5625 108.243044)
		(width 0.15)
		(layer "In7.Cu")
		(net 1271)
	)
	(segment
		(start 107.5625 108.243044)
		(end 107.5625 96.743044)
		(width 0.15)
		(layer "In7.Cu")
		(net 1271)
	)
	(segment
		(start 90.956956 104.4625)
		(end 92.856956 104.4625)
		(width 0.15)
		(layer "In7.Cu")
		(net 1271)
	)
	(segment
		(start 89.2375 95.456956)
		(end 89.2375 102.743044)
		(width 0.15)
		(layer "In7.Cu")
		(net 1271)
	)
	(segment
		(start 121.9625 79.006956)
		(end 121.5625 78.606956)
		(width 0.15)
		(layer "In7.Cu")
		(net 1271)
	)
	(segment
		(start 121.3625 74.506956)
		(end 120.6625 73.806956)
		(width 0.15)
		(layer "In7.Cu")
		(net 1271)
	)
	(segment
		(start 117.356956 73.1375)
		(end 117.819579 73.1375)
		(width 0.15)
		(layer "In7.Cu")
		(net 1271)
	)
	(segment
		(start 91.556956 92.3375)
		(end 91.1375 92.756956)
		(width 0.15)
		(layer "In7.Cu")
		(net 1271)
	)
	(segment
		(start 120.6625 73.456956)
		(end 120.343044 73.1375)
		(width 0.15)
		(layer "In7.Cu")
		(net 1271)
	)
	(segment
		(start 90.831989 94.508244)
		(end 90.608097 94.284352)
		(width 0.15)
		(layer "In7.Cu")
		(net 1271)
	)
	(segment
		(start 91.1375 93.556956)
		(end 90.855585 93.838871)
		(width 0.15)
		(layer "In7.Cu")
		(net 1271)
	)
	(segment
		(start 122.0625 82.056956)
		(end 121.4125 81.406956)
		(width 0.15)
		(layer "In7.Cu")
		(net 1271)
	)
	(segment
		(start 121.9625 76.106956)
		(end 121.3625 75.506956)
		(width 0.15)
		(layer "In7.Cu")
		(net 1271)
	)
	(segment
		(start 91.1375 92.756956)
		(end 91.1375 93.556956)
		(width 0.15)
		(layer "In7.Cu")
		(net 1271)
	)
	(segment
		(start 117.018032 74.4375)
		(end 117.018032 73.476424)
		(width 0.15)
		(layer "In7.Cu")
		(net 1271)
	)
	(segment
		(start 118.139579 73.9375)
		(end 118.219579 73.9375)
		(width 0.15)
		(layer "In7.Cu")
		(net 1271)
	)
	(segment
		(start 121.9625 77.193044)
		(end 121.9625 76.106956)
		(width 0.15)
		(layer "In7.Cu")
		(net 1271)
	)
	(segment
		(start 122.0625 83.143044)
		(end 122.0625 82.056956)
		(width 0.15)
		(layer "In7.Cu")
		(net 1271)
	)
	(segment
		(start 89.2375 102.743044)
		(end 90.956956 104.4625)
		(width 0.15)
		(layer "In7.Cu")
		(net 1271)
	)
	(segment
		(start 120.6625 73.806956)
		(end 120.6625 73.456956)
		(width 0.15)
		(layer "In7.Cu")
		(net 1271)
	)
	(segment
		(start 92.2 92.5)
		(end 92.0375 92.3375)
		(width 0.15)
		(layer "In7.Cu")
		(net 1271)
	)
	(segment
		(start 121.9625 79.943044)
		(end 121.9625 79.006956)
		(width 0.15)
		(layer "In7.Cu")
		(net 1271)
	)
	(arc
		(start 90.608097 94.284352)
		(mid 90.509102 94.243347)
		(end 90.410107 94.284352)
		(width 0.15)
		(layer "In7.Cu")
		(net 1271)
	)
	(arc
		(start 117.819579 73.1375)
		(mid 117.932716 73.184363)
		(end 117.979579 73.2975)
		(width 0.15)
		(layer "In7.Cu")
		(net 1271)
	)
	(arc
		(start 118.379579 73.2975)
		(mid 118.426442 73.184363)
		(end 118.539579 73.1375)
		(width 0.15)
		(layer "In7.Cu")
		(net 1271)
	)
	(arc
		(start 91.079478 94.260754)
		(mid 91.120483 94.359749)
		(end 91.079478 94.458744)
		(width 0.15)
		(layer "In7.Cu")
		(net 1271)
	)
	(arc
		(start 91.029979 94.508244)
		(mid 90.930984 94.549249)
		(end 90.831989 94.508244)
		(width 0.15)
		(layer "In7.Cu")
		(net 1271)
	)
	(arc
		(start 117.979579 73.7775)
		(mid 118.026442 73.890637)
		(end 118.139579 73.9375)
		(width 0.15)
		(layer "In7.Cu")
		(net 1271)
	)
	(arc
		(start 90.855585 93.838871)
		(mid 90.81458 93.937866)
		(end 90.855585 94.036861)
		(width 0.15)
		(layer "In7.Cu")
		(net 1271)
	)
	(arc
		(start 118.219579 73.9375)
		(mid 118.332716 73.890637)
		(end 118.379579 73.7775)
		(width 0.15)
		(layer "In7.Cu")
		(net 1271)
	)
	(segment
		(start 96.72337 101.915)
		(end 97.215 101.42337)
		(width 0.19)
		(layer "F.Cu")
		(net 1272)
	)
	(segment
		(start 104.695532 77.885)
		(end 104.695532 77.315)
		(width 0.19)
		(layer "F.Cu")
		(net 1272)
	)
	(segment
		(start 104.695532 77.315)
		(end 104.580532 77.2)
		(width 0.19)
		(layer "F.Cu")
		(net 1272)
	)
	(segment
		(start 89.58 101.6)
		(end 89.605 101.6)
		(width 0.19)
		(layer "F.Cu")
		(net 1272)
	)
	(segment
		(start 89.605 101.6)
		(end 89.92 101.915)
		(width 0.19)
		(layer "F.Cu")
		(net 1272)
	)
	(segment
		(start 97.215 101.42337)
		(end 97.215 100.77663)
		(width 0.19)
		(layer "F.Cu")
		(net 1272)
	)
	(segment
		(start 104.430532 78.15)
		(end 104.695532 77.885)
		(width 0.19)
		(layer "F.Cu")
		(net 1272)
	)
	(segment
		(start 89.92 101.915)
		(end 96.72337 101.915)
		(width 0.19)
		(layer "F.Cu")
		(net 1272)
	)
	(segment
		(start 96.941664 100.503294)
		(end 96.796706 100.503294)
		(width 0.19)
		(layer "F.Cu")
		(net 1272)
	)
	(segment
		(start 97.215 100.77663)
		(end 96.941664 100.503294)
		(width 0.19)
		(layer "F.Cu")
		(net 1272)
	)
	(via
		(at 96.796706 100.503294)
		(size 0.45)
		(drill 0.1)
		(layers "F.Cu" "B.Cu")
		(net 1272)
	)
	(via
		(at 104.580532 77.2)
		(size 0.45)
		(drill 0.1)
		(layers "F.Cu" "B.Cu")
		(net 1272)
	)
	(segment
		(start 106.256956 77.4375)
		(end 105.756956 77.9375)
		(width 0.15)
		(layer "In5.Cu")
		(net 1272)
	)
	(segment
		(start 106.97862 79.726924)
		(end 108.0625 78.643044)
		(width 0.15)
		(layer "In5.Cu")
		(net 1272)
	)
	(segment
		(start 102.7625 85.043044)
		(end 102.7625 80.843044)
		(width 0.15)
		(layer "In5.Cu")
		(net 1272)
	)
	(segment
		(start 108.0625 78.643044)
		(end 108.0625 77.856956)
		(width 0.15)
		(layer "In5.Cu")
		(net 1272)
	)
	(segment
		(start 104.743032 77.537488)
		(end 104.743032 77.3625)
		(width 0.15)
		(layer "In5.Cu")
		(net 1272)
	)
	(segment
		(start 106.443044 80.2625)
		(end 106.761242 79.944301)
		(width 0.15)
		(layer "In5.Cu")
		(net 1272)
	)
	(segment
		(start 104.743032 77.3625)
		(end 104.580532 77.2)
		(width 0.15)
		(layer "In5.Cu")
		(net 1272)
	)
	(segment
		(start 106.761242 79.944301)
		(end 106.97862 79.726924)
		(width 0.15)
		(layer "In5.Cu")
		(net 1272)
	)
	(segment
		(start 102.7625 80.843044)
		(end 103.343044 80.2625)
		(width 0.15)
		(layer "In5.Cu")
		(net 1272)
	)
	(segment
		(start 96.0625 91.743044)
		(end 102.7625 85.043044)
		(width 0.15)
		(layer "In5.Cu")
		(net 1272)
	)
	(segment
		(start 105.143044 77.9375)
		(end 104.743032 77.537488)
		(width 0.15)
		(layer "In5.Cu")
		(net 1272)
	)
	(segment
		(start 96.0625 99.556955)
		(end 96.0625 91.743044)
		(width 0.15)
		(layer "In5.Cu")
		(net 1272)
	)
	(segment
		(start 104.636752 80.1025)
		(end 104.636752 79.93936)
		(width 0.15)
		(layer "In5.Cu")
		(net 1272)
	)
	(segment
		(start 104.796752 79.77936)
		(end 104.876752 79.77936)
		(width 0.15)
		(layer "In5.Cu")
		(net 1272)
	)
	(segment
		(start 105.756956 77.9375)
		(end 105.143044 77.9375)
		(width 0.15)
		(layer "In5.Cu")
		(net 1272)
	)
	(segment
		(start 103.343044 80.2625)
		(end 104.476752 80.2625)
		(width 0.15)
		(layer "In5.Cu")
		(net 1272)
	)
	(segment
		(start 96.796706 100.291161)
		(end 96.0625 99.556955)
		(width 0.15)
		(layer "In5.Cu")
		(net 1272)
	)
	(segment
		(start 96.796706 100.503294)
		(end 96.796706 100.291161)
		(width 0.15)
		(layer "In5.Cu")
		(net 1272)
	)
	(segment
		(start 105.036752 79.93936)
		(end 105.036752 80.1025)
		(width 0.15)
		(layer "In5.Cu")
		(net 1272)
	)
	(segment
		(start 105.196752 80.2625)
		(end 105.276752 80.2625)
		(width 0.15)
		(layer "In5.Cu")
		(net 1272)
	)
	(segment
		(start 108.0625 77.856956)
		(end 107.643044 77.4375)
		(width 0.15)
		(layer "In5.Cu")
		(net 1272)
	)
	(segment
		(start 107.643044 77.4375)
		(end 106.256956 77.4375)
		(width 0.15)
		(layer "In5.Cu")
		(net 1272)
	)
	(segment
		(start 105.276752 80.2625)
		(end 106.443044 80.2625)
		(width 0.15)
		(layer "In5.Cu")
		(net 1272)
	)
	(arc
		(start 104.476752 80.2625)
		(mid 104.589889 80.215637)
		(end 104.636752 80.1025)
		(width 0.15)
		(layer "In5.Cu")
		(net 1272)
	)
	(arc
		(start 104.876752 79.77936)
		(mid 104.989889 79.826223)
		(end 105.036752 79.93936)
		(width 0.15)
		(layer "In5.Cu")
		(net 1272)
	)
	(arc
		(start 104.636752 79.93936)
		(mid 104.683615 79.826223)
		(end 104.796752 79.77936)
		(width 0.15)
		(layer "In5.Cu")
		(net 1272)
	)
	(arc
		(start 105.036752 80.1025)
		(mid 105.083615 80.215637)
		(end 105.196752 80.2625)
		(width 0.15)
		(layer "In5.Cu")
		(net 1272)
	)
	(segment
		(start 96.87663 102.285)
		(end 97.585 101.57663)
		(width 0.19)
		(layer "F.Cu")
		(net 1273)
	)
	(segment
		(start 97.585 101.57663)
		(end 97.585 100.62337)
		(width 0.19)
		(layer "F.Cu")
		(net 1273)
	)
	(segment
		(start 105.065532 77.315)
		(end 105.180532 77.2)
		(width 0.19)
		(layer "F.Cu")
		(net 1273)
	)
	(segment
		(start 97.585 100.62337)
		(end 97.203294 100.241664)
		(width 0.19)
		(layer "F.Cu")
		(net 1273)
	)
	(segment
		(start 105.330532 78.15)
		(end 105.065532 77.885)
		(width 0.19)
		(layer "F.Cu")
		(net 1273)
	)
	(segment
		(start 97.203294 100.241664)
		(end 97.203294 100.096706)
		(width 0.19)
		(layer "F.Cu")
		(net 1273)
	)
	(segment
		(start 89.92 102.285)
		(end 96.87663 102.285)
		(width 0.19)
		(layer "F.Cu")
		(net 1273)
	)
	(segment
		(start 89.605 102.6)
		(end 89.92 102.285)
		(width 0.19)
		(layer "F.Cu")
		(net 1273)
	)
	(segment
		(start 105.065532 77.885)
		(end 105.065532 77.315)
		(width 0.19)
		(layer "F.Cu")
		(net 1273)
	)
	(segment
		(start 89.58 102.6)
		(end 89.605 102.6)
		(width 0.19)
		(layer "F.Cu")
		(net 1273)
	)
	(via
		(at 105.180532 77.2)
		(size 0.45)
		(drill 0.1)
		(layers "F.Cu" "B.Cu")
		(net 1273)
	)
	(via
		(at 97.203294 100.096706)
		(size 0.45)
		(drill 0.1)
		(layers "F.Cu" "B.Cu")
		(net 1273)
	)
	(segment
		(start 105.180532 77.2)
		(end 105.018032 77.3625)
		(width 0.15)
		(layer "In5.Cu")
		(net 1273)
	)
	(segment
		(start 96.991161 100.096706)
		(end 97.203294 100.096706)
		(width 0.15)
		(layer "In5.Cu")
		(net 1273)
	)
	(segment
		(start 108.3375 77.743044)
		(end 108.3375 78.756956)
		(width 0.15)
		(layer "In5.Cu")
		(net 1273)
	)
	(segment
		(start 107.756956 77.1625)
		(end 108.3375 77.743044)
		(width 0.15)
		(layer "In5.Cu")
		(net 1273)
	)
	(segment
		(start 105.643044 77.6625)
		(end 106.143044 77.1625)
		(width 0.15)
		(layer "In5.Cu")
		(net 1273)
	)
	(segment
		(start 105.018032 77.3625)
		(end 105.018032 77.423576)
		(width 0.15)
		(layer "In5.Cu")
		(net 1273)
	)
	(segment
		(start 106.556956 80.5375)
		(end 103.456956 80.5375)
		(width 0.15)
		(layer "In5.Cu")
		(net 1273)
	)
	(segment
		(start 105.018032 77.423576)
		(end 105.256956 77.6625)
		(width 0.15)
		(layer "In5.Cu")
		(net 1273)
	)
	(segment
		(start 96.3375 91.856956)
		(end 96.3375 99.443045)
		(width 0.15)
		(layer "In5.Cu")
		(net 1273)
	)
	(segment
		(start 96.3375 99.443045)
		(end 96.991161 100.096706)
		(width 0.15)
		(layer "In5.Cu")
		(net 1273)
	)
	(segment
		(start 103.456956 80.5375)
		(end 103.0375 80.956956)
		(width 0.15)
		(layer "In5.Cu")
		(net 1273)
	)
	(segment
		(start 103.0375 80.956956)
		(end 103.0375 85.156956)
		(width 0.15)
		(layer "In5.Cu")
		(net 1273)
	)
	(segment
		(start 105.256956 77.6625)
		(end 105.643044 77.6625)
		(width 0.15)
		(layer "In5.Cu")
		(net 1273)
	)
	(segment
		(start 106.143044 77.1625)
		(end 107.756956 77.1625)
		(width 0.15)
		(layer "In5.Cu")
		(net 1273)
	)
	(segment
		(start 108.3375 78.756956)
		(end 106.556956 80.5375)
		(width 0.15)
		(layer "In5.Cu")
		(net 1273)
	)
	(segment
		(start 103.0375 85.156956)
		(end 96.3375 91.856956)
		(width 0.15)
		(layer "In5.Cu")
		(net 1273)
	)
	(segment
		(start 127.959999 65.49)
		(end 131.549999 65.49)
		(width 0.2)
		(layer "F.Cu")
		(net 1274)
	)
	(segment
		(start 127.144212 63.49)
		(end 127.144212 64.674213)
		(width 0.2)
		(layer "F.Cu")
		(net 1274)
	)
	(segment
		(start 133.549999 62.581207)
		(end 132.945349 61.976557)
		(width 0.2)
		(layer "F.Cu")
		(net 1274)
	)
	(segment
		(start 127.339999 64.87)
		(end 127.959999 65.49)
		(width 0.2)
		(layer "F.Cu")
		(net 1274)
	)
	(segment
		(start 131.549999 65.49)
		(end 133.549999 63.49)
		(width 0.2)
		(layer "F.Cu")
		(net 1274)
	)
	(segment
		(start 127.144212 64.674213)
		(end 127.339999 64.87)
		(width 0.2)
		(layer "F.Cu")
		(net 1274)
	)
	(segment
		(start 133.549999 63.49)
		(end 133.549999 62.581207)
		(width 0.2)
		(layer "F.Cu")
		(net 1274)
	)
	(segment
		(start 125.794212 64.175787)
		(end 125.089999 64.88)
		(width 0.2)
		(layer "F.Cu")
		(net 1275)
	)
	(segment
		(start 125.794212 63.49)
		(end 125.794212 64.175787)
		(width 0.2)
		(layer "F.Cu")
		(net 1275)
	)
	(segment
		(start 128.709212 60.525)
		(end 129.534999 60.525)
		(width 0.2)
		(layer "F.Cu")
		(net 1276)
	)
	(segment
		(start 129.534999 60.525)
		(end 129.839999 60.22)
		(width 0.2)
		(layer "F.Cu")
		(net 1276)
	)
	(segment
		(start 129.839999 60.22)
		(end 130.279999 60.22)
		(width 0.2)
		(layer "F.Cu")
		(net 1276)
	)
	(segment
		(start 130.279999 60.22)
		(end 131.029999 59.47)
		(width 0.2)
		(layer "F.Cu")
		(net 1276)
	)
	(segment
		(start 128.709212 60.075)
		(end 129.464999 60.075)
		(width 0.2)
		(layer "F.Cu")
		(net 1277)
	)
	(segment
		(start 129.464999 60.075)
		(end 130.069999 59.47)
		(width 0.2)
		(layer "F.Cu")
		(net 1277)
	)
	(segment
		(start 130.014999 63.025)
		(end 128.709212 63.025)
		(width 0.2)
		(layer "F.Cu")
		(net 1278)
	)
	(segment
		(start 130.069999 62.97)
		(end 130.014999 63.025)
		(width 0.2)
		(layer "F.Cu")
		(net 1278)
	)
	(via
		(at 109.510001 60.22)
		(size 0.45)
		(drill 0.1)
		(layers "F.Cu" "B.Cu")
		(net 1278)
	)
	(via
		(at 115.1 58.54)
		(size 0.45)
		(drill 0.1)
		(layers "F.Cu" "B.Cu")
		(net 1278)
	)
	(via
		(at 107.035001 57.68)
		(size 0.45)
		(drill 0.1)
		(layers "F.Cu" "B.Cu")
		(net 1278)
	)
	(via
		(at 130.069999 62.97)
		(size 0.45)
		(drill 0.1)
		(layers "F.Cu" "B.Cu")
		(net 1278)
	)
	(segment
		(start 107.435001 57.28)
		(end 107.035001 57.68)
		(width 0.1)
		(layer "B.Cu")
		(net 1278)
	)
	(segment
		(start 109.510001 60.22)
		(end 109.910001 60.62)
		(width 0.1)
		(layer "B.Cu")
		(net 1278)
	)
	(segment
		(start 117.37 60.81)
		(end 127.8 60.81)
		(width 0.2)
		(layer "B.Cu")
		(net 1278)
	)
	(segment
		(start 128.68 62.76)
		(end 129.22 63.3)
		(width 0.2)
		(layer "B.Cu")
		(net 1278)
	)
	(segment
		(start 109.436743 57.280999)
		(end 107.436 57.280999)
		(width 0.1)
		(layer "B.Cu")
		(net 1278)
	)
	(segment
		(start 110.46 60.38)
		(end 110.46 58.304256)
		(width 0.1)
		(layer "B.Cu")
		(net 1278)
	)
	(segment
		(start 129.22 63.3)
		(end 129.739999 63.3)
		(width 0.2)
		(layer "B.Cu")
		(net 1278)
	)
	(segment
		(start 110.46 58.304256)
		(end 109.436743 57.280999)
		(width 0.1)
		(layer "B.Cu")
		(net 1278)
	)
	(segment
		(start 109.910001 60.62)
		(end 110.22 60.62)
		(width 0.1)
		(layer "B.Cu")
		(net 1278)
	)
	(segment
		(start 128.68 61.69)
		(end 128.68 62.76)
		(width 0.2)
		(layer "B.Cu")
		(net 1278)
	)
	(segment
		(start 115.1 58.54)
		(end 117.37 60.81)
		(width 0.2)
		(layer "B.Cu")
		(net 1278)
	)
	(segment
		(start 107.436 57.280999)
		(end 107.435001 57.28)
		(width 0.1)
		(layer "B.Cu")
		(net 1278)
	)
	(segment
		(start 127.8 60.81)
		(end 128.68 61.69)
		(width 0.2)
		(layer "B.Cu")
		(net 1278)
	)
	(segment
		(start 110.22 60.62)
		(end 110.46 60.38)
		(width 0.1)
		(layer "B.Cu")
		(net 1278)
	)
	(segment
		(start 129.739999 63.3)
		(end 130.069999 62.97)
		(width 0.2)
		(layer "B.Cu")
		(net 1278)
	)
	(segment
		(start 106.35 56.7)
		(end 106.370001 56.68)
		(width 0.1)
		(layer "F.Cu")
		(net 1279)
	)
	(segment
		(start 105.39 56.7)
		(end 106.35 56.7)
		(width 0.1)
		(layer "F.Cu")
		(net 1279)
	)
	(segment
		(start 105.235 56.855)
		(end 105.39 56.7)
		(width 0.1)
		(layer "F.Cu")
		(net 1279)
	)
	(segment
		(start 104.04 56.854999)
		(end 105.235 56.855)
		(width 0.1)
		(layer "F.Cu")
		(net 1279)
	)
	(segment
		(start 105.235 57.505001)
		(end 105.39 57.66)
		(width 0.1)
		(layer "F.Cu")
		(net 1280)
	)
	(segment
		(start 104.04 57.505)
		(end 105.235 57.505001)
		(width 0.1)
		(layer "F.Cu")
		(net 1280)
	)
	(segment
		(start 106.35 57.66)
		(end 106.37 57.68)
		(width 0.1)
		(layer "F.Cu")
		(net 1280)
	)
	(segment
		(start 105.39 57.66)
		(end 106.35 57.66)
		(width 0.1)
		(layer "F.Cu")
		(net 1280)
	)
	(segment
		(start 172.869468 118.286)
		(end 172.869468 119.216)
		(width 0.1)
		(layer "F.Cu")
		(net 1281)
	)
	(segment
		(start 172.465 120.401)
		(end 172.465 119.640468)
		(width 0.1)
		(layer "F.Cu")
		(net 1281)
	)
	(segment
		(start 172.465 119.640468)
		(end 172.879468 119.226)
		(width 0.1)
		(layer "F.Cu")
		(net 1281)
	)
	(segment
		(start 172.869468 119.216)
		(end 172.879468 119.226)
		(width 0.1)
		(layer "F.Cu")
		(net 1281)
	)
	(segment
		(start 171.254468 134.56)
		(end 171.264468 134.57)
		(width 0.1)
		(layer "F.Cu")
		(net 1282)
	)
	(segment
		(start 170.879468 134.955)
		(end 171.264468 134.57)
		(width 0.1)
		(layer "F.Cu")
		(net 1282)
	)
	(segment
		(start 170.879468 135.92)
		(end 170.879468 134.955)
		(width 0.1)
		(layer "F.Cu")
		(net 1282)
	)
	(segment
		(start 171.254468 133.6)
		(end 171.254468 134.56)
		(width 0.1)
		(layer "F.Cu")
		(net 1282)
	)
	(segment
		(start 162.379468 99.899468)
		(end 162.379468 100.775)
		(width 0.2)
		(layer "F.Cu")
		(net 1283)
	)
	(segment
		(start 162.694468 98.625)
		(end 162.694468 99.555532)
		(width 0.1)
		(layer "F.Cu")
		(net 1283)
	)
	(segment
		(start 162.694468 99.555532)
		(end 162.708936 99.57)
		(width 0.1)
		(layer "F.Cu")
		(net 1283)
	)
	(segment
		(start 162.708936 99.57)
		(end 162.379468 99.899468)
		(width 0.2)
		(layer "F.Cu")
		(net 1283)
	)
	(segment
		(start 162.729468 78.6)
		(end 162.709468 78.58)
		(width 0.1)
		(layer "F.Cu")
		(net 1284)
	)
	(segment
		(start 162.297234 79.942234)
		(end 162.729468 79.51)
		(width 0.1)
		(layer "F.Cu")
		(net 1284)
	)
	(segment
		(start 162.297234 80.652234)
		(end 162.297234 79.942234)
		(width 0.1)
		(layer "F.Cu")
		(net 1284)
	)
	(segment
		(start 162.729468 79.51)
		(end 162.729468 78.6)
		(width 0.1)
		(layer "F.Cu")
		(net 1284)
	)
	(segment
		(start 70.25 56.4)
		(end 70.25 63.37)
		(width 0.1)
		(layer "F.Cu")
		(net 1285)
	)
	(segment
		(start 108.7 63.45)
		(end 108.37 63.78)
		(width 0.1)
		(layer "F.Cu")
		(net 1285)
	)
	(segment
		(start 90.75 68.2)
		(end 92.965 65.985)
		(width 0.1)
		(layer "F.Cu")
		(net 1285)
	)
	(segment
		(start 181.960369 86.759099)
		(end 180.725 87.994468)
		(width 0.1)
		(layer "F.Cu")
		(net 1285)
	)
	(segment
		(start 154.087868 81.087868)
		(end 154.087868 80.612132)
		(width 0.1)
		(layer "F.Cu")
		(net 1285)
	)
	(segment
		(start 155.2 83.4)
		(end 157.8 86)
		(width 0.1)
		(layer "F.Cu")
		(net 1285)
	)
	(segment
		(start 93.98 66)
		(end 94.48 65.5)
		(width 0.1)
		(layer "F.Cu")
		(net 1285)
	)
	(segment
		(start 109.11 63.45)
		(end 108.7 63.45)
		(width 0.1)
		(layer "F.Cu")
		(net 1285)
	)
	(segment
		(start 157.8 86)
		(end 165.8 86)
		(width 0.1)
		(layer "F.Cu")
		(net 1285)
	)
	(segment
		(start 183.759099 86.759099)
		(end 181.960369 86.759099)
		(width 0.1)
		(layer "F.Cu")
		(net 1285)
	)
	(segment
		(start 100.3 62.4)
		(end 100.6 62.4)
		(width 0.1)
		(layer "F.Cu")
		(net 1285)
	)
	(segment
		(start 184.6 88.4)
		(end 184.6 87.6)
		(width 0.1)
		(layer "F.Cu")
		(net 1285)
	)
	(segment
		(start 154.087868 80.612132)
		(end 156.1 78.6)
		(width 0.1)
		(layer "F.Cu")
		(net 1285)
	)
	(segment
		(start 70.25 63.37)
		(end 72.21 65.33)
		(width 0.1)
		(layer "F.Cu")
		(net 1285)
	)
	(segment
		(start 92.48 65.5)
		(end 92.965 65.985)
		(width 0.1)
		(layer "F.Cu")
		(net 1285)
	)
	(segment
		(start 97.85 64.85)
		(end 96.35 64.85)
		(width 0.1)
		(layer "F.Cu")
		(net 1285)
	)
	(segment
		(start 96 64.5)
		(end 94.48 64.5)
		(width 0.1)
		(layer "F.Cu")
		(net 1285)
	)
	(segment
		(start 72.21 65.33)
		(end 73.64 65.33)
		(width 0.1)
		(layer "F.Cu")
		(net 1285)
	)
	(segment
		(start 156.1 78.6)
		(end 156.1 76.7)
		(width 0.1)
		(layer "F.Cu")
		(net 1285)
	)
	(segment
		(start 98.9 63.8)
		(end 100.3 62.4)
		(width 0.1)
		(layer "F.Cu")
		(net 1285)
	)
	(segment
		(start 153.7 82.7)
		(end 153.7 81.475736)
		(width 0.1)
		(layer "F.Cu")
		(net 1285)
	)
	(segment
		(start 86.5 68.2)
		(end 90.75 68.2)
		(width 0.1)
		(layer "F.Cu")
		(net 1285)
	)
	(segment
		(start 92.98 66)
		(end 93.98 66)
		(width 0.1)
		(layer "F.Cu")
		(net 1285)
	)
	(segment
		(start 155.2 83.4)
		(end 154.4 83.4)
		(width 0.1)
		(layer "F.Cu")
		(net 1285)
	)
	(segment
		(start 78.15 66.65)
		(end 79.5 68)
		(width 0.1)
		(layer "F.Cu")
		(net 1285)
	)
	(segment
		(start 98.9 63.8)
		(end 97.85 64.85)
		(width 0.1)
		(layer "F.Cu")
		(net 1285)
	)
	(segment
		(start 74.96 66.65)
		(end 78.15 66.65)
		(width 0.1)
		(layer "F.Cu")
		(net 1285)
	)
	(segment
		(start 96.35 64.85)
		(end 96 64.5)
		(width 0.1)
		(layer "F.Cu")
		(net 1285)
	)
	(segment
		(start 180.725 87.994468)
		(end 180.725 88.51)
		(width 0.1)
		(layer "F.Cu")
		(net 1285)
	)
	(segment
		(start 154.4 83.4)
		(end 153.7 82.7)
		(width 0.1)
		(layer "F.Cu")
		(net 1285)
	)
	(segment
		(start 153.7 81.475736)
		(end 154.087868 81.087868)
		(width 0.1)
		(layer "F.Cu")
		(net 1285)
	)
	(segment
		(start 79.5 68)
		(end 86.3 68)
		(width 0.1)
		(layer "F.Cu")
		(net 1285)
	)
	(segment
		(start 92.965 65.985)
		(end 92.98 66)
		(width 0.1)
		(layer "F.Cu")
		(net 1285)
	)
	(segment
		(start 167.9 88.1)
		(end 165.8 86)
		(width 0.1)
		(layer "F.Cu")
		(net 1285)
	)
	(segment
		(start 94.48 65.5)
		(end 94.48 64.5)
		(width 0.1)
		(layer "F.Cu")
		(net 1285)
	)
	(segment
		(start 184.6 87.6)
		(end 183.759099 86.759099)
		(width 0.1)
		(layer "F.Cu")
		(net 1285)
	)
	(segment
		(start 86.3 68)
		(end 86.5 68.2)
		(width 0.1)
		(layer "F.Cu")
		(net 1285)
	)
	(segment
		(start 73.64 65.33)
		(end 74.96 66.65)
		(width 0.1)
		(layer "F.Cu")
		(net 1285)
	)
	(via
		(at 149.5 66.6)
		(size 0.45)
		(drill 0.1)
		(layers "F.Cu" "B.Cu")
		(net 1285)
	)
	(via
		(at 108.37 63.78)
		(size 0.45)
		(drill 0.1)
		(layers "F.Cu" "B.Cu")
		(net 1285)
	)
	(via
		(at 100.6 62.4)
		(size 0.45)
		(drill 0.1)
		(layers "F.Cu" "B.Cu")
		(net 1285)
	)
	(via
		(at 167.9 88.1)
		(size 0.45)
		(drill 0.1)
		(layers "F.Cu" "B.Cu")
		(net 1285)
	)
	(via
		(at 184.6 88.4)
		(size 0.45)
		(drill 0.1)
		(layers "F.Cu" "B.Cu")
		(net 1285)
	)
	(via
		(at 153.78 70.35)
		(size 0.45)
		(drill 0.1)
		(layers "F.Cu" "B.Cu")
		(net 1285)
	)
	(via
		(at 156.1 76.7)
		(size 0.45)
		(drill 0.1)
		(layers "F.Cu" "B.Cu")
		(net 1285)
	)
	(segment
		(start 153.78 70.35)
		(end 153.77 70.34)
		(width 0.1)
		(layer "B.Cu")
		(net 1285)
	)
	(segment
		(start 100.6 62.4)
		(end 100.58 62.42)
		(width 0.1)
		(layer "B.Cu")
		(net 1285)
	)
	(segment
		(start 100.58 62.42)
		(end 98.4 62.42)
		(width 0.1)
		(layer "B.Cu")
		(net 1285)
	)
	(segment
		(start 153.24 70.34)
		(end 149.5 66.6)
		(width 0.1)
		(layer "B.Cu")
		(net 1285)
	)
	(segment
		(start 153.77 70.34)
		(end 153.24 70.34)
		(width 0.1)
		(layer "B.Cu")
		(net 1285)
	)
	(segment
		(start 109.71 62.97)
		(end 110.07 62.61)
		(width 0.1)
		(layer "In5.Cu")
		(net 1285)
	)
	(segment
		(start 101.1 62.4)
		(end 101.54 61.96)
		(width 0.1)
		(layer "In5.Cu")
		(net 1285)
	)
	(segment
		(start 139.95 62.95)
		(end 140.45 62.95)
		(width 0.1)
		(layer "In5.Cu")
		(net 1285)
	)
	(segment
		(start 108.72 62.97)
		(end 109.71 62.97)
		(width 0.1)
		(layer "In5.Cu")
		(net 1285)
	)
	(segment
		(start 108.37 63.78)
		(end 108.37 63.32)
		(width 0.1)
		(layer "In5.Cu")
		(net 1285)
	)
	(segment
		(start 108.33 60.72)
		(end 110.07 60.72)
		(width 0.1)
		(layer "In5.Cu")
		(net 1285)
	)
	(segment
		(start 135.3 62.3)
		(end 139.3 62.3)
		(width 0.1)
		(layer "In5.Cu")
		(net 1285)
	)
	(segment
		(start 102.4 61.74)
		(end 107.31 61.74)
		(width 0.1)
		(layer "In5.Cu")
		(net 1285)
	)
	(segment
		(start 145.432842 62.6)
		(end 149.432842 66.6)
		(width 0.1)
		(layer "In5.Cu")
		(net 1285)
	)
	(segment
		(start 133.72 60.72)
		(end 135.3 62.3)
		(width 0.1)
		(layer "In5.Cu")
		(net 1285)
	)
	(segment
		(start 102.18 61.96)
		(end 102.4 61.74)
		(width 0.1)
		(layer "In5.Cu")
		(net 1285)
	)
	(segment
		(start 140.45 62.95)
		(end 140.8 62.6)
		(width 0.1)
		(layer "In5.Cu")
		(net 1285)
	)
	(segment
		(start 140.8 62.6)
		(end 145.432842 62.6)
		(width 0.1)
		(layer "In5.Cu")
		(net 1285)
	)
	(segment
		(start 107.31 61.74)
		(end 108.33 60.72)
		(width 0.1)
		(layer "In5.Cu")
		(net 1285)
	)
	(segment
		(start 139.3 62.3)
		(end 139.95 62.95)
		(width 0.1)
		(layer "In5.Cu")
		(net 1285)
	)
	(segment
		(start 153.78 70.35)
		(end 156.1 72.67)
		(width 0.1)
		(layer "In5.Cu")
		(net 1285)
	)
	(segment
		(start 101.54 61.96)
		(end 102.18 61.96)
		(width 0.1)
		(layer "In5.Cu")
		(net 1285)
	)
	(segment
		(start 110.07 60.72)
		(end 133.72 60.72)
		(width 0.1)
		(layer "In5.Cu")
		(net 1285)
	)
	(segment
		(start 149.432842 66.6)
		(end 149.5 66.6)
		(width 0.1)
		(layer "In5.Cu")
		(net 1285)
	)
	(segment
		(start 110.07 62.61)
		(end 110.07 60.72)
		(width 0.1)
		(layer "In5.Cu")
		(net 1285)
	)
	(segment
		(start 100.6 62.4)
		(end 101.1 62.4)
		(width 0.1)
		(layer "In5.Cu")
		(net 1285)
	)
	(segment
		(start 156.1 72.67)
		(end 156.1 76.7)
		(width 0.1)
		(layer "In5.Cu")
		(net 1285)
	)
	(segment
		(start 108.37 63.32)
		(end 108.72 62.97)
		(width 0.1)
		(layer "In5.Cu")
		(net 1285)
	)
	(segment
		(start 182.41 88.4)
		(end 184.6 88.4)
		(width 0.1)
		(layer "In7.Cu")
		(net 1285)
	)
	(segment
		(start 181 88.1)
		(end 181.18 87.92)
		(width 0.1)
		(layer "In7.Cu")
		(net 1285)
	)
	(segment
		(start 181.18 87.92)
		(end 181.93 87.92)
		(width 0.1)
		(layer "In7.Cu")
		(net 1285)
	)
	(segment
		(start 181.93 87.92)
		(end 182.41 88.4)
		(width 0.1)
		(layer "In7.Cu")
		(net 1285)
	)
	(segment
		(start 167.9 88.1)
		(end 181 88.1)
		(width 0.1)
		(layer "In7.Cu")
		(net 1285)
	)
	(via
		(at 175.25 56.05)
		(size 0.45)
		(drill 0.1)
		(layers "F.Cu" "B.Cu")
		(net 1286)
	)
	(segment
		(start 175.25 56)
		(end 175.25 57.02)
		(width 0.1)
		(layer "B.Cu")
		(net 1286)
	)
	(segment
		(start 93.17 62.85)
		(end 93.52 62.5)
		(width 0.1)
		(layer "F.Cu")
		(net 1287)
	)
	(segment
		(start 96.667906 60.467906)
		(end 96.667906 59.776198)
		(width 0.1)
		(layer "F.Cu")
		(net 1287)
	)
	(segment
		(start 97.2 60.775)
		(end 96.975 60.775)
		(width 0.1)
		(layer "F.Cu")
		(net 1287)
	)
	(segment
		(start 136.830532 69.969468)
		(end 136.9 69.9)
		(width 0.1)
		(layer "F.Cu")
		(net 1287)
	)
	(segment
		(start 93.52 61.5)
		(end 93.52 62.5)
		(width 0.1)
		(layer "F.Cu")
		(net 1287)
	)
	(segment
		(start 92.8 61.7)
		(end 93 61.5)
		(width 0.1)
		(layer "F.Cu")
		(net 1287)
	)
	(segment
		(start 93 61.5)
		(end 93.52 61.5)
		(width 0.1)
		(layer "F.Cu")
		(net 1287)
	)
	(segment
		(start 96.975 60.775)
		(end 96.667906 60.467906)
		(width 0.1)
		(layer "F.Cu")
		(net 1287)
	)
	(segment
		(start 136.830532 70.65)
		(end 136.830532 69.969468)
		(width 0.1)
		(layer "F.Cu")
		(net 1287)
	)
	(segment
		(start 92.1 62.85)
		(end 93.17 62.85)
		(width 0.1)
		(layer "F.Cu")
		(net 1287)
	)
	(via
		(at 92.8 61.7)
		(size 0.45)
		(drill 0.1)
		(layers "F.Cu" "B.Cu")
		(net 1287)
	)
	(via
		(at 136.9 69.9)
		(size 0.45)
		(drill 0.1)
		(layers "F.Cu" "B.Cu")
		(net 1287)
	)
	(via
		(at 96.667906 59.776198)
		(size 0.45)
		(drill 0.1)
		(layers "F.Cu" "B.Cu")
		(net 1287)
	)
	(segment
		(start 94.5 59.8)
		(end 96.4 59.8)
		(width 0.1)
		(layer "B.Cu")
		(net 1287)
	)
	(segment
		(start 98 55.4)
		(end 97.2 56.2)
		(width 0.1)
		(layer "B.Cu")
		(net 1287)
	)
	(segment
		(start 124.01 54.6)
		(end 122.86 54.6)
		(width 0.1)
		(layer "B.Cu")
		(net 1287)
	)
	(segment
		(start 96.667906 59.776198)
		(end 96.576198 59.68449)
		(width 0.1)
		(layer "B.Cu")
		(net 1287)
	)
	(segment
		(start 124.4 59.56)
		(end 123.9 59.06)
		(width 0.1)
		(layer "B.Cu")
		(net 1287)
	)
	(segment
		(start 130.55 63.25)
		(end 130.55 62.11)
		(width 0.1)
		(layer "B.Cu")
		(net 1287)
	)
	(segment
		(start 96.4 59.8)
		(end 96.576198 59.623802)
		(width 0.1)
		(layer "B.Cu")
		(net 1287)
	)
	(segment
		(start 130.55 62.11)
		(end 128 59.56)
		(width 0.1)
		(layer "B.Cu")
		(net 1287)
	)
	(segment
		(start 97.2 56.2)
		(end 97.2 59)
		(width 0.1)
		(layer "B.Cu")
		(net 1287)
	)
	(segment
		(start 92.8 61.5)
		(end 94.5 59.8)
		(width 0.1)
		(layer "B.Cu")
		(net 1287)
	)
	(segment
		(start 122.86 55.29)
		(end 122.86 54.6)
		(width 0.1)
		(layer "B.Cu")
		(net 1287)
	)
	(segment
		(start 96.576198 59.68449)
		(end 96.576198 59.623802)
		(width 0.1)
		(layer "B.Cu")
		(net 1287)
	)
	(segment
		(start 97.2 59)
		(end 96.65 59.55)
		(width 0.1)
		(layer "B.Cu")
		(net 1287)
	)
	(segment
		(start 122.86 54.6)
		(end 100.2 54.6)
		(width 0.1)
		(layer "B.Cu")
		(net 1287)
	)
	(segment
		(start 123.9 59.06)
		(end 123.9 56.33)
		(width 0.1)
		(layer "B.Cu")
		(net 1287)
	)
	(segment
		(start 132 68.5)
		(end 130.15 66.65)
		(width 0.1)
		(layer "B.Cu")
		(net 1287)
	)
	(segment
		(start 96.65 59.55)
		(end 96.667906 59.567906)
		(width 0.1)
		(layer "B.Cu")
		(net 1287)
	)
	(segment
		(start 123.9 56.33)
		(end 124.49 55.74)
		(width 0.1)
		(layer "B.Cu")
		(net 1287)
	)
	(segment
		(start 96.667906 59.567906)
		(end 96.667906 59.776198)
		(width 0.1)
		(layer "B.Cu")
		(net 1287)
	)
	(segment
		(start 135.5 68.5)
		(end 132 68.5)
		(width 0.1)
		(layer "B.Cu")
		(net 1287)
	)
	(segment
		(start 99.4 55.4)
		(end 98 55.4)
		(width 0.1)
		(layer "B.Cu")
		(net 1287)
	)
	(segment
		(start 130.15 63.65)
		(end 130.55 63.25)
		(width 0.1)
		(layer "B.Cu")
		(net 1287)
	)
	(segment
		(start 100.2 54.6)
		(end 99.4 55.4)
		(width 0.1)
		(layer "B.Cu")
		(net 1287)
	)
	(segment
		(start 136.9 69.9)
		(end 135.5 68.5)
		(width 0.1)
		(layer "B.Cu")
		(net 1287)
	)
	(segment
		(start 128 59.56)
		(end 124.4 59.56)
		(width 0.1)
		(layer "B.Cu")
		(net 1287)
	)
	(segment
		(start 92.8 61.7)
		(end 92.8 61.5)
		(width 0.1)
		(layer "B.Cu")
		(net 1287)
	)
	(segment
		(start 130.15 66.65)
		(end 130.15 63.65)
		(width 0.1)
		(layer "B.Cu")
		(net 1287)
	)
	(segment
		(start 124.49 55.74)
		(end 124.49 55.08)
		(width 0.1)
		(layer "B.Cu")
		(net 1287)
	)
	(segment
		(start 96.576198 59.623802)
		(end 96.65 59.55)
		(width 0.1)
		(layer "B.Cu")
		(net 1287)
	)
	(segment
		(start 124.49 55.08)
		(end 124.01 54.6)
		(width 0.1)
		(layer "B.Cu")
		(net 1287)
	)
	(segment
		(start 112.9 86)
		(end 117.1 90.2)
		(width 0.1)
		(layer "F.Cu")
		(net 1292)
	)
	(segment
		(start 98 80.5)
		(end 98.2 80.7)
		(width 0.1)
		(layer "F.Cu")
		(net 1292)
	)
	(segment
		(start 109.8 83.8)
		(end 109.8 84.4)
		(width 0.1)
		(layer "F.Cu")
		(net 1292)
	)
	(segment
		(start 105.6 83.3)
		(end 109.3 83.3)
		(width 0.1)
		(layer "F.Cu")
		(net 1292)
	)
	(segment
		(start 90.780532 80.5)
		(end 98 80.5)
		(width 0.1)
		(layer "F.Cu")
		(net 1292)
	)
	(segment
		(start 109.8 84.4)
		(end 110.3 84.9)
		(width 0.1)
		(layer "F.Cu")
		(net 1292)
	)
	(segment
		(start 104.2 81.9)
		(end 105.6 83.3)
		(width 0.1)
		(layer "F.Cu")
		(net 1292)
	)
	(segment
		(start 117.1 90.2)
		(end 120.3 90.2)
		(width 0.1)
		(layer "F.Cu")
		(net 1292)
	)
	(segment
		(start 110.3 84.9)
		(end 112.6 84.9)
		(width 0.1)
		(layer "F.Cu")
		(net 1292)
	)
	(segment
		(start 112.9 85.2)
		(end 112.9 86)
		(width 0.1)
		(layer "F.Cu")
		(net 1292)
	)
	(segment
		(start 109.3 83.3)
		(end 109.8 83.8)
		(width 0.1)
		(layer "F.Cu")
		(net 1292)
	)
	(segment
		(start 89.930532 79.65)
		(end 90.780532 80.5)
		(width 0.1)
		(layer "F.Cu")
		(net 1292)
	)
	(segment
		(start 151.8 100)
		(end 151 100)
		(width 0.1)
		(layer "F.Cu")
		(net 1292)
	)
	(segment
		(start 100.5 81.9)
		(end 104.2 81.9)
		(width 0.1)
		(layer "F.Cu")
		(net 1292)
	)
	(segment
		(start 99.9 80.7)
		(end 100 80.8)
		(width 0.1)
		(layer "F.Cu")
		(net 1292)
	)
	(segment
		(start 98.2 80.7)
		(end 99.9 80.7)
		(width 0.1)
		(layer "F.Cu")
		(net 1292)
	)
	(segment
		(start 100 81.4)
		(end 100.5 81.9)
		(width 0.1)
		(layer "F.Cu")
		(net 1292)
	)
	(segment
		(start 112.6 84.9)
		(end 112.9 85.2)
		(width 0.1)
		(layer "F.Cu")
		(net 1292)
	)
	(segment
		(start 100 80.8)
		(end 100 81.4)
		(width 0.1)
		(layer "F.Cu")
		(net 1292)
	)
	(via
		(at 129.8 88.4)
		(size 0.45)
		(drill 0.1)
		(layers "F.Cu" "B.Cu")
		(net 1292)
	)
	(via
		(at 120.3 90.2)
		(size 0.45)
		(drill 0.1)
		(layers "F.Cu" "B.Cu")
		(net 1292)
	)
	(via
		(at 151 100)
		(size 0.45)
		(drill 0.1)
		(layers "F.Cu" "B.Cu")
		(net 1292)
	)
	(segment
		(start 122 91.9)
		(end 120.3 90.2)
		(width 0.1)
		(layer "In5.Cu")
		(net 1292)
	)
	(segment
		(start 129.8 89.2)
		(end 127.1 91.9)
		(width 0.1)
		(layer "In5.Cu")
		(net 1292)
	)
	(segment
		(start 127.1 91.9)
		(end 122 91.9)
		(width 0.1)
		(layer "In5.Cu")
		(net 1292)
	)
	(segment
		(start 129.8 88.4)
		(end 129.8 89.2)
		(width 0.1)
		(layer "In5.Cu")
		(net 1292)
	)
	(segment
		(start 134.3 88.4)
		(end 145.9 100)
		(width 0.1)
		(layer "In7.Cu")
		(net 1292)
	)
	(segment
		(start 151 100)
		(end 145.9 100)
		(width 0.1)
		(layer "In7.Cu")
		(net 1292)
	)
	(segment
		(start 134.3 88.4)
		(end 129.8 88.4)
		(width 0.1)
		(layer "In7.Cu")
		(net 1292)
	)
	(segment
		(start 190.081 125.919)
		(end 190.4 125.6)
		(width 0.1)
		(layer "F.Cu")
		(net 1293)
	)
	(segment
		(start 139.23 130.67)
		(end 139.25 130.65)
		(width 0.2)
		(layer "F.Cu")
		(net 1293)
	)
	(segment
		(start 142.5 71.6)
		(end 141.5 71.6)
		(width 0.1)
		(layer "F.Cu")
		(net 1293)
	)
	(segment
		(start 141.5 71.6)
		(end 140.9 71)
		(width 0.1)
		(layer "F.Cu")
		(net 1293)
	)
	(segment
		(start 182.5 134.6)
		(end 182.5 132.3)
		(width 0.1)
		(layer "F.Cu")
		(net 1293)
	)
	(segment
		(start 144.030532 70.65)
		(end 143.380532 71.3)
		(width 0.1)
		(layer "F.Cu")
		(net 1293)
	)
	(segment
		(start 182.015 125.45)
		(end 182.015 126.06)
		(width 0.15)
		(layer "F.Cu")
		(net 1293)
	)
	(segment
		(start 145.605391 127.025942)
		(end 146.15 126.481333)
		(width 0.2)
		(layer "F.Cu")
		(net 1293)
	)
	(segment
		(start 140.9 71)
		(end 140.9 70.4)
		(width 0.1)
		(layer "F.Cu")
		(net 1293)
	)
	(segment
		(start 140.9 70.4)
		(end 140.4 69.9)
		(width 0.1)
		(layer "F.Cu")
		(net 1293)
	)
	(segment
		(start 182.025 141.06)
		(end 182.025 140.446569)
		(width 0.2)
		(layer "F.Cu")
		(net 1293)
	)
	(segment
		(start 146.15 126.481333)
		(end 146.15 126.15)
		(width 0.2)
		(layer "F.Cu")
		(net 1293)
	)
	(segment
		(start 142.8 71.3)
		(end 142.5 71.6)
		(width 0.1)
		(layer "F.Cu")
		(net 1293)
	)
	(segment
		(start 182.025 108.325)
		(end 182.05 108.3)
		(width 0.15)
		(layer "F.Cu")
		(net 1293)
	)
	(segment
		(start 182.025 140.446569)
		(end 182.008431 140.43)
		(width 0.2)
		(layer "F.Cu")
		(net 1293)
	)
	(segment
		(start 182.5 132.3)
		(end 182.45 132.25)
		(width 0.1)
		(layer "F.Cu")
		(net 1293)
	)
	(segment
		(start 140.4 69.9)
		(end 140.4 69.5)
		(width 0.1)
		(layer "F.Cu")
		(net 1293)
	)
	(segment
		(start 140.24 130.65)
		(end 139.25 130.65)
		(width 0.2)
		(layer "F.Cu")
		(net 1293)
	)
	(segment
		(start 143.380532 71.3)
		(end 142.8 71.3)
		(width 0.1)
		(layer "F.Cu")
		(net 1293)
	)
	(segment
		(start 145.605391 127.463)
		(end 145.605391 127.025942)
		(width 0.2)
		(layer "F.Cu")
		(net 1293)
	)
	(segment
		(start 182.025 109.06)
		(end 182.025 108.325)
		(width 0.15)
		(layer "F.Cu")
		(net 1293)
	)
	(segment
		(start 190.081 126.613)
		(end 190.081 125.919)
		(width 0.1)
		(layer "F.Cu")
		(net 1293)
	)
	(via
		(at 162.2 88.4)
		(size 0.45)
		(drill 0.1)
		(layers "F.Cu" "B.Cu")
		(net 1293)
	)
	(via
		(at 146.15 126.15)
		(size 0.45)
		(drill 0.1)
		(layers "F.Cu" "B.Cu")
		(remove_unused_layers yes)
		(keep_end_layers yes)
		(zone_layer_connections)
		(net 1293)
	)
	(via
		(at 187.2 125.4)
		(size 0.45)
		(drill 0.1)
		(layers "F.Cu" "B.Cu")
		(net 1293)
	)
	(via
		(at 140.4 69.5)
		(size 0.45)
		(drill 0.1)
		(layers "F.Cu" "B.Cu")
		(net 1293)
	)
	(via
		(at 182.5 134.6)
		(size 0.45)
		(drill 0.1)
		(layers "F.Cu" "B.Cu")
		(net 1293)
	)
	(via
		(at 169.7 65)
		(size 0.45)
		(drill 0.1)
		(layers "F.Cu" "B.Cu")
		(net 1293)
	)
	(via
		(at 182.015 125.45)
		(size 0.45)
		(drill 0.1)
		(layers "F.Cu" "B.Cu")
		(remove_unused_layers yes)
		(keep_end_layers yes)
		(zone_layer_connections)
		(net 1293)
	)
	(via
		(at 190.4 125.6)
		(size 0.45)
		(drill 0.1)
		(layers "F.Cu" "B.Cu")
		(net 1293)
	)
	(via
		(at 167.5 65.8)
		(size 0.45)
		(drill 0.1)
		(layers "F.Cu" "B.Cu")
		(net 1293)
	)
	(via
		(at 182.45 132.25)
		(size 0.45)
		(drill 0.1)
		(layers "F.Cu" "B.Cu")
		(net 1293)
	)
	(via
		(at 182.05 108.3)
		(size 0.45)
		(drill 0.1)
		(layers "F.Cu" "B.Cu")
		(remove_unused_layers yes)
		(keep_end_layers yes)
		(zone_layer_connections)
		(net 1293)
	)
	(via
		(at 139.25 130.65)
		(size 0.45)
		(drill 0.1)
		(layers "F.Cu" "B.Cu")
		(net 1293)
	)
	(via
		(at 182.008431 140.43)
		(size 0.45)
		(drill 0.1)
		(layers "F.Cu" "B.Cu")
		(remove_unused_layers yes)
		(keep_end_layers yes)
		(zone_layer_connections)
		(net 1293)
	)
	(via
		(at 157.5 77.95)
		(size 0.45)
		(drill 0.1)
		(layers "F.Cu" "B.Cu")
		(net 1293)
	)
	(segment
		(start 169.7 65)
		(end 175.2 65)
		(width 0.1)
		(layer "B.Cu")
		(net 1293)
	)
	(segment
		(start 160.4 100)
		(end 161.7 101.3)
		(width 0.1)
		(layer "B.Cu")
		(net 1293)
	)
	(segment
		(start 160 99.2)
		(end 160.4 99.6)
		(width 0.1)
		(layer "B.Cu")
		(net 1293)
	)
	(segment
		(start 160 98.5)
		(end 160 99.2)
		(width 0.1)
		(layer "B.Cu")
		(net 1293)
	)
	(segment
		(start 163.2 101.3)
		(end 170.2 108.3)
		(width 0.1)
		(layer "B.Cu")
		(net 1293)
	)
	(segment
		(start 139.35 128.7)
		(end 139.25 128.6)
		(width 0.1)
		(layer "B.Cu")
		(net 1293)
	)
	(segment
		(start 182.015 125.45)
		(end 187.15 125.45)
		(width 0.1)
		(layer "B.Cu")
		(net 1293)
	)
	(segment
		(start 139.35 128.7)
		(end 139.25 128.7)
		(width 0.1)
		(layer "B.Cu")
		(net 1293)
	)
	(segment
		(start 140.95 126.15)
		(end 146.15 126.15)
		(width 0.1)
		(layer "B.Cu")
		(net 1293)
	)
	(segment
		(start 139.25 128.9)
		(end 139.25 128.8)
		(width 0.1)
		(layer "B.Cu")
		(net 1293)
	)
	(segment
		(start 139.25 127.85)
		(end 140.95 126.15)
		(width 0.1)
		(layer "B.Cu")
		(net 1293)
	)
	(segment
		(start 177 64.4)
		(end 177.82 65.22)
		(width 0.1)
		(layer "B.Cu")
		(net 1293)
	)
	(segment
		(start 139.25 128.9)
		(end 139.25 128.7)
		(width 0.1)
		(layer "B.Cu")
		(net 1293)
	)
	(segment
		(start 175.8 64.4)
		(end 177 64.4)
		(width 0.1)
		(layer "B.Cu")
		(net 1293)
	)
	(segment
		(start 160.9 98.3)
		(end 160.2 98.3)
		(width 0.1)
		(layer "B.Cu")
		(net 1293)
	)
	(segment
		(start 162.65 93.65)
		(end 161.8 94.5)
		(width 0.1)
		(layer "B.Cu")
		(net 1293)
	)
	(segment
		(start 139.25 128.7)
		(end 139.25 128.6)
		(width 0.1)
		(layer "B.Cu")
		(net 1293)
	)
	(segment
		(start 139.25 128.8)
		(end 139.35 128.7)
		(width 0.1)
		(layer "B.Cu")
		(net 1293)
	)
	(segment
		(start 161.7 101.3)
		(end 163.2 101.3)
		(width 0.1)
		(layer "B.Cu")
		(net 1293)
	)
	(segment
		(start 161.8 94.5)
		(end 161.8 97.4)
		(width 0.1)
		(layer "B.Cu")
		(net 1293)
	)
	(segment
		(start 162.2 92.5)
		(end 162.65 92.95)
		(width 0.1)
		(layer "B.Cu")
		(net 1293)
	)
	(segment
		(start 187.15 125.45)
		(end 187.2 125.4)
		(width 0.1)
		(layer "B.Cu")
		(net 1293)
	)
	(segment
		(start 139.25 128.6)
		(end 139.25 127.85)
		(width 0.1)
		(layer "B.Cu")
		(net 1293)
	)
	(segment
		(start 160.4 99.6)
		(end 160.4 100)
		(width 0.1)
		(layer "B.Cu")
		(net 1293)
	)
	(segment
		(start 162.2 88.4)
		(end 162.2 92.5)
		(width 0.1)
		(layer "B.Cu")
		(net 1293)
	)
	(segment
		(start 161.8 97.4)
		(end 160.9 98.3)
		(width 0.1)
		(layer "B.Cu")
		(net 1293)
	)
	(segment
		(start 139.25 130.65)
		(end 139.25 128.9)
		(width 0.1)
		(layer "B.Cu")
		(net 1293)
	)
	(segment
		(start 140.45 128.7)
		(end 139.35 128.7)
		(width 0.1)
		(layer "B.Cu")
		(net 1293)
	)
	(segment
		(start 160.2 98.3)
		(end 160 98.5)
		(width 0.1)
		(layer "B.Cu")
		(net 1293)
	)
	(segment
		(start 170.2 108.3)
		(end 182.05 108.3)
		(width 0.1)
		(layer "B.Cu")
		(net 1293)
	)
	(segment
		(start 177.82 65.22)
		(end 177.82 66.3)
		(width 0.1)
		(layer "B.Cu")
		(net 1293)
	)
	(segment
		(start 175.2 65)
		(end 175.8 64.4)
		(width 0.1)
		(layer "B.Cu")
		(net 1293)
	)
	(segment
		(start 162.65 92.95)
		(end 162.65 93.65)
		(width 0.1)
		(layer "B.Cu")
		(net 1293)
	)
	(segment
		(start 140.4 69.5)
		(end 140.4 69.1)
		(width 0.1)
		(layer "In2.Cu")
		(net 1293)
	)
	(segment
		(start 166.85 65.8)
		(end 167.5 65.8)
		(width 0.1)
		(layer "In2.Cu")
		(net 1293)
	)
	(segment
		(start 140.4 69.1)
		(end 141.4 68.1)
		(width 0.1)
		(layer "In2.Cu")
		(net 1293)
	)
	(segment
		(start 162.3 68.1)
		(end 162.95 67.45)
		(width 0.1)
		(layer "In2.Cu")
		(net 1293)
	)
	(segment
		(start 162.95 67.45)
		(end 165.2 67.45)
		(width 0.1)
		(layer "In2.Cu")
		(net 1293)
	)
	(segment
		(start 141.4 68.1)
		(end 162.3 68.1)
		(width 0.1)
		(layer "In2.Cu")
		(net 1293)
	)
	(segment
		(start 165.2 67.45)
		(end 166.85 65.8)
		(width 0.1)
		(layer "In2.Cu")
		(net 1293)
	)
	(segment
		(start 162.65 86.6)
		(end 162.65 87.95)
		(width 0.1)
		(layer "In4.Cu")
		(net 1293)
	)
	(segment
		(start 156.075 78.275)
		(end 156.075 80.025)
		(width 0.1)
		(layer "In4.Cu")
		(net 1293)
	)
	(segment
		(start 156.075 80.025)
		(end 162.65 86.6)
		(width 0.1)
		(layer "In4.Cu")
		(net 1293)
	)
	(segment
		(start 157.5 77.95)
		(end 156.4 77.95)
		(width 0.1)
		(layer "In4.Cu")
		(net 1293)
	)
	(segment
		(start 156.4 77.95)
		(end 156.075 78.275)
		(width 0.1)
		(layer "In4.Cu")
		(net 1293)
	)
	(segment
		(start 162.65 87.95)
		(end 162.2 88.4)
		(width 0.1)
		(layer "In4.Cu")
		(net 1293)
	)
	(segment
		(start 163.5 74.8)
		(end 169.7 68.6)
		(width 0.1)
		(layer "In5.Cu")
		(net 1293)
	)
	(segment
		(start 168.1 65.8)
		(end 168.9 65)
		(width 0.1)
		(layer "In5.Cu")
		(net 1293)
	)
	(segment
		(start 169.7 68.6)
		(end 169.7 65)
		(width 0.1)
		(layer "In5.Cu")
		(net 1293)
	)
	(segment
		(start 167.5 65.8)
		(end 168.1 65.8)
		(width 0.1)
		(layer "In5.Cu")
		(net 1293)
	)
	(segment
		(start 162.525 77.95)
		(end 163.5 76.975)
		(width 0.1)
		(layer "In5.Cu")
		(net 1293)
	)
	(segment
		(start 163.5 74.8)
		(end 163.5 76.975)
		(width 0.1)
		(layer "In5.Cu")
		(net 1293)
	)
	(segment
		(start 168.9 65)
		(end 169.7 65)
		(width 0.1)
		(layer "In5.Cu")
		(net 1293)
	)
	(segment
		(start 162.525 77.95)
		(end 157.5 77.95)
		(width 0.1)
		(layer "In5.Cu")
		(net 1293)
	)
	(segment
		(start 182.8 109.05)
		(end 182.05 108.3)
		(width 0.15)
		(layer "In7.Cu")
		(net 1293)
	)
	(segment
		(start 190.2 125.4)
		(end 190.4 125.6)
		(width 0.1)
		(layer "In7.Cu")
		(net 1293)
	)
	(segment
		(start 182.8 121)
		(end 187.2 125.4)
		(width 0.15)
		(layer "In7.Cu")
		(net 1293)
	)
	(segment
		(start 182.5 134.6)
		(end 182.5 136.108431)
		(width 0.1)
		(layer "In7.Cu")
		(net 1293)
	)
	(segment
		(start 182.45 132.25)
		(end 182.45 125.885)
		(width 0.1)
		(layer "In7.Cu")
		(net 1293)
	)
	(segment
		(start 182.008431 140.43)
		(end 182.008431 136.6)
		(width 0.1)
		(layer "In7.Cu")
		(net 1293)
	)
	(segment
		(start 167.06 125.35)
		(end 176.31 134.6)
		(width 0.1)
		(layer "In7.Cu")
		(net 1293)
	)
	(segment
		(start 187.2 125.4)
		(end 190.2 125.4)
		(width 0.1)
		(layer "In7.Cu")
		(net 1293)
	)
	(segment
		(start 146.95 125.35)
		(end 167.06 125.35)
		(width 0.1)
		(layer "In7.Cu")
		(net 1293)
	)
	(segment
		(start 146.15 126.15)
		(end 146.95 125.35)
		(width 0.1)
		(layer "In7.Cu")
		(net 1293)
	)
	(segment
		(start 182.8 109.05)
		(end 182.8 121)
		(width 0.15)
		(layer "In7.Cu")
		(net 1293)
	)
	(segment
		(start 182.5 136.108431)
		(end 182.008431 136.6)
		(width 0.1)
		(layer "In7.Cu")
		(net 1293)
	)
	(segment
		(start 182.45 125.885)
		(end 182.015 125.45)
		(width 0.1)
		(layer "In7.Cu")
		(net 1293)
	)
	(segment
		(start 176.31 134.6)
		(end 182.5 134.6)
		(width 0.1)
		(layer "In7.Cu")
		(net 1293)
	)
	(segment
		(start 205.926 144.3)
		(end 207.326 144.3)
		(width 0.1)
		(layer "F.Cu")
		(net 1296)
	)
	(segment
		(start 207.326 144.3)
		(end 207.426 144.2)
		(width 0.1)
		(layer "F.Cu")
		(net 1296)
	)
	(via
		(at 207.426 144.2)
		(size 0.45)
		(drill 0.1)
		(layers "F.Cu" "B.Cu")
		(net 1296)
	)
	(segment
		(start 207.114 144.512)
		(end 207.426 144.2)
		(width 0.1)
		(layer "B.Cu")
		(net 1296)
	)
	(segment
		(start 203.638 144.012)
		(end 204.138 144.512)
		(width 0.1)
		(layer "B.Cu")
		(net 1296)
	)
	(segment
		(start 206.181 144.512)
		(end 205.409 144.512)
		(width 0.1)
		(layer "B.Cu")
		(net 1296)
	)
	(segment
		(start 207.626 144)
		(end 207.426 144.2)
		(width 0.1)
		(layer "B.Cu")
		(net 1296)
	)
	(segment
		(start 208.246 144)
		(end 207.626 144)
		(width 0.1)
		(layer "B.Cu")
		(net 1296)
	)
	(segment
		(start 206.181 144.512)
		(end 207.114 144.512)
		(width 0.1)
		(layer "B.Cu")
		(net 1296)
	)
	(segment
		(start 204.138 144.512)
		(end 205.409 144.512)
		(width 0.1)
		(layer "B.Cu")
		(net 1296)
	)
	(segment
		(start 203.106 144.012)
		(end 203.638 144.012)
		(width 0.1)
		(layer "B.Cu")
		(net 1296)
	)
	(segment
		(start 96.53 65)
		(end 96.53 64.53)
		(width 0.1)
		(layer "B.Cu")
		(net 1298)
	)
	(segment
		(start 97.03 63.47)
		(end 96 63.47)
		(width 0.1)
		(layer "B.Cu")
		(net 1298)
	)
	(segment
		(start 97.098 62.92)
		(end 97.098 63.402)
		(width 0.1)
		(layer "B.Cu")
		(net 1298)
	)
	(segment
		(start 96 64)
		(end 96 63.47)
		(width 0.1)
		(layer "B.Cu")
		(net 1298)
	)
	(segment
		(start 97.098 63.402)
		(end 97.03 63.47)
		(width 0.1)
		(layer "B.Cu")
		(net 1298)
	)
	(segment
		(start 99.79 65)
		(end 99.8 65.01)
		(width 0.1)
		(layer "B.Cu")
		(net 1298)
	)
	(segment
		(start 96.53 64.53)
		(end 96 64)
		(width 0.1)
		(layer "B.Cu")
		(net 1298)
	)
	(segment
		(start 96.53 65)
		(end 99.79 65)
		(width 0.1)
		(layer "B.Cu")
		(net 1298)
	)
	(segment
		(start 158 62.8)
		(end 157.6 62.4)
		(width 0.1)
		(layer "F.Cu")
		(net 1299)
	)
	(segment
		(start 159.647999 62.8)
		(end 158 62.8)
		(width 0.1)
		(layer "F.Cu")
		(net 1299)
	)
	(via
		(at 157.6 62.4)
		(size 0.45)
		(drill 0.1)
		(layers "F.Cu" "B.Cu")
		(net 1299)
	)
	(segment
		(start 160.86 62.29)
		(end 160.29 62.29)
		(width 0.1)
		(layer "B.Cu")
		(net 1299)
	)
	(segment
		(start 160.1 61.5)
		(end 160.1 62.1)
		(width 0.1)
		(layer "B.Cu")
		(net 1299)
	)
	(segment
		(start 161.39 62.75)
		(end 161.92 63.28)
		(width 0.1)
		(layer "B.Cu")
		(net 1299)
	)
	(segment
		(start 157.6 62.4)
		(end 157.6 61.7)
		(width 0.1)
		(layer "B.Cu")
		(net 1299)
	)
	(segment
		(start 161 62.75)
		(end 161.39 62.75)
		(width 0.1)
		(layer "B.Cu")
		(net 1299)
	)
	(segment
		(start 157.6 61.7)
		(end 158.3 61)
		(width 0.1)
		(layer "B.Cu")
		(net 1299)
	)
	(segment
		(start 160.86 62.29)
		(end 160.86 62.61)
		(width 0.1)
		(layer "B.Cu")
		(net 1299)
	)
	(segment
		(start 158.3 61)
		(end 159.6 61)
		(width 0.1)
		(layer "B.Cu")
		(net 1299)
	)
	(segment
		(start 159.6 61)
		(end 160.1 61.5)
		(width 0.1)
		(layer "B.Cu")
		(net 1299)
	)
	(segment
		(start 160.29 62.29)
		(end 160.1 62.1)
		(width 0.1)
		(layer "B.Cu")
		(net 1299)
	)
	(segment
		(start 160.86 62.61)
		(end 161 62.75)
		(width 0.1)
		(layer "B.Cu")
		(net 1299)
	)
	(segment
		(start 219.372618 96.584486)
		(end 219.880132 97.092)
		(width 0.1)
		(layer "B.Cu")
		(net 1300)
	)
	(segment
		(start 218.842132 95.477868)
		(end 218.92 95.4)
		(width 0.1)
		(layer "B.Cu")
		(net 1300)
	)
	(segment
		(start 218.842132 96.584486)
		(end 219.372618 96.584486)
		(width 0.1)
		(layer "B.Cu")
		(net 1300)
	)
	(segment
		(start 218.842132 96.584486)
		(end 218.842132 95.477868)
		(width 0.1)
		(layer "B.Cu")
		(net 1300)
	)
	(segment
		(start 214.9 95.58)
		(end 214.9 96.4)
		(width 0.1)
		(layer "B.Cu")
		(net 1301)
	)
	(segment
		(start 216.972132 95.872132)
		(end 217.540132 96.440132)
		(width 0.1)
		(layer "B.Cu")
		(net 1301)
	)
	(segment
		(start 215.584486 97.084486)
		(end 217.540132 97.084486)
		(width 0.1)
		(layer "B.Cu")
		(net 1301)
	)
	(segment
		(start 217.540132 96.440132)
		(end 217.540132 97.084486)
		(width 0.1)
		(layer "B.Cu")
		(net 1301)
	)
	(segment
		(start 214.9 96.4)
		(end 215.584486 97.084486)
		(width 0.1)
		(layer "B.Cu")
		(net 1301)
	)
	(segment
		(start 216.972132 95.392)
		(end 216.972132 95.872132)
		(width 0.1)
		(layer "B.Cu")
		(net 1301)
	)
	(segment
		(start 98.498 65.51)
		(end 98.498 67.228)
		(width 0.2)
		(layer "B.Cu")
		(net 1302)
	)
	(segment
		(start 98.498 67.228)
		(end 98.52 67.25)
		(width 0.2)
		(layer "B.Cu")
		(net 1302)
	)
	(segment
		(start 143.912 133.44)
		(end 143.912 133.972)
		(width 0.2)
		(layer "F.Cu")
		(net 1303)
	)
	(segment
		(start 144.04 135.04)
		(end 144.04 134.1)
		(width 0.2)
		(layer "F.Cu")
		(net 1303)
	)
	(segment
		(start 143.912 133.972)
		(end 144.04 134.1)
		(width 0.2)
		(layer "F.Cu")
		(net 1303)
	)
	(segment
		(start 92.65 64.15)
		(end 92.1 64.15)
		(width 0.1)
		(layer "F.Cu")
		(net 1304)
	)
	(segment
		(start 93.5 65.5)
		(end 93 65)
		(width 0.1)
		(layer "F.Cu")
		(net 1304)
	)
	(segment
		(start 93 65)
		(end 93 64.5)
		(width 0.1)
		(layer "F.Cu")
		(net 1304)
	)
	(segment
		(start 93.52 65.5)
		(end 93.5 65.5)
		(width 0.1)
		(layer "F.Cu")
		(net 1304)
	)
	(segment
		(start 93 64.5)
		(end 92.65 64.15)
		(width 0.1)
		(layer "F.Cu")
		(net 1304)
	)
	(segment
		(start 132.845 54.875)
		(end 132.845 55.785)
		(width 0.1)
		(layer "F.Cu")
		(net 1305)
	)
	(segment
		(start 132.845 54.875)
		(end 132.26 54.29)
		(width 0.1)
		(layer "F.Cu")
		(net 1305)
	)
	(segment
		(start 132.26 54.29)
		(end 124.46 54.29)
		(width 0.1)
		(layer "F.Cu")
		(net 1305)
	)
	(segment
		(start 124.46 54.29)
		(end 123.98 54.77)
		(width 0.1)
		(layer "F.Cu")
		(net 1305)
	)
	(segment
		(start 123.98 54.77)
		(end 123.98 55.49)
		(width 0.1)
		(layer "F.Cu")
		(net 1305)
	)
	(segment
		(start 129.419999 62.575)
		(end 128.709212 62.575)
		(width 0.2)
		(layer "F.Cu")
		(net 1305)
	)
	(segment
		(start 132.845 55.785)
		(end 132.85 55.79)
		(width 0.1)
		(layer "F.Cu")
		(net 1305)
	)
	(segment
		(start 132.85 55.79)
		(end 133.8 55.79)
		(width 0.2)
		(layer "F.Cu")
		(net 1305)
	)
	(via
		(at 123.98 55.49)
		(size 0.45)
		(drill 0.1)
		(layers "F.Cu" "B.Cu")
		(net 1305)
	)
	(via
		(at 129.419999 62.575)
		(size 0.45)
		(drill 0.1)
		(layers "F.Cu" "B.Cu")
		(net 1305)
	)
	(segment
		(start 123.98 55.49)
		(end 123.6 55.87)
		(width 0.1)
		(layer "B.Cu")
		(net 1305)
	)
	(segment
		(start 124.28 59.83)
		(end 127.79 59.83)
		(width 0.1)
		(layer "B.Cu")
		(net 1305)
	)
	(segment
		(start 123.6 55.87)
		(end 123.6 59.15)
		(width 0.1)
		(layer "B.Cu")
		(net 1305)
	)
	(segment
		(start 127.79 59.83)
		(end 129.419999 61.459999)
		(width 0.1)
		(layer "B.Cu")
		(net 1305)
	)
	(segment
		(start 123.6 59.15)
		(end 124.28 59.83)
		(width 0.1)
		(layer "B.Cu")
		(net 1305)
	)
	(segment
		(start 129.419999 61.459999)
		(end 129.419999 62.575)
		(width 0.1)
		(layer "B.Cu")
		(net 1305)
	)
	(segment
		(start 131.985349 61.976557)
		(end 131.985349 61.94)
		(width 0.2)
		(layer "F.Cu")
		(net 1306)
	)
	(segment
		(start 128.709212 61.675)
		(end 131.683792 61.675)
		(width 0.2)
		(layer "F.Cu")
		(net 1306)
	)
	(segment
		(start 131.683792 61.675)
		(end 131.985349 61.976557)
		(width 0.2)
		(layer "F.Cu")
		(net 1306)
	)
	(segment
		(start 131.985349 61.94)
		(end 132.945349 60.98)
		(width 0.2)
		(layer "F.Cu")
		(net 1306)
	)
	(segment
		(start 128.709212 62.125)
		(end 131.140349 62.125)
		(width 0.2)
		(layer "F.Cu")
		(net 1307)
	)
	(segment
		(start 131.140349 62.125)
		(end 131.985349 62.97)
		(width 0.2)
		(layer "F.Cu")
		(net 1307)
	)
	(segment
		(start 128.044212 63.49)
		(end 129.579999 63.49)
		(width 0.2)
		(layer "F.Cu")
		(net 1308)
	)
	(segment
		(start 130.069999 63.93)
		(end 131.029999 62.97)
		(width 0.2)
		(layer "F.Cu")
		(net 1308)
	)
	(segment
		(start 130.069999 63.98)
		(end 130.069999 63.93)
		(width 0.2)
		(layer "F.Cu")
		(net 1308)
	)
	(segment
		(start 129.579999 63.49)
		(end 130.069999 63.98)
		(width 0.2)
		(layer "F.Cu")
		(net 1308)
	)
	(segment
		(start 153.35 100.4)
		(end 155.6 100.4)
		(width 0.1)
		(layer "F.Cu")
		(net 1309)
	)
	(segment
		(start 140.581999 107.65)
		(end 142.206999 107.65)
		(width 0.1)
		(layer "F.Cu")
		(net 1309)
	)
	(segment
		(start 143.8 108.2)
		(end 143.8 109.4)
		(width 0.1)
		(layer "F.Cu")
		(net 1309)
	)
	(segment
		(start 143.8 109.4)
		(end 142.4 110.8)
		(width 0.1)
		(layer "F.Cu")
		(net 1309)
	)
	(segment
		(start 142.206999 107.65)
		(end 142.226999 107.67)
		(width 0.1)
		(layer "F.Cu")
		(net 1309)
	)
	(segment
		(start 143.27 107.67)
		(end 143.8 108.2)
		(width 0.1)
		(layer "F.Cu")
		(net 1309)
	)
	(segment
		(start 142.226999 107.67)
		(end 143.27 107.67)
		(width 0.1)
		(layer "F.Cu")
		(net 1309)
	)
	(via
		(at 155.6 100.4)
		(size 0.45)
		(drill 0.1)
		(layers "F.Cu" "B.Cu")
		(net 1309)
	)
	(via
		(at 154.8 109)
		(size 0.45)
		(drill 0.1)
		(layers "F.Cu" "B.Cu")
		(net 1309)
	)
	(via
		(at 142.4 110.8)
		(size 0.45)
		(drill 0.1)
		(layers "F.Cu" "B.Cu")
		(net 1309)
	)
	(segment
		(start 157 106.8)
		(end 157 101.2)
		(width 0.1)
		(layer "B.Cu")
		(net 1309)
	)
	(segment
		(start 156.2 100.4)
		(end 155.6 100.4)
		(width 0.1)
		(layer "B.Cu")
		(net 1309)
	)
	(segment
		(start 154.8 109)
		(end 157 106.8)
		(width 0.1)
		(layer "B.Cu")
		(net 1309)
	)
	(segment
		(start 157 101.2)
		(end 156.2 100.4)
		(width 0.1)
		(layer "B.Cu")
		(net 1309)
	)
	(segment
		(start 149 110.8)
		(end 150.8 109)
		(width 0.1)
		(layer "In7.Cu")
		(net 1309)
	)
	(segment
		(start 142.4 110.8)
		(end 149 110.8)
		(width 0.1)
		(layer "In7.Cu")
		(net 1309)
	)
	(segment
		(start 150.8 109)
		(end 154.8 109)
		(width 0.1)
		(layer "In7.Cu")
		(net 1309)
	)
	(segment
		(start 137.13 106.93)
		(end 136.48 106.93)
		(width 0.1)
		(layer "F.Cu")
		(net 1310)
	)
	(segment
		(start 137.781999 107.15)
		(end 137.35 107.15)
		(width 0.1)
		(layer "F.Cu")
		(net 1310)
	)
	(segment
		(start 137.35 107.15)
		(end 137.13 106.93)
		(width 0.1)
		(layer "F.Cu")
		(net 1310)
	)
	(segment
		(start 138.2 105.8)
		(end 138.2 105.28)
		(width 0.1)
		(layer "F.Cu")
		(net 1311)
	)
	(segment
		(start 138.431999 106.5)
		(end 138.431999 106.031999)
		(width 0.1)
		(layer "F.Cu")
		(net 1311)
	)
	(segment
		(start 138.431999 106.031999)
		(end 138.2 105.8)
		(width 0.1)
		(layer "F.Cu")
		(net 1311)
	)
	(segment
		(start 136.48 111.1)
		(end 137.1 111.1)
		(width 0.1)
		(layer "F.Cu")
		(net 1312)
	)
	(segment
		(start 138.431999 109.768001)
		(end 138.431999 109.3)
		(width 0.1)
		(layer "F.Cu")
		(net 1312)
	)
	(segment
		(start 137.1 111.1)
		(end 138.431999 109.768001)
		(width 0.1)
		(layer "F.Cu")
		(net 1312)
	)
	(segment
		(start 137 110.1)
		(end 136.48 110.1)
		(width 0.1)
		(layer "F.Cu")
		(net 1313)
	)
	(segment
		(start 137.45 108.65)
		(end 137.4 108.7)
		(width 0.1)
		(layer "F.Cu")
		(net 1313)
	)
	(segment
		(start 137.4 108.7)
		(end 137.4 109.7)
		(width 0.1)
		(layer "F.Cu")
		(net 1313)
	)
	(segment
		(start 137.781999 108.65)
		(end 137.45 108.65)
		(width 0.1)
		(layer "F.Cu")
		(net 1313)
	)
	(segment
		(start 137.4 109.7)
		(end 137 110.1)
		(width 0.1)
		(layer "F.Cu")
		(net 1313)
	)
	(segment
		(start 136.9 109.1)
		(end 136.48 109.1)
		(width 0.1)
		(layer "F.Cu")
		(net 1314)
	)
	(segment
		(start 137.1 108.9)
		(end 136.9 109.1)
		(width 0.1)
		(layer "F.Cu")
		(net 1314)
	)
	(segment
		(start 137.1 108.5)
		(end 137.1 108.9)
		(width 0.1)
		(layer "F.Cu")
		(net 1314)
	)
	(segment
		(start 137.45 108.15)
		(end 137.1 108.5)
		(width 0.1)
		(layer "F.Cu")
		(net 1314)
	)
	(segment
		(start 137.733999 108.198)
		(end 137.781999 108.15)
		(width 0.1)
		(layer "F.Cu")
		(net 1314)
	)
	(segment
		(start 137.781999 108.15)
		(end 137.45 108.15)
		(width 0.1)
		(layer "F.Cu")
		(net 1314)
	)
	(segment
		(start 137.35 107.65)
		(end 136.9 108.1)
		(width 0.1)
		(layer "F.Cu")
		(net 1315)
	)
	(segment
		(start 136.9 108.1)
		(end 136.48 108.1)
		(width 0.1)
		(layer "F.Cu")
		(net 1315)
	)
	(segment
		(start 137.781999 107.65)
		(end 137.35 107.65)
		(width 0.1)
		(layer "F.Cu")
		(net 1315)
	)
	(segment
		(start 139.431999 109.3)
		(end 139.431999 110.068001)
		(width 0.1)
		(layer "F.Cu")
		(net 1316)
	)
	(segment
		(start 139.431999 110.068001)
		(end 138.7 110.8)
		(width 0.1)
		(layer "F.Cu")
		(net 1316)
	)
	(segment
		(start 138.7 110.8)
		(end 138.7 111.24)
		(width 0.1)
		(layer "F.Cu")
		(net 1316)
	)
	(segment
		(start 139.931999 110.268001)
		(end 139.7 110.5)
		(width 0.1)
		(layer "F.Cu")
		(net 1317)
	)
	(segment
		(start 139.7 110.5)
		(end 139.7 111.24)
		(width 0.1)
		(layer "F.Cu")
		(net 1317)
	)
	(segment
		(start 139.931999 109.3)
		(end 139.931999 110.268001)
		(width 0.1)
		(layer "F.Cu")
		(net 1317)
	)
	(segment
		(start 140.581999 108.65)
		(end 141.05 108.65)
		(width 0.1)
		(layer "F.Cu")
		(net 1318)
	)
	(segment
		(start 141.05 108.65)
		(end 141.2 108.8)
		(width 0.1)
		(layer "F.Cu")
		(net 1318)
	)
	(segment
		(start 141.2 109.3)
		(end 140.7 109.8)
		(width 0.1)
		(layer "F.Cu")
		(net 1318)
	)
	(segment
		(start 140.7 109.8)
		(end 140.7 111.24)
		(width 0.1)
		(layer "F.Cu")
		(net 1318)
	)
	(segment
		(start 141.2 108.8)
		(end 141.2 109.3)
		(width 0.1)
		(layer "F.Cu")
		(net 1318)
	)
	(segment
		(start 141.7 110.3)
		(end 141.7 111.24)
		(width 0.1)
		(layer "F.Cu")
		(net 1319)
	)
	(segment
		(start 141.5 108.4)
		(end 141.5 110.1)
		(width 0.1)
		(layer "F.Cu")
		(net 1319)
	)
	(segment
		(start 141.5 110.1)
		(end 141.7 110.3)
		(width 0.1)
		(layer "F.Cu")
		(net 1319)
	)
	(segment
		(start 141.25 108.15)
		(end 141.5 108.4)
		(width 0.1)
		(layer "F.Cu")
		(net 1319)
	)
	(segment
		(start 140.581999 108.15)
		(end 141.25 108.15)
		(width 0.1)
		(layer "F.Cu")
		(net 1319)
	)
	(segment
		(start 220.179 110.523)
		(end 220.179 109.991)
		(width 0.1)
		(layer "B.Cu")
		(net 1330)
	)
	(segment
		(start 220.679 110.523)
		(end 220.679 109.529)
		(width 0.1)
		(layer "B.Cu")
		(net 1330)
	)
	(segment
		(start 220.179 109.991)
		(end 220.66 109.51)
		(width 0.1)
		(layer "B.Cu")
		(net 1330)
	)
	(segment
		(start 220.679 109.529)
		(end 220.66 109.51)
		(width 0.1)
		(layer "B.Cu")
		(net 1330)
	)
	(segment
		(start 217.039 110.493)
		(end 217.039 109.961)
		(width 0.1)
		(layer "B.Cu")
		(net 1331)
	)
	(segment
		(start 217.039 109.961)
		(end 217.52 109.48)
		(width 0.1)
		(layer "B.Cu")
		(net 1331)
	)
	(segment
		(start 217.539 109.499)
		(end 217.52 109.48)
		(width 0.1)
		(layer "B.Cu")
		(net 1331)
	)
	(segment
		(start 217.539 110.493)
		(end 217.539 109.499)
		(width 0.1)
		(layer "B.Cu")
		(net 1331)
	)
	(segment
		(start 223.579 119.939)
		(end 223.54 119.9)
		(width 0.1)
		(layer "B.Cu")
		(net 1332)
	)
	(segment
		(start 223.079 120.923)
		(end 223.079 120.361)
		(width 0.1)
		(layer "B.Cu")
		(net 1332)
	)
	(segment
		(start 223.079 120.361)
		(end 223.54 119.9)
		(width 0.1)
		(layer "B.Cu")
		(net 1332)
	)
	(segment
		(start 223.579 120.923)
		(end 223.579 119.939)
		(width 0.1)
		(layer "B.Cu")
		(net 1332)
	)
	(segment
		(start 219.889 120.904698)
		(end 219.889 120.371)
		(width 0.1)
		(layer "B.Cu")
		(net 1333)
	)
	(segment
		(start 220.389 120.904698)
		(end 220.389 119.929)
		(width 0.1)
		(layer "B.Cu")
		(net 1333)
	)
	(segment
		(start 220.389 119.929)
		(end 220.36 119.9)
		(width 0.1)
		(layer "B.Cu")
		(net 1333)
	)
	(segment
		(start 219.889 120.371)
		(end 220.36 119.9)
		(width 0.1)
		(layer "B.Cu")
		(net 1333)
	)
	(segment
		(start 216.725 101.325)
		(end 217.2 100.85)
		(width 0.1)
		(layer "F.Cu")
		(net 1366)
	)
	(segment
		(start 216.445 101.325)
		(end 216.725 101.325)
		(width 0.1)
		(layer "F.Cu")
		(net 1366)
	)
	(via
		(at 204.5 106.8)
		(size 0.45)
		(drill 0.1)
		(layers "F.Cu" "B.Cu")
		(net 1366)
	)
	(via
		(at 217.2 100.85)
		(size 0.45)
		(drill 0.1)
		(layers "F.Cu" "B.Cu")
		(net 1366)
	)
	(segment
		(start 203.88 106.800001)
		(end 204.5 106.8)
		(width 0.1)
		(layer "B.Cu")
		(net 1366)
	)
	(segment
		(start 217.65 100.85)
		(end 217.2 100.85)
		(width 0.1)
		(layer "In5.Cu")
		(net 1366)
	)
	(segment
		(start 204.1 104.2)
		(end 207.3 104.2)
		(width 0.1)
		(layer "In5.Cu")
		(net 1366)
	)
	(segment
		(start 207.8 103.7)
		(end 210.5 103.7)
		(width 0.1)
		(layer "In5.Cu")
		(net 1366)
	)
	(segment
		(start 205.2 106.4)
		(end 205.2 105.7)
		(width 0.1)
		(layer "In5.Cu")
		(net 1366)
	)
	(segment
		(start 217.8 101.6)
		(end 217.8 101)
		(width 0.1)
		(layer "In5.Cu")
		(net 1366)
	)
	(segment
		(start 205.2 105.7)
		(end 204.8 105.3)
		(width 0.1)
		(layer "In5.Cu")
		(net 1366)
	)
	(segment
		(start 210.8 104)
		(end 215.4 104)
		(width 0.1)
		(layer "In5.Cu")
		(net 1366)
	)
	(segment
		(start 215.4 104)
		(end 217.8 101.6)
		(width 0.1)
		(layer "In5.Cu")
		(net 1366)
	)
	(segment
		(start 203.9 105.3)
		(end 203.7 105.1)
		(width 0.1)
		(layer "In5.Cu")
		(net 1366)
	)
	(segment
		(start 203.7 105.1)
		(end 203.7 104.6)
		(width 0.1)
		(layer "In5.Cu")
		(net 1366)
	)
	(segment
		(start 210.5 103.7)
		(end 210.8 104)
		(width 0.1)
		(layer "In5.Cu")
		(net 1366)
	)
	(segment
		(start 217.8 101)
		(end 217.65 100.85)
		(width 0.1)
		(layer "In5.Cu")
		(net 1366)
	)
	(segment
		(start 204.8 105.3)
		(end 203.9 105.3)
		(width 0.1)
		(layer "In5.Cu")
		(net 1366)
	)
	(segment
		(start 207.3 104.2)
		(end 207.8 103.7)
		(width 0.1)
		(layer "In5.Cu")
		(net 1366)
	)
	(segment
		(start 203.7 104.6)
		(end 204.1 104.2)
		(width 0.1)
		(layer "In5.Cu")
		(net 1366)
	)
	(segment
		(start 204.8 106.8)
		(end 205.2 106.4)
		(width 0.1)
		(layer "In5.Cu")
		(net 1366)
	)
	(segment
		(start 204.5 106.8)
		(end 204.8 106.8)
		(width 0.1)
		(layer "In5.Cu")
		(net 1366)
	)
	(segment
		(start 205.926 146.7)
		(end 207.326 146.7)
		(width 0.1)
		(layer "F.Cu")
		(net 1367)
	)
	(segment
		(start 207.326 146.7)
		(end 207.426 146.8)
		(width 0.1)
		(layer "F.Cu")
		(net 1367)
	)
	(via
		(at 207.426 146.8)
		(size 0.45)
		(drill 0.1)
		(layers "F.Cu" "B.Cu")
		(net 1367)
	)
	(segment
		(start 207.426 146.8)
		(end 207.626 147)
		(width 0.1)
		(layer "B.Cu")
		(net 1367)
	)
	(segment
		(start 207.626 147)
		(end 208.246 147)
		(width 0.1)
		(layer "B.Cu")
		(net 1367)
	)
	(segment
		(start 205.926 143.5)
		(end 207.326 143.5)
		(width 0.1)
		(layer "F.Cu")
		(net 1368)
	)
	(segment
		(start 207.326 143.5)
		(end 207.426 143.4)
		(width 0.1)
		(layer "F.Cu")
		(net 1368)
	)
	(via
		(at 207.426 143.4)
		(size 0.45)
		(drill 0.1)
		(layers "F.Cu" "B.Cu")
		(net 1368)
	)
	(segment
		(start 207.846 143.4)
		(end 207.426 143.4)
		(width 0.1)
		(layer "B.Cu")
		(net 1368)
	)
	(segment
		(start 208.246 143)
		(end 207.846 143.4)
		(width 0.1)
		(layer "B.Cu")
		(net 1368)
	)
	(segment
		(start 207.326 141.9)
		(end 207.426 141.8)
		(width 0.1)
		(layer "F.Cu")
		(net 1369)
	)
	(segment
		(start 205.926 141.9)
		(end 207.326 141.9)
		(width 0.1)
		(layer "F.Cu")
		(net 1369)
	)
	(via
		(at 207.426 141.8)
		(size 0.45)
		(drill 0.1)
		(layers "F.Cu" "B.Cu")
		(net 1369)
	)
	(segment
		(start 208.236532 141)
		(end 207.436532 141.8)
		(width 0.1)
		(layer "B.Cu")
		(net 1369)
	)
	(segment
		(start 207.436532 141.8)
		(end 207.426 141.8)
		(width 0.1)
		(layer "B.Cu")
		(net 1369)
	)
	(segment
		(start 205.926 142.7)
		(end 206.026 142.6)
		(width 0.1)
		(layer "F.Cu")
		(net 1370)
	)
	(segment
		(start 206.026 142.6)
		(end 207.426 142.6)
		(width 0.1)
		(layer "F.Cu")
		(net 1370)
	)
	(via
		(at 207.426 142.6)
		(size 0.45)
		(drill 0.1)
		(layers "F.Cu" "B.Cu")
		(net 1370)
	)
	(segment
		(start 207.636532 142.6)
		(end 207.426 142.6)
		(width 0.1)
		(layer "B.Cu")
		(net 1370)
	)
	(segment
		(start 208.236532 142)
		(end 207.636532 142.6)
		(width 0.1)
		(layer "B.Cu")
		(net 1370)
	)
	(segment
		(start 206.186532 142.6)
		(end 205.966532 142.82)
		(width 0.1)
		(layer "B.Cu")
		(net 1370)
	)
	(segment
		(start 207.426 142.6)
		(end 206.186532 142.6)
		(width 0.1)
		(layer "B.Cu")
		(net 1370)
	)
	(segment
		(start 207.326 147.5)
		(end 207.426 147.6)
		(width 0.1)
		(layer "F.Cu")
		(net 1371)
	)
	(segment
		(start 205.926 147.5)
		(end 207.326 147.5)
		(width 0.1)
		(layer "F.Cu")
		(net 1371)
	)
	(via
		(at 207.426 147.6)
		(size 0.45)
		(drill 0.1)
		(layers "F.Cu" "B.Cu")
		(net 1371)
	)
	(segment
		(start 207.406 147.62)
		(end 207.426 147.6)
		(width 0.1)
		(layer "B.Cu")
		(net 1371)
	)
	(segment
		(start 206.066532 147.62)
		(end 207.406 147.62)
		(width 0.1)
		(layer "B.Cu")
		(net 1371)
	)
	(segment
		(start 207.426 147.6)
		(end 207.826 148)
		(width 0.1)
		(layer "B.Cu")
		(net 1371)
	)
	(segment
		(start 207.826 148)
		(end 208.246 148)
		(width 0.1)
		(layer "B.Cu")
		(net 1371)
	)
	(via
		(at 215.25 55.9)
		(size 0.45)
		(drill 0.1)
		(layers "F.Cu" "B.Cu")
		(net 1372)
	)
	(via
		(at 73.299997 66.300003)
		(size 0.45)
		(drill 0.1)
		(layers "F.Cu" "B.Cu")
		(net 1372)
	)
	(segment
		(start 73.297999 66.302001)
		(end 73.299997 66.300003)
		(width 0.1)
		(layer "B.Cu")
		(net 1372)
	)
	(segment
		(start 214.2 55.9)
		(end 213.157 56.943)
		(width 0.1)
		(layer "B.Cu")
		(net 1372)
	)
	(segment
		(start 215.25 55.9)
		(end 214.2 55.9)
		(width 0.1)
		(layer "B.Cu")
		(net 1372)
	)
	(segment
		(start 73.299997 66.300003)
		(end 73.299994 66.3)
		(width 0.1)
		(layer "B.Cu")
		(net 1372)
	)
	(segment
		(start 213.157 56.943)
		(end 213.157 58.39)
		(width 0.1)
		(layer "B.Cu")
		(net 1372)
	)
	(segment
		(start 73.299994 66.3)
		(end 71.58 66.3)
		(width 0.1)
		(layer "B.Cu")
		(net 1372)
	)
	(segment
		(start 73.75 66.2)
		(end 73.649997 66.300003)
		(width 0.1)
		(layer "In5.Cu")
		(net 1372)
	)
	(segment
		(start 159.734314 63.3)
		(end 155.234314 67.8)
		(width 0.1)
		(layer "In5.Cu")
		(net 1372)
	)
	(segment
		(start 211.6 57.6)
		(end 194.234314 57.6)
		(width 0.1)
		(layer "In5.Cu")
		(net 1372)
	)
	(segment
		(start 75.6 67.4)
		(end 74.4 66.2)
		(width 0.1)
		(layer "In5.Cu")
		(net 1372)
	)
	(segment
		(start 84.26863 67.4)
		(end 75.6 67.4)
		(width 0.1)
		(layer "In5.Cu")
		(net 1372)
	)
	(segment
		(start 181.95 63.3)
		(end 159.734314 63.3)
		(width 0.1)
		(layer "In5.Cu")
		(net 1372)
	)
	(segment
		(start 85.46863 66.2)
		(end 84.26863 67.4)
		(width 0.1)
		(layer "In5.Cu")
		(net 1372)
	)
	(segment
		(start 105.182843 66.817157)
		(end 104.565686 66.2)
		(width 0.1)
		(layer "In5.Cu")
		(net 1372)
	)
	(segment
		(start 74.4 66.2)
		(end 73.75 66.2)
		(width 0.1)
		(layer "In5.Cu")
		(net 1372)
	)
	(segment
		(start 189.584314 62.25)
		(end 183 62.25)
		(width 0.1)
		(layer "In5.Cu")
		(net 1372)
	)
	(segment
		(start 111.842157 66.175)
		(end 111.2 66.817157)
		(width 0.1)
		(layer "In5.Cu")
		(net 1372)
	)
	(segment
		(start 213.3 55.9)
		(end 211.6 57.6)
		(width 0.1)
		(layer "In5.Cu")
		(net 1372)
	)
	(segment
		(start 145.584316 64.1)
		(end 126.45 64.1)
		(width 0.1)
		(layer "In5.Cu")
		(net 1372)
	)
	(segment
		(start 73.649997 66.300003)
		(end 73.299997 66.300003)
		(width 0.1)
		(layer "In5.Cu")
		(net 1372)
	)
	(segment
		(start 149.284316 67.8)
		(end 145.584316 64.1)
		(width 0.1)
		(layer "In5.Cu")
		(net 1372)
	)
	(segment
		(start 111.2 66.817157)
		(end 105.182843 66.817157)
		(width 0.1)
		(layer "In5.Cu")
		(net 1372)
	)
	(segment
		(start 183 62.25)
		(end 181.95 63.3)
		(width 0.1)
		(layer "In5.Cu")
		(net 1372)
	)
	(segment
		(start 194.234314 57.6)
		(end 189.584314 62.25)
		(width 0.1)
		(layer "In5.Cu")
		(net 1372)
	)
	(segment
		(start 215.25 55.9)
		(end 213.3 55.9)
		(width 0.1)
		(layer "In5.Cu")
		(net 1372)
	)
	(segment
		(start 126.45 64.1)
		(end 124.375 66.175)
		(width 0.1)
		(layer "In5.Cu")
		(net 1372)
	)
	(segment
		(start 124.375 66.175)
		(end 111.842157 66.175)
		(width 0.1)
		(layer "In5.Cu")
		(net 1372)
	)
	(segment
		(start 155.234314 67.8)
		(end 149.284316 67.8)
		(width 0.1)
		(layer "In5.Cu")
		(net 1372)
	)
	(segment
		(start 104.565686 66.2)
		(end 85.46863 66.2)
		(width 0.1)
		(layer "In5.Cu")
		(net 1372)
	)
	(via
		(at 72.599997 66.700003)
		(size 0.45)
		(drill 0.1)
		(layers "F.Cu" "B.Cu")
		(net 1373)
	)
	(via
		(at 216 55.5)
		(size 0.45)
		(drill 0.1)
		(layers "F.Cu" "B.Cu")
		(net 1373)
	)
	(segment
		(start 212.657 56.543)
		(end 212.657 58.39)
		(width 0.1)
		(layer "B.Cu")
		(net 1373)
	)
	(segment
		(start 71.58 67.3)
		(end 72 67.3)
		(width 0.1)
		(layer "B.Cu")
		(net 1373)
	)
	(segment
		(start 72 67.3)
		(end 72.599997 66.700003)
		(width 0.1)
		(layer "B.Cu")
		(net 1373)
	)
	(segment
		(start 216 55.5)
		(end 213.7 55.5)
		(width 0.1)
		(layer "B.Cu")
		(net 1373)
	)
	(segment
		(start 213.7 55.5)
		(end 212.657 56.543)
		(width 0.1)
		(layer "B.Cu")
		(net 1373)
	)
	(segment
		(start 72.549997 66.700003)
		(end 72.049997 66.200003)
		(width 0.1)
		(layer "In5.Cu")
		(net 1373)
	)
	(segment
		(start 108.93 65.3)
		(end 109.53 65.9)
		(width 0.1)
		(layer "In5.Cu")
		(net 1373)
	)
	(segment
		(start 103.719999 65.800001)
		(end 104.22 65.3)
		(width 0.1)
		(layer "In5.Cu")
		(net 1373)
	)
	(segment
		(start 75.765684 67.000002)
		(end 84.102944 67.000002)
		(width 0.1)
		(layer "In5.Cu")
		(net 1373)
	)
	(segment
		(start 73.649997 65.800003)
		(end 74.565685 65.800003)
		(width 0.1)
		(layer "In5.Cu")
		(net 1373)
	)
	(segment
		(start 213.1 55.5)
		(end 216 55.5)
		(width 0.1)
		(layer "In5.Cu")
		(net 1373)
	)
	(segment
		(start 85.302945 65.800001)
		(end 103.719999 65.800001)
		(width 0.1)
		(layer "In5.Cu")
		(net 1373)
	)
	(segment
		(start 154.91863 67.55)
		(end 159.468629 63.000001)
		(width 0.1)
		(layer "In5.Cu")
		(net 1373)
	)
	(segment
		(start 84.102944 67.000002)
		(end 85.302945 65.800001)
		(width 0.1)
		(layer "In5.Cu")
		(net 1373)
	)
	(segment
		(start 182.640686 61.959315)
		(end 189.490685 61.959315)
		(width 0.1)
		(layer "In5.Cu")
		(net 1373)
	)
	(segment
		(start 124.116422 65.9)
		(end 126.216422 63.8)
		(width 0.1)
		(layer "In5.Cu")
		(net 1373)
	)
	(segment
		(start 149.45 67.55)
		(end 154.91863 67.55)
		(width 0.1)
		(layer "In5.Cu")
		(net 1373)
	)
	(segment
		(start 145.7 63.8)
		(end 149.45 67.55)
		(width 0.1)
		(layer "In5.Cu")
		(net 1373)
	)
	(segment
		(start 104.22 65.3)
		(end 108.93 65.3)
		(width 0.1)
		(layer "In5.Cu")
		(net 1373)
	)
	(segment
		(start 211.3 57.3)
		(end 213.1 55.5)
		(width 0.1)
		(layer "In5.Cu")
		(net 1373)
	)
	(segment
		(start 74.565685 65.800003)
		(end 75.765684 67.000002)
		(width 0.1)
		(layer "In5.Cu")
		(net 1373)
	)
	(segment
		(start 181.6 63.000001)
		(end 182.640686 61.959315)
		(width 0.1)
		(layer "In5.Cu")
		(net 1373)
	)
	(segment
		(start 72.049997 65.450003)
		(end 72.299997 65.200003)
		(width 0.1)
		(layer "In5.Cu")
		(net 1373)
	)
	(segment
		(start 189.490685 61.959315)
		(end 194.15 57.3)
		(width 0.1)
		(layer "In5.Cu")
		(net 1373)
	)
	(segment
		(start 72.299997 65.200003)
		(end 73.049997 65.200003)
		(width 0.1)
		(layer "In5.Cu")
		(net 1373)
	)
	(segment
		(start 109.53 65.9)
		(end 124.116422 65.9)
		(width 0.1)
		(layer "In5.Cu")
		(net 1373)
	)
	(segment
		(start 72.599997 66.700003)
		(end 72.549997 66.700003)
		(width 0.1)
		(layer "In5.Cu")
		(net 1373)
	)
	(segment
		(start 72.049997 66.200003)
		(end 72.049997 65.450003)
		(width 0.1)
		(layer "In5.Cu")
		(net 1373)
	)
	(segment
		(start 73.049997 65.200003)
		(end 73.649997 65.800003)
		(width 0.1)
		(layer "In5.Cu")
		(net 1373)
	)
	(segment
		(start 126.216422 63.8)
		(end 145.7 63.8)
		(width 0.1)
		(layer "In5.Cu")
		(net 1373)
	)
	(segment
		(start 159.468629 63.000001)
		(end 181.6 63.000001)
		(width 0.1)
		(layer "In5.Cu")
		(net 1373)
	)
	(segment
		(start 194.15 57.3)
		(end 211.3 57.3)
		(width 0.1)
		(layer "In5.Cu")
		(net 1373)
	)
	(via
		(at 63.2 71.9)
		(size 0.45)
		(drill 0.1)
		(layers "F.Cu" "B.Cu")
		(net 1374)
	)
	(via
		(at 62.7 97.4)
		(size 0.45)
		(drill 0.1)
		(layers "F.Cu" "B.Cu")
		(net 1374)
	)
	(segment
		(start 63.139 96.961)
		(end 64.59 96.961)
		(width 0.1)
		(layer "B.Cu")
		(net 1374)
	)
	(segment
		(start 62.7 97.4)
		(end 63.139 96.961)
		(width 0.1)
		(layer "B.Cu")
		(net 1374)
	)
	(segment
		(start 63 71.8)
		(end 63.1 71.9)
		(width 0.1)
		(layer "B.Cu")
		(net 1374)
	)
	(segment
		(start 62.1 70.9)
		(end 63 71.8)
		(width 0.1)
		(layer "B.Cu")
		(net 1374)
	)
	(segment
		(start 63.1 71.9)
		(end 63.2 71.9)
		(width 0.1)
		(layer "B.Cu")
		(net 1374)
	)
	(segment
		(start 62.1 70.88)
		(end 62.1 70.9)
		(width 0.1)
		(layer "B.Cu")
		(net 1374)
	)
	(segment
		(start 63.2 73.482842)
		(end 61.234315 75.448527)
		(width 0.1)
		(layer "In5.Cu")
		(net 1374)
	)
	(segment
		(start 63.2 71.9)
		(end 63.2 73.482842)
		(width 0.1)
		(layer "In5.Cu")
		(net 1374)
	)
	(segment
		(start 61.234315 95.9)
		(end 62.7 97.365685)
		(width 0.1)
		(layer "In5.Cu")
		(net 1374)
	)
	(segment
		(start 61.234315 75.448527)
		(end 61.234315 95.9)
		(width 0.1)
		(layer "In5.Cu")
		(net 1374)
	)
	(segment
		(start 62.7 97.365685)
		(end 62.7 97.4)
		(width 0.1)
		(layer "In5.Cu")
		(net 1374)
	)
	(via
		(at 62.7 95.4)
		(size 0.45)
		(drill 0.1)
		(layers "F.Cu" "B.Cu")
		(net 1375)
	)
	(via
		(at 65.1 71.9)
		(size 0.45)
		(drill 0.1)
		(layers "F.Cu" "B.Cu")
		(net 1375)
	)
	(segment
		(start 62.761 95.461)
		(end 62.7 95.4)
		(width 0.1)
		(layer "B.Cu")
		(net 1375)
	)
	(segment
		(start 64.59 95.461)
		(end 62.761 95.461)
		(width 0.1)
		(layer "B.Cu")
		(net 1375)
	)
	(segment
		(start 65.1 70.88)
		(end 65.1 71.9)
		(width 0.1)
		(layer "B.Cu")
		(net 1375)
	)
	(segment
		(start 65.1 72.782842)
		(end 62.082842 75.8)
		(width 0.1)
		(layer "In5.Cu")
		(net 1375)
	)
	(segment
		(start 62.082842 75.8)
		(end 62.082842 94.782842)
		(width 0.1)
		(layer "In5.Cu")
		(net 1375)
	)
	(segment
		(start 62.082842 94.782842)
		(end 62.7 95.4)
		(width 0.1)
		(layer "In5.Cu")
		(net 1375)
	)
	(segment
		(start 65.1 71.9)
		(end 65.1 72.782842)
		(width 0.1)
		(layer "In5.Cu")
		(net 1375)
	)
	(via
		(at 64.5 71.9)
		(size 0.45)
		(drill 0.1)
		(layers "F.Cu" "B.Cu")
		(net 1376)
	)
	(via
		(at 62.7 96)
		(size 0.45)
		(drill 0.1)
		(layers "F.Cu" "B.Cu")
		(net 1376)
	)
	(segment
		(start 64.1 70.88)
		(end 64.1 71.3)
		(width 0.1)
		(layer "B.Cu")
		(net 1376)
	)
	(segment
		(start 64.5 71.7)
		(end 64.5 71.9)
		(width 0.1)
		(layer "B.Cu")
		(net 1376)
	)
	(segment
		(start 64.1 71.3)
		(end 64.5 71.7)
		(width 0.1)
		(layer "B.Cu")
		(net 1376)
	)
	(segment
		(start 62.739 95.961)
		(end 62.7 96)
		(width 0.1)
		(layer "B.Cu")
		(net 1376)
	)
	(segment
		(start 64.59 95.961)
		(end 62.739 95.961)
		(width 0.1)
		(layer "B.Cu")
		(net 1376)
	)
	(segment
		(start 61.8 95.1)
		(end 62.7 96)
		(width 0.1)
		(layer "In5.Cu")
		(net 1376)
	)
	(segment
		(start 61.8 75.682842)
		(end 61.8 95.1)
		(width 0.1)
		(layer "In5.Cu")
		(net 1376)
	)
	(segment
		(start 64.5 72.982842)
		(end 61.8 75.682842)
		(width 0.1)
		(layer "In5.Cu")
		(net 1376)
	)
	(segment
		(start 64.5 71.9)
		(end 64.5 72.982842)
		(width 0.1)
		(layer "In5.Cu")
		(net 1376)
	)
	(via
		(at 63.949997 71.9)
		(size 0.45)
		(drill 0.1)
		(layers "F.Cu" "B.Cu")
		(net 1377)
	)
	(via
		(at 62.7 96.7)
		(size 0.45)
		(drill 0.1)
		(layers "F.Cu" "B.Cu")
		(net 1377)
	)
	(segment
		(start 63.949997 71.9)
		(end 63.949997 71.729997)
		(width 0.1)
		(layer "B.Cu")
		(net 1377)
	)
	(segment
		(start 64.59 96.461)
		(end 62.939 96.461)
		(width 0.1)
		(layer "B.Cu")
		(net 1377)
	)
	(segment
		(start 63.949997 71.729997)
		(end 63.1 70.88)
		(width 0.1)
		(layer "B.Cu")
		(net 1377)
	)
	(segment
		(start 62.939 96.461)
		(end 62.7 96.7)
		(width 0.1)
		(layer "B.Cu")
		(net 1377)
	)
	(segment
		(start 61.517158 75.565684)
		(end 61.517158 95.5)
		(width 0.1)
		(layer "In5.Cu")
		(net 1377)
	)
	(segment
		(start 63.949997 73.132845)
		(end 61.517158 75.565684)
		(width 0.1)
		(layer "In5.Cu")
		(net 1377)
	)
	(segment
		(start 62.7 96.682842)
		(end 62.7 96.7)
		(width 0.1)
		(layer "In5.Cu")
		(net 1377)
	)
	(segment
		(start 61.517158 95.5)
		(end 62.7 96.682842)
		(width 0.1)
		(layer "In5.Cu")
		(net 1377)
	)
	(segment
		(start 63.949997 71.9)
		(end 63.949997 73.132845)
		(width 0.1)
		(layer "In5.Cu")
		(net 1377)
	)
	(segment
		(start 142.9 112.2)
		(end 141.7 112.2)
		(width 0.1)
		(layer "F.Cu")
		(net 1378)
	)
	(segment
		(start 96.248 63.5)
		(end 96.248 63.052)
		(width 0.1)
		(layer "F.Cu")
		(net 1379)
	)
	(segment
		(start 97.4 62.5)
		(end 97.58 62.32)
		(width 0.1)
		(layer "F.Cu")
		(net 1379)
	)
	(segment
		(start 96.248 63.052)
		(end 96.8 62.5)
		(width 0.1)
		(layer "F.Cu")
		(net 1379)
	)
	(segment
		(start 96.8 62.5)
		(end 97.4 62.5)
		(width 0.1)
		(layer "F.Cu")
		(net 1379)
	)
	(segment
		(start 97.58 62.32)
		(end 97.58 61.9)
		(width 0.1)
		(layer "F.Cu")
		(net 1379)
	)
	(segment
		(start 97.6 57.4)
		(end 97.7 57.5)
		(width 0.1)
		(layer "F.Cu")
		(net 1380)
	)
	(segment
		(start 97.7 57.5)
		(end 97.7 57.925)
		(width 0.1)
		(layer "F.Cu")
		(net 1380)
	)
	(segment
		(start 95.97 57.19)
		(end 96.18 57.4)
		(width 0.1)
		(layer "F.Cu")
		(net 1380)
	)
	(segment
		(start 95.97 55.87)
		(end 95.97 56.87)
		(width 0.1)
		(layer "F.Cu")
		(net 1380)
	)
	(segment
		(start 96.18 57.4)
		(end 97.6 57.4)
		(width 0.1)
		(layer "F.Cu")
		(net 1380)
	)
	(segment
		(start 95.97 56.87)
		(end 95.97 57.19)
		(width 0.1)
		(layer "F.Cu")
		(net 1380)
	)
	(segment
		(start 95.925 57.925)
		(end 95.9 57.9)
		(width 0.1)
		(layer "F.Cu")
		(net 1381)
	)
	(segment
		(start 97.2 57.925)
		(end 95.925 57.925)
		(width 0.1)
		(layer "F.Cu")
		(net 1381)
	)
	(segment
		(start 85.25 58.55)
		(end 85.9 59.2)
		(width 0.1)
		(layer "F.Cu")
		(net 1382)
	)
	(segment
		(start 85.9 59.2)
		(end 85.9 64.1)
		(width 0.1)
		(layer "F.Cu")
		(net 1382)
	)
	(segment
		(start 87.52 58.5)
		(end 86.6 58.5)
		(width 0.1)
		(layer "F.Cu")
		(net 1382)
	)
	(segment
		(start 86.6 58.5)
		(end 85.9 59.2)
		(width 0.1)
		(layer "F.Cu")
		(net 1382)
	)
	(segment
		(start 86.3 64.5)
		(end 87.47 64.5)
		(width 0.1)
		(layer "F.Cu")
		(net 1382)
	)
	(segment
		(start 85.9 64.1)
		(end 86.3 64.5)
		(width 0.1)
		(layer "F.Cu")
		(net 1382)
	)
	(segment
		(start 87.52 57.5)
		(end 87.52 58.5)
		(width 0.1)
		(layer "F.Cu")
		(net 1382)
	)
	(segment
		(start 85.3 58.5)
		(end 85.25 58.55)
		(width 0.1)
		(layer "F.Cu")
		(net 1382)
	)
	(via
		(at 85.25 58.55)
		(size 0.45)
		(drill 0.1)
		(layers "F.Cu" "B.Cu")
		(net 1382)
	)
	(segment
		(start 208.1 62.2)
		(end 208.3 62)
		(width 0.1)
		(layer "F.Cu")
		(net 1383)
	)
	(segment
		(start 211.715 63.415)
		(end 211.35 63.415)
		(width 0.1)
		(layer "F.Cu")
		(net 1383)
	)
	(segment
		(start 208.93 62.92)
		(end 209.3 62.55)
		(width 0.1)
		(layer "F.Cu")
		(net 1383)
	)
	(segment
		(start 213.124 65.624)
		(end 213.25 65.75)
		(width 0.1)
		(layer "F.Cu")
		(net 1383)
	)
	(segment
		(start 210.96 65.825)
		(end 212.075 65.825)
		(width 0.1)
		(layer "F.Cu")
		(net 1383)
	)
	(segment
		(start 212 64)
		(end 212 63.7)
		(width 0.1)
		(layer "F.Cu")
		(net 1383)
	)
	(segment
		(start 208.92 62.92)
		(end 208.93 62.92)
		(width 0.1)
		(layer "F.Cu")
		(net 1383)
	)
	(segment
		(start 208.1 63.74)
		(end 208.92 62.92)
		(width 0.1)
		(layer "F.Cu")
		(net 1383)
	)
	(segment
		(start 208.306 63.946)
		(end 208.1 63.74)
		(width 0.1)
		(layer "F.Cu")
		(net 1383)
	)
	(segment
		(start 208.1 63.74)
		(end 208.1 62.2)
		(width 0.1)
		(layer "F.Cu")
		(net 1383)
	)
	(segment
		(start 212.16 64.16)
		(end 212 64)
		(width 0.1)
		(layer "F.Cu")
		(net 1383)
	)
	(segment
		(start 211.35 62.75)
		(end 211.35 63.415)
		(width 0.1)
		(layer "F.Cu")
		(net 1383)
	)
	(segment
		(start 212 63.7)
		(end 211.715 63.415)
		(width 0.1)
		(layer "F.Cu")
		(net 1383)
	)
	(segment
		(start 210.4 66.385)
		(end 210.96 65.825)
		(width 0.1)
		(layer "F.Cu")
		(net 1383)
	)
	(segment
		(start 212.075 65.825)
		(end 212.276 65.624)
		(width 0.1)
		(layer "F.Cu")
		(net 1383)
	)
	(segment
		(start 209.3 62.55)
		(end 211.15 62.55)
		(width 0.1)
		(layer "F.Cu")
		(net 1383)
	)
	(segment
		(start 212.8 64.16)
		(end 212.16 64.16)
		(width 0.1)
		(layer "F.Cu")
		(net 1383)
	)
	(segment
		(start 212.276 65.624)
		(end 213.124 65.624)
		(width 0.1)
		(layer "F.Cu")
		(net 1383)
	)
	(segment
		(start 211.15 62.55)
		(end 211.35 62.75)
		(width 0.1)
		(layer "F.Cu")
		(net 1383)
	)
	(via
		(at 213.6 67.8)
		(size 0.45)
		(drill 0.1)
		(layers "F.Cu" "B.Cu")
		(free yes)
		(net 1383)
	)
	(via
		(at 214.3 68.4)
		(size 0.45)
		(drill 0.1)
		(layers "F.Cu" "B.Cu")
		(free yes)
		(net 1383)
	)
	(via
		(at 213.6 68.4)
		(size 0.45)
		(drill 0.1)
		(layers "F.Cu" "B.Cu")
		(free yes)
		(net 1383)
	)
	(via
		(at 212.8 66.85)
		(size 0.45)
		(drill 0.1)
		(layers "F.Cu" "B.Cu")
		(free yes)
		(net 1383)
	)
	(via
		(at 213.25 65.75)
		(size 0.45)
		(drill 0.1)
		(layers "F.Cu" "B.Cu")
		(free yes)
		(net 1383)
	)
	(via
		(at 213.2 66.5)
		(size 0.45)
		(drill 0.1)
		(layers "F.Cu" "B.Cu")
		(free yes)
		(net 1383)
	)
	(via
		(at 214.3 67.8)
		(size 0.45)
		(drill 0.1)
		(layers "F.Cu" "B.Cu")
		(free yes)
		(net 1383)
	)
	(segment
		(start 212.2 67.3)
		(end 211.35 66.45)
		(width 0.1)
		(layer "F.Cu")
		(net 1384)
	)
	(segment
		(start 216.1 67.6)
		(end 216.1 69.55)
		(width 0.1)
		(layer "F.Cu")
		(net 1384)
	)
	(segment
		(start 215.862 69.788)
		(end 216.1 69.55)
		(width 0.1)
		(layer "F.Cu")
		(net 1384)
	)
	(segment
		(start 216.1 73.1)
		(end 216.1 69.55)
		(width 0.1)
		(layer "F.Cu")
		(net 1384)
	)
	(segment
		(start 216.1 73.1)
		(end 215.7 73.5)
		(width 0.1)
		(layer "F.Cu")
		(net 1384)
	)
	(segment
		(start 216.1 67.6)
		(end 215.8 67.3)
		(width 0.1)
		(layer "F.Cu")
		(net 1384)
	)
	(segment
		(start 211.35 66.45)
		(end 211.35 66.385)
		(width 0.1)
		(layer "F.Cu")
		(net 1384)
	)
	(segment
		(start 215.8 67.3)
		(end 212.2 67.3)
		(width 0.1)
		(layer "F.Cu")
		(net 1384)
	)
	(segment
		(start 215.307 69.788)
		(end 215.862 69.788)
		(width 0.1)
		(layer "F.Cu")
		(net 1384)
	)
	(segment
		(start 215.7 73.5)
		(end 215.3 73.5)
		(width 0.1)
		(layer "F.Cu")
		(net 1384)
	)
	(segment
		(start 209.123 65.825)
		(end 209.775 65.825)
		(width 0.1)
		(layer "F.Cu")
		(net 1385)
	)
	(segment
		(start 209.45 63.415)
		(end 209.085 63.415)
		(width 0.1)
		(layer "F.Cu")
		(net 1385)
	)
	(segment
		(start 209.775 65.825)
		(end 209.925 65.975)
		(width 0.1)
		(layer "F.Cu")
		(net 1385)
	)
	(segment
		(start 211.822 67.822)
		(end 211.8 67.8)
		(width 0.1)
		(layer "F.Cu")
		(net 1385)
	)
	(segment
		(start 209.085 63.415)
		(end 208.9 63.6)
		(width 0.1)
		(layer "F.Cu")
		(net 1385)
	)
	(segment
		(start 212.65 71.522)
		(end 212.022 71.522)
		(width 0.1)
		(layer "F.Cu")
		(net 1385)
	)
	(segment
		(start 212.65 67.822)
		(end 211.822 67.822)
		(width 0.1)
		(layer "F.Cu")
		(net 1385)
	)
	(segment
		(start 208.9 65.602)
		(end 209.123 65.825)
		(width 0.1)
		(layer "F.Cu")
		(net 1385)
	)
	(segment
		(start 210.05 67.05)
		(end 211.2 67.05)
		(width 0.1)
		(layer "F.Cu")
		(net 1385)
	)
	(segment
		(start 211.8 67.65)
		(end 211.8 67.8)
		(width 0.1)
		(layer "F.Cu")
		(net 1385)
	)
	(segment
		(start 211.2 67.05)
		(end 211.8 67.65)
		(width 0.1)
		(layer "F.Cu")
		(net 1385)
	)
	(segment
		(start 212.022 71.522)
		(end 211.8 71.3)
		(width 0.1)
		(layer "F.Cu")
		(net 1385)
	)
	(segment
		(start 209.925 65.975)
		(end 209.925 66.925)
		(width 0.1)
		(layer "F.Cu")
		(net 1385)
	)
	(segment
		(start 208.9 63.6)
		(end 208.9 65.602)
		(width 0.1)
		(layer "F.Cu")
		(net 1385)
	)
	(segment
		(start 209.925 66.925)
		(end 210.05 67.05)
		(width 0.1)
		(layer "F.Cu")
		(net 1385)
	)
	(segment
		(start 211.8 71.3)
		(end 211.8 67.8)
		(width 0.1)
		(layer "F.Cu")
		(net 1385)
	)
	(segment
		(start 208.9 65.9)
		(end 208.64 65.64)
		(width 0.1)
		(layer "F.Cu")
		(net 1386)
	)
	(segment
		(start 208.985 66.385)
		(end 208.9 66.3)
		(width 0.1)
		(layer "F.Cu")
		(net 1386)
	)
	(segment
		(start 208.9 66.3)
		(end 208.9 65.9)
		(width 0.1)
		(layer "F.Cu")
		(net 1386)
	)
	(segment
		(start 208.64 65.64)
		(end 208.1 65.64)
		(width 0.1)
		(layer "F.Cu")
		(net 1386)
	)
	(segment
		(start 209.45 66.385)
		(end 208.985 66.385)
		(width 0.1)
		(layer "F.Cu")
		(net 1386)
	)
	(segment
		(start 208.1 64.7)
		(end 208.1 65.64)
		(width 0.1)
		(layer "F.Cu")
		(net 1386)
	)
	(segment
		(start 233.020532 82.71)
		(end 234.840532 82.71)
		(width 0.1)
		(layer "F.Cu")
		(net 1387)
	)
	(segment
		(start 233.020532 95.71)
		(end 234.840532 95.71)
		(width 0.1)
		(layer "F.Cu")
		(net 1388)
	)
	(segment
		(start 233.020532 121.71)
		(end 234.840532 121.71)
		(width 0.2)
		(layer "F.Cu")
		(net 1389)
	)
	(segment
		(start 233.020532 134.323)
		(end 234.840532 134.323)
		(width 0.1)
		(layer "F.Cu")
		(net 1390)
	)
	(segment
		(start 233.020532 108.71)
		(end 234.840532 108.71)
		(width 0.2)
		(layer "F.Cu")
		(net 1391)
	)
	(segment
		(start 111.22 63.63)
		(end 110.9 63.95)
		(width 0.1)
		(layer "F.Cu")
		(net 1392)
	)
	(segment
		(start 110.9 63.95)
		(end 110.412001 63.95)
		(width 0.1)
		(layer "F.Cu")
		(net 1392)
	)
	(segment
		(start 111.92 62.27)
		(end 111.22 62.27)
		(width 0.1)
		(layer "F.Cu")
		(net 1392)
	)
	(segment
		(start 112.58 61.898)
		(end 112.292 61.898)
		(width 0.1)
		(layer "F.Cu")
		(net 1392)
	)
	(segment
		(start 111.22 62.27)
		(end 111.22 63.63)
		(width 0.1)
		(layer "F.Cu")
		(net 1392)
	)
	(segment
		(start 112.292 61.898)
		(end 111.92 62.27)
		(width 0.1)
		(layer "F.Cu")
		(net 1392)
	)
	(segment
		(start 237.2 65.6)
		(end 236.240532 65.6)
		(width 0.2)
		(layer "B.Cu")
		(net 1393)
	)
	(segment
		(start 237.6 70.452001)
		(end 237.052001 71)
		(width 0.2)
		(layer "B.Cu")
		(net 1393)
	)
	(segment
		(start 237.6 70.452001)
		(end 237.6 66)
		(width 0.2)
		(layer "B.Cu")
		(net 1393)
	)
	(segment
		(start 237.6 66)
		(end 237.2 65.6)
		(width 0.2)
		(layer "B.Cu")
		(net 1393)
	)
	(segment
		(start 234.72 63.8)
		(end 234.72 65.17)
		(width 0.2)
		(layer "B.Cu")
		(net 1394)
	)
	(segment
		(start 234.72 65.17)
		(end 234.725 65.175)
		(width 0.2)
		(layer "B.Cu")
		(net 1394)
	)
	(segment
		(start 238.895 61.975)
		(end 239 61.87)
		(width 0.15)
		(layer "B.Cu")
		(net 1395)
	)
	(segment
		(start 236.25 61.975)
		(end 238.895 61.975)
		(width 0.15)
		(layer "B.Cu")
		(net 1395)
	)
	(segment
		(start 140.7 57.3)
		(end 141.06 57.66)
		(width 0.1)
		(layer "F.Cu")
		(net 1396)
	)
	(segment
		(start 142.06 59.28)
		(end 142.03 59.28)
		(width 0.1)
		(layer "F.Cu")
		(net 1396)
	)
	(segment
		(start 141.06 57.66)
		(end 141.06 58.31)
		(width 0.1)
		(layer "F.Cu")
		(net 1396)
	)
	(segment
		(start 142.03 59.28)
		(end 141.06 58.31)
		(width 0.1)
		(layer "F.Cu")
		(net 1396)
	)
	(segment
		(start 140.049 57.3)
		(end 140.7 57.3)
		(width 0.1)
		(layer "F.Cu")
		(net 1396)
	)
	(zone
		(net 295)
		(net_name "/Expansion connector/+V_{ADJ}")
		(layer "F.Cu")
		(hatch edge 0.5)
		(priority 66)
		(connect_pads yes
			(clearance 0.1)
		)
		(min_thickness 0.1)
		(filled_areas_thickness no)
		(fill yes
			(thermal_gap 0.5)
			(thermal_bridge_width 0.5)
		)
		(polygon
			(pts
				(xy 71.75 132.9) (xy 79 132.9) (xy 79 130.25) (xy 78.25 130.25) (xy 77.5 129.5) (xy 73.75 129.5)
				(xy 73.75 130.75) (xy 73.5 131) (xy 71.75 131)
			)
		)
	)
	(zone
		(net 3)
		(net_name "VCC_IN")
		(layer "F.Cu")
		(hatch edge 0.5)
		(priority 25)
		(connect_pads yes
			(clearance 0.25)
		)
		(min_thickness 0.2)
		(filled_areas_thickness no)
		(fill yes
			(thermal_gap 0.5)
			(thermal_bridge_width 0.5)
		)
		(polygon
			(pts
				(xy 239.75 53.5) (xy 239.75 70.75) (xy 228.5 70.75) (xy 225.25 74) (xy 216.1 74) (xy 216.1 70.3)
				(xy 216.1 67.6) (xy 215.8 67.3) (xy 213.5 67.3) (xy 213.5 59.178) (xy 219 53.5)
			)
		)
	)
	(zone
		(net 522)
		(net_name "/Power/USBPD1_HV")
		(layer "F.Cu")
		(hatch edge 0.5)
		(priority 11)
		(connect_pads yes
			(clearance 0.1)
		)
		(min_thickness 0.25)
		(filled_areas_thickness no)
		(fill yes
			(thermal_gap 0.5)
			(thermal_bridge_width 0.5)
		)
		(polygon
			(pts
				(xy 203.5 80.5) (xy 204.5 80.5) (xy 204.5 81) (xy 205.5 81) (xy 205.5 86.5) (xy 201.5 86.5) (xy 201.5 83.5)
				(xy 202.5 83.5) (xy 203.5 82.5)
			)
		)
	)
	(zone
		(net 1)
		(net_name "GND")
		(layer "F.Cu")
		(hatch edge 0.5)
		(priority 35)
		(connect_pads yes
			(clearance 0.125)
		)
		(min_thickness 0.2)
		(filled_areas_thickness no)
		(fill yes
			(thermal_gap 0.5)
			(thermal_bridge_width 0.5)
		)
		(polygon
			(pts
				(xy 175.11 69.11) (xy 176.4 70.4) (xy 176.95 70.4) (xy 177.05 70.5) (xy 179.25 70.5) (xy 179.25 69)
				(xy 181 69) (xy 181 71.75) (xy 178 71.75) (xy 178 73.5) (xy 159.2 73.5) (xy 159.2 72.3) (xy 162.64 69.11)
			)
		)
	)
	(zone
		(net 13)
		(net_name "VCC")
		(layer "F.Cu")
		(hatch edge 0.5)
		(priority 42)
		(connect_pads yes
			(clearance 0.125)
		)
		(min_thickness 0.2)
		(filled_areas_thickness no)
		(fill yes
			(thermal_gap 0.5)
			(thermal_bridge_width 0.5)
		)
		(polygon
			(pts
				(xy 180.49 128) (xy 180.49 126.5) (xy 179.5 126.5) (xy 178.25 125.25) (xy 178.25 123.5) (xy 177.75 123)
				(xy 174 123) (xy 172.75 124.25) (xy 170.25 124.25) (xy 169.75 124.75) (xy 169.75 126.75) (xy 176.5 126.75)
				(xy 177.446 127.696) (xy 177.446 127.706) (xy 178.446 127.706) (xy 178.74 128)
			)
		)
	)
	(zone
		(net 12)
		(net_name "SYS_VIN_HV")
		(layer "F.Cu")
		(hatch edge 0.5)
		(priority 12)
		(connect_pads yes
			(clearance 0.1)
		)
		(min_thickness 0.25)
		(filled_areas_thickness no)
		(fill yes
			(thermal_gap 0.5)
			(thermal_bridge_width 0.5)
		)
		(polygon
			(pts
				(xy 89.2 84.4) (xy 89.2 79.4) (xy 85.2 79.4) (xy 84.8 79.8) (xy 84.8 82.2) (xy 87 84.4)
			)
		)
	)
	(zone
		(net 1181)
		(net_name "/DCDC/5V_SW")
		(layer "F.Cu")
		(hatch edge 0.5)
		(priority 40)
		(connect_pads yes
			(clearance 0.125)
		)
		(min_thickness 0.2)
		(filled_areas_thickness no)
		(fill yes
			(thermal_gap 0.5)
			(thermal_bridge_width 0.5)
		)
		(polygon
			(pts
				(xy 179.375 112.5) (xy 182 112.5) (xy 182 121.25) (xy 181.75 121.5) (xy 179.5 121.5) (xy 178.66 120.66)
				(xy 178.66 113.59) (xy 179 113.25) (xy 179 112.875)
			)
		)
	)
	(zone
		(net 1)
		(net_name "GND")
		(layer "F.Cu")
		(hatch edge 0.5)
		(priority 37)
		(connect_pads yes
			(clearance 0.125)
		)
		(min_thickness 0.2)
		(filled_areas_thickness no)
		(fill yes
			(thermal_gap 0.5)
			(thermal_bridge_width 0.5)
		)
		(polygon
			(pts
				(xy 175.2 82.3) (xy 176 81.5) (xy 176 80.25) (xy 175.56 79.81) (xy 163.25 79.81) (xy 163.25 82.3)
			)
		)
	)
	(zone
		(net 1383)
		(net_name "VCC_NO_OVP")
		(layer "F.Cu")
		(hatch edge 0.5)
		(priority 71)
		(connect_pads yes
			(clearance 0.125)
		)
		(min_thickness 0.2)
		(filled_areas_thickness no)
		(fill yes
			(thermal_gap 0.5)
			(thermal_bridge_width 0.5)
		)
		(polygon
			(pts
				(xy 216.1 74) (xy 211.85 74) (xy 211.85 67.3) (xy 211.85 63.7) (xy 213.5 63.7) (xy 213.5 67.3) (xy 215.8 67.3)
				(xy 216.1 67.6)
			)
		)
	)
	(zone
		(net 1)
		(net_name "GND")
		(layer "F.Cu")
		(hatch edge 0.5)
		(priority 19)
		(connect_pads
			(clearance 0.1)
		)
		(min_thickness 0.25)
		(filled_areas_thickness no)
		(fill yes
			(thermal_gap 0.5)
			(thermal_bridge_width 0.5)
			(island_removal_mode 1)
			(island_area_min 10)
		)
		(polygon
			(pts
				(xy 60 126.5) (xy 71.5 126.5) (xy 71.5 154) (xy 60 154)
			)
		)
	)
	(zone
		(net 1096)
		(net_name "Net-(Q9-D)")
		(layer "F.Cu")
		(hatch edge 0.5)
		(priority 50)
		(connect_pads yes
			(clearance 0.125)
		)
		(min_thickness 0.25)
		(filled_areas_thickness no)
		(fill yes
			(thermal_gap 0.5)
			(thermal_bridge_width 0.5)
		)
		(polygon
			(pts
				(xy 116.045499 59.615) (xy 116.045499 64.05) (xy 114.97 64.05) (xy 114.97 62.97) (xy 114.1275 62.1275)
				(xy 113.610499 62.1275) (xy 113.610499 59.7425) (xy 113.737999 59.615)
			)
		)
	)
	(zone
		(net 1184)
		(net_name "/DCDC/20V_SW")
		(layer "F.Cu")
		(hatch edge 0.5)
		(priority 38)
		(connect_pads yes
			(clearance 0.125)
		)
		(min_thickness 0.2)
		(filled_areas_thickness no)
		(fill yes
			(thermal_gap 0.5)
			(thermal_bridge_width 0.5)
		)
		(polygon
			(pts
				(xy 178 71.75) (xy 178 73.25) (xy 179 74.25) (xy 179 81.5) (xy 183.25 81.5) (xy 183.8 80.95) (xy 183.8 73.55)
				(xy 183.25 73) (xy 180.75 73) (xy 180.5 72.75) (xy 180.5 71.75)
			)
		)
	)
	(zone
		(net 176)
		(net_name "/USB Debug, PD/USBC0_VBUS")
		(layer "F.Cu")
		(hatch edge 0.5)
		(priority 6)
		(connect_pads yes
			(clearance 0.1)
		)
		(min_thickness 0.25)
		(filled_areas_thickness no)
		(fill yes
			(thermal_gap 0.5)
			(thermal_bridge_width 0.5)
		)
		(polygon
			(pts
				(xy 203.4 76.4) (xy 206.4 76.4) (xy 206.4 74) (xy 203.4 74)
			)
		)
	)
	(zone
		(net 1183)
		(net_name "/DCDC/16V_SW")
		(layer "F.Cu")
		(hatch edge 0.5)
		(priority 38)
		(connect_pads yes
			(clearance 0.125)
		)
		(min_thickness 0.2)
		(filled_areas_thickness no)
		(fill yes
			(thermal_gap 0.5)
			(thermal_bridge_width 0.5)
		)
		(polygon
			(pts
				(xy 178 91.75) (xy 178 93.25) (xy 179 94.25) (xy 179 101.5) (xy 184 101.5) (xy 184 93.75) (xy 183.25 93)
				(xy 180.75 93) (xy 180.5 92.75) (xy 180.5 91.75)
			)
		)
	)
	(zone
		(net 525)
		(net_name "/Power/USBPD2_HV")
		(layer "F.Cu")
		(hatch edge 0.5)
		(priority 8)
		(connect_pads yes
			(clearance 0.1)
		)
		(min_thickness 0.25)
		(filled_areas_thickness no)
		(fill yes
			(thermal_gap 0.5)
			(thermal_bridge_width 0.5)
		)
		(polygon
			(pts
				(xy 203.4 76.4) (xy 206.4 76.4) (xy 206.4 76.2) (xy 208.6 76.2) (xy 208.6 75.2) (xy 210.2 75.2)
				(xy 210.2 78) (xy 206.8 78) (xy 206.8 77.4) (xy 203.4 77.4)
			)
		)
	)
	(zone
		(net 1105)
		(net_name "/DCDC/20V_OUT")
		(layer "F.Cu")
		(hatch edge 0.5)
		(priority 36)
		(connect_pads yes
			(clearance 0.125)
		)
		(min_thickness 0.2)
		(filled_areas_thickness no)
		(fill yes
			(thermal_gap 0.5)
			(thermal_bridge_width 0.5)
		)
		(polygon
			(pts
				(xy 178.25 73.5) (xy 179 74.25) (xy 179 81.5) (xy 176 81.5) (xy 176 80.25) (xy 175.56 79.81) (xy 163.25 79.81)
				(xy 163.25 75.5) (xy 162.75 75) (xy 161.75 75) (xy 161.75 73.5)
			)
		)
	)
	(zone
		(net 1185)
		(net_name "/DCDC/1V8_SW")
		(layer "F.Cu")
		(hatch edge 0.5)
		(priority 28)
		(connect_pads yes
			(clearance 0.125)
		)
		(min_thickness 0.25)
		(filled_areas_thickness no)
		(fill yes
			(thermal_gap 0.5)
			(thermal_bridge_width 0.5)
		)
		(polygon
			(pts
				(xy 145.34 128.57) (xy 145.34 129.36) (xy 144.93 129.915009) (xy 144.93 133.68) (xy 146.25 133.68)
				(xy 146.25 129.97) (xy 145.84 129.37) (xy 145.84 128.57)
			)
		)
	)
	(zone
		(net 1297)
		(net_name "/DCDC/5V_{AON}_SW")
		(layer "F.Cu")
		(hatch edge 0.5)
		(priority 73)
		(connect_pads yes
			(clearance 0.125)
		)
		(min_thickness 0.25)
		(filled_areas_thickness no)
		(fill yes
			(thermal_gap 0.5)
			(thermal_bridge_width 0.5)
		)
		(polygon
			(pts
				(xy 122.242244 60.43) (xy 124.513011 59.82) (xy 125.291712 59.82) (xy 125.291712 62.375) (xy 124.36 62.375)
				(xy 121.9 63.58) (xy 118.413125 63.58) (xy 118.27 63.436875) (xy 118.27 60.5675) (xy 118.4075 60.43)
			)
		)
	)
	(zone
		(net 1182)
		(net_name "/DCDC/3V3_SW")
		(layer "F.Cu")
		(hatch edge 0.5)
		(priority 40)
		(connect_pads yes
			(clearance 0.125)
		)
		(min_thickness 0.2)
		(filled_areas_thickness no)
		(fill yes
			(thermal_gap 0.5)
			(thermal_bridge_width 0.5)
		)
		(polygon
			(pts
				(xy 179.365 129.443406) (xy 181.74 129.443406) (xy 181.74 136.943406) (xy 181.44 137.243406) (xy 179.04 137.243406)
				(xy 178.65 136.84) (xy 178.65 130.433406) (xy 178.99 130.093406) (xy 178.99 129.818406)
			)
		)
	)
	(zone
		(net 5)
		(net_name "+5V")
		(layer "F.Cu")
		(hatch edge 0.5)
		(priority 100)
		(connect_pads yes
			(clearance 0.125)
		)
		(min_thickness 0.25)
		(filled_areas_thickness no)
		(fill yes
			(thermal_gap 0.5)
			(thermal_bridge_width 0.5)
		)
		(polygon
			(pts
				(xy 189.717653 128.409958) (xy 188.88 129.09) (xy 186.307653 129.094813) (xy 186.307653 127.509958)
				(xy 188.812044 127.509958) (xy 189.722044 127.819958)
			)
		)
	)
	(zone
		(net 13)
		(net_name "VCC")
		(layer "F.Cu")
		(hatch edge 0.5)
		(priority 46)
		(connect_pads yes
			(clearance 0.125)
		)
		(min_thickness 0.2)
		(filled_areas_thickness no)
		(fill yes
			(thermal_gap 0.5)
			(thermal_bridge_width 0.5)
		)
		(polygon
			(pts
				(xy 177.25 142.5) (xy 177.63 142.88) (xy 178.63 142.88) (xy 178.75 143) (xy 180.5 143) (xy 180.5 141.5)
				(xy 179.5 141.5) (xy 178.5 140.5) (xy 178.5 139.5) (xy 170.75 139.5) (xy 169.75 140.5) (xy 169.75 142.5)
			)
		)
	)
	(zone
		(net 213)
		(net_name "+5V_SOM")
		(layer "F.Cu")
		(hatch edge 0.5)
		(priority 22)
		(connect_pads yes
			(clearance 0.125)
		)
		(min_thickness 0.2)
		(filled_areas_thickness no)
		(fill yes
			(thermal_gap 0.5)
			(thermal_bridge_width 0.5)
		)
		(polygon
			(pts
				(xy 114.57 62.85) (xy 114.57 65.34) (xy 116.73 67.5) (xy 121.4 67.5) (xy 123.8 69.9) (xy 123.8 71.5)
				(xy 105.9 71.5) (xy 105.9 69.4) (xy 106.7 68.6) (xy 109.59 68.6) (xy 112.8 65.39) (xy 112.8 62.85)
			)
		)
	)
	(zone
		(net 7)
		(net_name "/CSI/CSIA_5V")
		(layer "F.Cu")
		(hatch edge 0.5)
		(priority 35)
		(connect_pads yes
			(clearance 0.1)
		)
		(min_thickness 0.15)
		(filled_areas_thickness no)
		(fill yes
			(thermal_gap 0.1)
			(thermal_bridge_width 0.15)
		)
		(polygon
			(pts
				(xy 65 92.2) (xy 67.4 92.2) (xy 67.4 91) (xy 66.2 91) (xy 66.2 89.6) (xy 65 89.6)
			)
		)
	)
	(zone
		(net 280)
		(net_name "/DCDC/1V15_OUT")
		(layer "F.Cu")
		(hatch edge 0.5)
		(priority 33)
		(connect_pads yes
			(clearance 0.1)
		)
		(min_thickness 0.25)
		(filled_areas_thickness no)
		(fill yes
			(thermal_gap 0.5)
			(thermal_bridge_width 0.5)
		)
		(polygon
			(pts
				(xy 192.6 123.4) (xy 193.8 123.4) (xy 193.8 128.2) (xy 193.2 128.8) (xy 193.2 133) (xy 191.8 133)
				(xy 191.8 129.2) (xy 192.4 128.6) (xy 192.4 123.6)
			)
		)
	)
	(zone
		(net 12)
		(net_name "SYS_VIN_HV")
		(layer "F.Cu")
		(hatch edge 0.5)
		(priority 32)
		(connect_pads yes
			(clearance 0.1)
		)
		(min_thickness 0.1)
		(filled_areas_thickness no)
		(fill yes
			(thermal_gap 0.5)
			(thermal_bridge_width 0.5)
		)
		(polygon
			(pts
				(xy 161.2 97.4) (xy 161.5 97.1) (xy 162.1 97.1) (xy 162.444468 96.728859) (xy 162.444468 95.2) (xy 162.3 95)
				(xy 161.4 95) (xy 147.75 81.35) (xy 147.75 73) (xy 147.5 72.75) (xy 144.5 72.75) (xy 144.5 85.25)
				(xy 156.65 97.4)
			)
		)
	)
	(zone
		(net 491)
		(net_name "+5V_AON")
		(layer "F.Cu")
		(hatch edge 0.5)
		(priority 48)
		(connect_pads yes
			(clearance 0.125)
		)
		(min_thickness 0.25)
		(filled_areas_thickness no)
		(fill yes
			(thermal_gap 0.5)
			(thermal_bridge_width 0.5)
		)
		(polygon
			(pts
				(xy 113.175 58.9875) (xy 113.175 61.5425) (xy 112.0825 61.5425) (xy 111.75 61.875) (xy 110.939331 61.875)
				(xy 110.298293 62.519998) (xy 108.760001 62.519998) (xy 108.760001 60.579998) (xy 110.501204 60.579998)
				(xy 112.088407 58.9875)
			)
		)
	)
	(zone
		(net 1034)
		(net_name "/DCDC/1V15_SW")
		(layer "F.Cu")
		(hatch edge 0.5)
		(priority 33)
		(connect_pads yes
			(clearance 0.125)
		)
		(min_thickness 0.25)
		(filled_areas_thickness no)
		(fill yes
			(thermal_gap 0.5)
			(thermal_bridge_width 0.5)
		)
		(polygon
			(pts
				(xy 189.817653 127.719958) (xy 189.817653 128.509958) (xy 189.407653 129.064967) (xy 189.407653 132.829958)
				(xy 190.727653 132.829958) (xy 190.727653 129.119958) (xy 190.317653 128.519958) (xy 190.317653 127.719958)
			)
		)
	)
	(zone
		(net 1)
		(net_name "GND")
		(layer "F.Cu")
		(hatch edge 0.5)
		(priority 64)
		(connect_pads
			(clearance 0.1)
		)
		(min_thickness 0.25)
		(filled_areas_thickness no)
		(fill yes
			(thermal_gap 0.5)
			(thermal_bridge_width 0.5)
			(island_removal_mode 1)
			(island_area_min 10)
		)
		(polygon
			(pts
				(xy 189.2 115.4) (xy 197.7 115.4) (xy 197.7 108.05) (xy 189.2 108.05)
			)
		)
	)
	(zone
		(net 1)
		(net_name "GND")
		(layer "F.Cu")
		(hatch edge 0.5)
		(priority 29)
		(connect_pads yes
			(clearance 0.125)
		)
		(min_thickness 0.25)
		(filled_areas_thickness no)
		(fill yes
			(thermal_gap 0.5)
			(thermal_bridge_width 0.5)
		)
		(polygon
			(pts
				(xy 141.81 129.36) (xy 147.45 129.36) (xy 147.644391 128.28) (xy 147.644391 125.84) (xy 146.694391 125.84)
				(xy 145.874391 127.18) (xy 145.864391 127.76) (xy 144.974391 127.75) (xy 144.434391 127.05) (xy 141.814391 127.04)
			)
		)
	)
	(zone
		(net 1)
		(net_name "GND")
		(layer "F.Cu")
		(hatch edge 0.5)
		(priority 35)
		(connect_pads yes
			(clearance 0.125)
		)
		(min_thickness 0.2)
		(filled_areas_thickness no)
		(fill yes
			(thermal_gap 0.5)
			(thermal_bridge_width 0.5)
		)
		(polygon
			(pts
				(xy 175.11 89.11) (xy 176.25 90.25) (xy 177 90.25) (xy 177.25 90.5) (xy 179.25 90.5) (xy 179.25 89)
				(xy 181 89) (xy 181 91.75) (xy 178 91.75) (xy 178 93.5) (xy 160.2 93.5) (xy 160.2 91.25) (xy 162.64 89.11)
			)
		)
	)
	(zone
		(net 1)
		(net_name "GND")
		(layer "F.Cu")
		(hatch edge 0.5)
		(priority 29)
		(connect_pads yes
			(clearance 0.125)
		)
		(min_thickness 0.25)
		(filled_areas_thickness no)
		(fill yes
			(thermal_gap 0.5)
			(thermal_bridge_width 0.5)
		)
		(polygon
			(pts
				(xy 186.286801 128.959958) (xy 192.2 128.959958) (xy 192.2 124.9) (xy 191.2 124.9) (xy 190.352044 126.329958)
				(xy 190.342044 126.909958) (xy 189.452044 126.899958) (xy 188.912044 126.199958) (xy 186.292044 126.189958)
			)
		)
	)
	(zone
		(net 2)
		(net_name "+3V3")
		(layer "F.Cu")
		(hatch edge 0.5)
		(priority 34)
		(connect_pads yes
			(clearance 0.125)
		)
		(min_thickness 0.2)
		(filled_areas_thickness no)
		(fill yes
			(thermal_gap 0.5)
			(thermal_bridge_width 0.5)
		)
		(polygon
			(pts
				(xy 166.2 128.8) (xy 169.1 128.8) (xy 169.1 129.8) (xy 170 129.8) (xy 170.4 130.2) (xy 170.4 132.2)
				(xy 169.8 132.2) (xy 169.8 133.1) (xy 169.494 133.1) (xy 168.7 133.9) (xy 166.6 133.9) (xy 166.2 133.5)
			)
		)
	)
	(zone
		(net 1)
		(net_name "GND")
		(layer "F.Cu")
		(hatch edge 0.5)
		(priority 39)
		(connect_pads yes
			(clearance 0.125)
		)
		(min_thickness 0.2)
		(filled_areas_thickness no)
		(fill yes
			(thermal_gap 0.5)
			(thermal_bridge_width 0.5)
		)
		(polygon
			(pts
				(xy 180.5 109.5) (xy 182.5 109.5) (xy 182.5 112.5) (xy 179.375 112.5) (xy 179 112.875) (xy 179 113.25)
				(xy 178.66 113.59) (xy 170.59 113.59) (xy 169.75 112.75) (xy 169.75 110.25) (xy 177 110.25) (xy 177.456 110.706)
				(xy 178.456 110.706) (xy 178.75 111) (xy 180.5 111)
			)
		)
	)
	(zone
		(net 1)
		(net_name "GND")
		(layer "F.Cu")
		(hatch edge 0.5)
		(priority 45)
		(connect_pads yes
			(clearance 0.125)
		)
		(min_thickness 0.2)
		(filled_areas_thickness no)
		(fill yes
			(thermal_gap 0.5)
			(thermal_bridge_width 0.5)
		)
		(polygon
			(pts
				(xy 180.5 143) (xy 180.5 141.5) (xy 182.5 141.5) (xy 182.5 144.5) (xy 179.25 144.5) (xy 179.25 145.75)
				(xy 178 145.75) (xy 177.5 146.25) (xy 170.25 146.25) (xy 169.75 145.75) (xy 169.75 142.5) (xy 177.25 142.5)
				(xy 177.63 142.88) (xy 178.63 142.88) (xy 178.75 143)
			)
		)
	)
	(zone
		(net 880)
		(net_name "/DCDC/12V_OUT")
		(layer "F.Cu")
		(hatch edge 0.5)
		(priority 44)
		(connect_pads yes
			(clearance 0.125)
		)
		(min_thickness 0.2)
		(filled_areas_thickness no)
		(fill yes
			(thermal_gap 0.5)
			(thermal_bridge_width 0.5)
		)
		(polygon
			(pts
				(xy 180.25 151.25) (xy 180 151.5) (xy 177.5 151.5) (xy 175.75 149.75) (xy 169.75 149.75) (xy 169.75 146.75)
				(xy 170.25 146.25) (xy 177.5 146.25) (xy 178 145.75) (xy 179.25 145.75) (xy 180.25 146.75)
			)
		)
	)
	(zone
		(net 567)
		(net_name "/DCDC/3V3_OUT")
		(layer "F.Cu")
		(hatch edge 0.5)
		(priority 41)
		(connect_pads yes
			(clearance 0.125)
		)
		(min_thickness 0.2)
		(filled_areas_thickness no)
		(fill yes
			(thermal_gap 0.5)
			(thermal_bridge_width 0.5)
		)
		(polygon
			(pts
				(xy 178.65 130.44) (xy 178.65 136.84) (xy 178.24 137.25) (xy 175.99 137.25) (xy 173.74 135) (xy 173.74 134.5)
				(xy 171.19 131.95) (xy 171.19 130.44)
			)
		)
	)
	(zone
		(net 5)
		(net_name "+5V")
		(layer "F.Cu")
		(hatch edge 0.5)
		(priority 34)
		(connect_pads yes
			(clearance 0.125)
		)
		(min_thickness 0.2)
		(filled_areas_thickness no)
		(fill yes
			(thermal_gap 0.5)
			(thermal_bridge_width 0.5)
		)
		(polygon
			(pts
				(xy 167.8 113.5) (xy 170.7 113.5) (xy 170.7 114.5) (xy 172 114.5) (xy 172 114.9) (xy 172 116.728572)
				(xy 171.8 116.9) (xy 170.3 116.9) (xy 170.3 118.6) (xy 168.2 118.6) (xy 167.8 118.2)
			)
		)
	)
	(zone
		(net 904)
		(net_name "+20V")
		(layer "F.Cu")
		(hatch edge 0.5)
		(priority 33)
		(connect_pads yes
			(clearance 0.125)
		)
		(min_thickness 0.2)
		(filled_areas_thickness no)
		(fill yes
			(thermal_gap 0.5)
			(thermal_bridge_width 0.5)
		)
		(polygon
			(pts
				(xy 161.35 74.65) (xy 162.4 75.7) (xy 162.4 76.55) (xy 162.05 76.9) (xy 160.6 76.9) (xy 160.6 77.925)
				(xy 160.5 78.05) (xy 157.345 78.05) (xy 157 77.705) (xy 157 75) (xy 157.35 74.65)
			)
		)
	)
	(zone
		(net 11)
		(net_name "+1V8")
		(layer "F.Cu")
		(hatch edge 0.5)
		(priority 68)
		(connect_pads yes
			(clearance 0.1)
		)
		(min_thickness 0.1)
		(filled_areas_thickness no)
		(fill yes
			(thermal_gap 0.5)
			(thermal_bridge_width 0.5)
		)
		(polygon
			(pts
				(xy 79 134.6) (xy 80.2 134.6) (xy 80.2 132.8) (xy 80.4 132.6) (xy 80.4 131.3) (xy 79.3 131.3) (xy 79.2 131.4)
				(xy 79.2 132.8) (xy 79 133)
			)
		)
	)
	(zone
		(net 1)
		(net_name "GND")
		(layer "F.Cu")
		(hatch edge 0.5)
		(priority 37)
		(connect_pads yes
			(clearance 0.125)
		)
		(min_thickness 0.2)
		(filled_areas_thickness no)
		(fill yes
			(thermal_gap 0.5)
			(thermal_bridge_width 0.5)
		)
		(polygon
			(pts
				(xy 175.2 102.3) (xy 176 101.5) (xy 176 100.25) (xy 175.56 99.81) (xy 163.25 99.81) (xy 163.25 102.3)
			)
		)
	)
	(zone
		(net 6)
		(net_name "/CSI/CSIA_3V3")
		(layer "F.Cu")
		(hatch edge 0.5)
		(priority 38)
		(connect_pads yes
			(clearance 0.1)
		)
		(min_thickness 0.15)
		(filled_areas_thickness no)
		(fill yes
			(thermal_gap 0.1)
			(thermal_bridge_width 0.15)
		)
		(polygon
			(pts
				(xy 61 89.7) (xy 61.9 89.7) (xy 61.9 91.1) (xy 63 91.1) (xy 63 93.5) (xy 61 93.5)
			)
		)
	)
	(zone
		(net 253)
		(net_name "/DCDC/5V_OUT")
		(layer "F.Cu")
		(hatch edge 0.5)
		(priority 41)
		(connect_pads yes
			(clearance 0.125)
		)
		(min_thickness 0.2)
		(filled_areas_thickness no)
		(fill yes
			(thermal_gap 0.5)
			(thermal_bridge_width 0.5)
		)
		(polygon
			(pts
				(xy 178.66 113.59) (xy 178.66 120.84) (xy 178 121.5) (xy 174 121.5) (xy 173.75 121.25) (xy 173.75 117.5)
				(xy 172.8 116.55) (xy 172.8 113.59)
			)
		)
	)
	(zone
		(net 1)
		(net_name "GND")
		(layer "F.Cu")
		(hatch edge 0.5)
		(priority 49)
		(connect_pads yes
			(clearance 0.125)
		)
		(min_thickness 0.25)
		(filled_areas_thickness no)
		(fill yes
			(thermal_gap 0.5)
			(thermal_bridge_width 0.5)
		)
		(polygon
			(pts
				(xy 130.499997 54.93) (xy 131.959997 54.93) (xy 131.959996 58.289999) (xy 130.499996 58.289999)
			)
		)
	)
	(zone
		(net 376)
		(net_name "/USB DP Alt mode/USBC1_VBUS")
		(layer "F.Cu")
		(hatch edge 0.5)
		(priority 7)
		(connect_pads yes
			(clearance 0.1)
		)
		(min_thickness 0.25)
		(filled_areas_thickness no)
		(fill yes
			(thermal_gap 0.5)
			(thermal_bridge_width 0.5)
		)
		(polygon
			(pts
				(xy 203.4 79.6) (xy 206.8 79.6) (xy 206.8 81.35) (xy 205.6 81.35) (xy 205.6 80.8) (xy 203.4 80.8)
			)
		)
	)
	(zone
		(net 1)
		(net_name "GND")
		(layer "F.Cu")
		(hatch edge 0.5)
		(priority 67)
		(connect_pads yes
			(clearance 0.1)
		)
		(min_thickness 0.1)
		(filled_areas_thickness no)
		(fill yes
			(thermal_gap 0.5)
			(thermal_bridge_width 0.5)
		)
		(polygon
			(pts
				(xy 71.75 130.75) (xy 73.250001 130.75) (xy 73.5 130.500001) (xy 73.5 129) (xy 77.25 129) (xy 77.25 127)
				(xy 75.75 125.5) (xy 71.75 125.5)
			)
		)
	)
	(zone
		(net 13)
		(net_name "VCC")
		(layer "F.Cu")
		(hatch edge 0.5)
		(priority 70)
		(connect_pads yes
			(clearance 0.125)
		)
		(min_thickness 0.25)
		(filled_areas_thickness no)
		(fill yes
			(thermal_gap 0.5)
			(thermal_bridge_width 0.5)
		)
		(polygon
			(pts
				(xy 129.629999 55.03) (xy 129.629999 58.214214) (xy 128.144213 59.7) (xy 128.144213 61.05) (xy 126.894212 61.049999)
				(xy 126.894212 58.414213) (xy 126.669999 58.19) (xy 126.669999 55.03)
			)
		)
	)
	(zone
		(net 1186)
		(net_name "/DCDC/12V_SW")
		(layer "F.Cu")
		(hatch edge 0.5)
		(priority 43)
		(connect_pads yes
			(clearance 0.125)
		)
		(min_thickness 0.2)
		(filled_areas_thickness no)
		(fill yes
			(thermal_gap 0.5)
			(thermal_bridge_width 0.5)
		)
		(polygon
			(pts
				(xy 179.25 144.5) (xy 182 144.5) (xy 182 145.5) (xy 182.75 146.25) (xy 182.75 151.25) (xy 182.5 151.5)
				(xy 180.5 151.5) (xy 180.25 151.25) (xy 180.25 146.75) (xy 179.25 145.75)
			)
		)
	)
	(zone
		(net 903)
		(net_name "/DCDC/16V_OUT")
		(layer "F.Cu")
		(hatch edge 0.5)
		(priority 36)
		(connect_pads yes
			(clearance 0.125)
		)
		(min_thickness 0.2)
		(filled_areas_thickness no)
		(fill yes
			(thermal_gap 0.5)
			(thermal_bridge_width 0.5)
		)
		(polygon
			(pts
				(xy 178.25 93.5) (xy 179 94.25) (xy 179 101.5) (xy 176 101.5) (xy 176 100.25) (xy 175.56 99.81)
				(xy 163.25 99.81) (xy 163.25 95.5) (xy 162.75 95) (xy 161.75 95) (xy 161.75 93.5)
			)
		)
	)
	(zone
		(net 1278)
		(net_name "/DCDC/5V_{AON}_OUT")
		(layer "F.Cu")
		(hatch edge 0.5)
		(priority 47)
		(connect_pads yes
			(clearance 0.125)
		)
		(min_thickness 0.25)
		(filled_areas_thickness no)
		(fill yes
			(thermal_gap 0.5)
			(thermal_bridge_width 0.5)
		)
		(polygon
			(pts
				(xy 121.969999 54.98) (xy 118.409999 54.98) (xy 116.939999 56.45) (xy 109.2825 56.449999) (xy 108.76 56.972499)
				(xy 108.760001 58.54) (xy 108.76 60.32) (xy 110.26 60.32) (xy 110.26 58.985) (xy 110.705 58.54)
				(xy 121.449999 58.54) (xy 121.969999 58.02)
			)
		)
	)
	(zone
		(net 1)
		(net_name "GND")
		(layer "F.Cu")
		(hatch edge 0.5)
		(priority 74)
		(connect_pads yes
			(clearance 0.125)
		)
		(min_thickness 0.25)
		(filled_areas_thickness no)
		(fill yes
			(thermal_gap 0.5)
			(thermal_bridge_width 0.5)
		)
		(polygon
			(pts
				(xy 126.794212 58.7) (xy 126.794212 61.15) (xy 128.15 61.15) (xy 128.15 62.93) (xy 126.94 62.93)
				(xy 126.74 62.73) (xy 126.139212 62.725) (xy 126.139212 62.075) (xy 125.394212 62.075) (xy 125.394212 59.7)
				(xy 124.340001 58.645789) (xy 124.340001 54.93) (xy 125.570001 54.93) (xy 126.394212 55.754211)
				(xy 126.394212 58.3)
			)
		)
	)
	(zone
		(net 1)
		(net_name "GND")
		(layer "F.Cu")
		(hatch edge 0.5)
		(priority 39)
		(connect_pads yes
			(clearance 0.125)
		)
		(min_thickness 0.2)
		(filled_areas_thickness no)
		(fill yes
			(thermal_gap 0.5)
			(thermal_bridge_width 0.5)
		)
		(polygon
			(pts
				(xy 180.49 126.5) (xy 182.49 126.5) (xy 182.49 129.5) (xy 179.365 129.5) (xy 178.99 129.875) (xy 178.99 130.1)
				(xy 178.65 130.44) (xy 170.63 130.44) (xy 169.75 129.55) (xy 169.75 126.75) (xy 176.49 126.75) (xy 177.446 127.706)
				(xy 178.446 127.706) (xy 178.74 128) (xy 180.49 128)
			)
		)
	)
	(zone
		(net 0)
		(net_name "")
		(layers "F.Cu" "B.Cu" "In1.Cu" "In2.Cu" "In3.Cu" "In4.Cu" "In5.Cu" "In6.Cu"
			"In7.Cu" "In8.Cu"
		)
		(name "auto-placement-area-DCDC_SOM")
		(hatch none 0.5)
		(connect_pads yes
			(clearance 0)
		)
		(min_thickness 0.25)
		(filled_areas_thickness no)
		(keepout
			(tracks allowed)
			(vias allowed)
			(pads allowed)
			(copperpour allowed)
			(footprints allowed)
		)
		(placement
			(enabled yes)
			(component_class "DCDC_SOM")
		)
		(fill
			(thermal_gap 0.5)
			(thermal_bridge_width 0.5)
		)
		(polygon
			(pts
				(xy 186.275 101.595) (xy 186.275 103.445) (xy 176.025 103.445) (xy 176.025 102.543) (xy 161.615 102.543)
				(xy 161.615 97.425) (xy 160.325 97.425) (xy 160.325 94.395) (xy 160.425 94.395) (xy 160.425 86.745)
				(xy 170.555 86.745) (xy 170.555 84.62) (xy 185.095 84.62) (xy 185.095 92.845) (xy 186.275 92.845)
			)
		)
	)
	(zone
		(net 0)
		(net_name "")
		(layers "F.Cu" "B.Cu" "In1.Cu" "In2.Cu" "In3.Cu" "In4.Cu" "In5.Cu" "In6.Cu"
			"In7.Cu" "In8.Cu"
		)
		(name "auto-placement-area-DCDC_20V")
		(hatch none 0.5)
		(connect_pads yes
			(clearance 0)
		)
		(min_thickness 0.25)
		(filled_areas_thickness no)
		(keepout
			(tracks allowed)
			(vias allowed)
			(pads allowed)
			(copperpour allowed)
			(footprints allowed)
		)
		(placement
			(enabled yes)
			(component_class "DCDC_20V")
		)
		(fill
			(thermal_gap 0.5)
			(thermal_bridge_width 0.5)
		)
		(polygon
			(pts
				(xy 184.215 81.875) (xy 184.215 83.725) (xy 173.965 83.725) (xy 173.965 82.823) (xy 159.555 82.823)
				(xy 159.555 77.705) (xy 158.265 77.705) (xy 158.265 74.675) (xy 158.365 74.675) (xy 158.365 67.025)
				(xy 168.495 67.025) (xy 168.495 64.9) (xy 183.035 64.9) (xy 183.035 73.125) (xy 184.215 73.125)
			)
		)
	)
	(zone
		(net 13)
		(net_name "VCC")
		(layers "F.Cu" "In4.Cu")
		(hatch edge 0.5)
		(priority 24)
		(connect_pads yes
			(clearance 0.125)
		)
		(min_thickness 0.2)
		(filled_areas_thickness no)
		(fill yes
			(thermal_gap 0.5)
			(thermal_bridge_width 0.5)
		)
		(polygon
			(pts
				(xy 207.535 67.015) (xy 211.85 67) (xy 211.85 74) (xy 206.4 74) (xy 204.646934 72) (xy 194.496934 72)
				(xy 191.746934 74.75) (xy 191.746934 76.75) (xy 191.246934 77.25) (xy 191 77.5) (xy 191 103.25)
				(xy 188.25 106) (xy 179 106) (xy 178.5 106.5) (xy 178.5 108.5) (xy 179.5 109.5) (xy 180.5 109.5)
				(xy 180.5 111) (xy 178.75 111) (xy 178.456 110.706) (xy 177.456 110.706) (xy 177 110.25) (xy 169.75 110.25)
				(xy 169.75 106.25) (xy 173.7 102.3) (xy 175.2 102.3) (xy 176 101.5) (xy 184 101.5) (xy 184 86.75)
				(xy 183 85.75) (xy 177.75 85.75) (xy 177.25 86.25) (xy 177.25 88.25) (xy 178 89) (xy 179.25 89)
				(xy 179.25 90.5) (xy 177.25 90.5) (xy 177 90.25) (xy 176.25 90.25) (xy 174.98 89.11) (xy 168.5 89.11)
				(xy 168.5 83.25) (xy 169.45 82.3) (xy 175.2 82.3) (xy 176 81.5) (xy 183.25 81.5) (xy 183.8 80.95)
				(xy 183.8 77.25) (xy 183.796934 77.25) (xy 183.806402 70.190532) (xy 184.496934 69.25) (xy 184.496934 66.286667)
				(xy 183.670463 65.35) (xy 178.496934 65.35) (xy 177.246934 66.6) (xy 177.246934 68.25) (xy 177.996934 69)
				(xy 179.246934 69) (xy 179.246934 70.45) (xy 176.196934 70.45) (xy 175.746934 70) (xy 175.746934 69.5)
				(xy 175.356934 69.11) (xy 168.246934 69.11) (xy 168.246934 66) (xy 169.746934 64.5) (xy 173.496934 64.5)
				(xy 173.996934 64) (xy 173.996934 63.25) (xy 177.746934 59.5) (xy 207.55 59.5)
			)
		)
	)
	(zone
		(net 176)
		(net_name "/USB Debug, PD/USBC0_VBUS")
		(layer "B.Cu")
		(hatch edge 0.5)
		(priority 4)
		(connect_pads yes
			(clearance 0.1)
		)
		(min_thickness 0.25)
		(filled_areas_thickness no)
		(fill yes
			(thermal_gap 0.5)
			(thermal_bridge_width 0.5)
		)
		(polygon
			(pts
				(xy 233.2 82.2) (xy 233.2 83.2) (xy 229.6 83.2) (xy 229.6 73) (xy 234.35 73) (xy 234.35 79) (xy 233.3 79)
				(xy 232.6 79.2) (xy 231.899 79.901) (xy 231.899 82.397) (xy 232.096 82.2)
			)
		)
	)
	(zone
		(net 5)
		(net_name "+5V")
		(layer "B.Cu")
		(hatch edge 0.5)
		(priority 16)
		(connect_pads yes
			(clearance 0.1)
		)
		(min_thickness 0.25)
		(filled_areas_thickness no)
		(fill yes
			(thermal_gap 0.5)
			(thermal_bridge_width 0.5)
		)
		(polygon
			(pts
				(xy 233 134.5) (xy 235.9 134.5) (xy 235.9 136.6) (xy 233 136.6)
			)
		)
	)
	(zone
		(net 13)
		(net_name "VCC")
		(layer "B.Cu")
		(hatch edge 0.5)
		(priority 26)
		(connect_pads yes
			(clearance 0.125)
		)
		(min_thickness 0.2)
		(filled_areas_thickness no)
		(fill yes
			(thermal_gap 0.5)
			(thermal_bridge_width 0.5)
		)
		(polygon
			(pts
				(xy 182.5 80.25) (xy 182.5 82.75) (xy 186.75 82.75) (xy 186.75 80.25)
			)
		)
	)
	(zone
		(net 12)
		(net_name "SYS_VIN_HV")
		(layer "B.Cu")
		(hatch edge 0.5)
		(priority 52)
		(connect_pads yes
			(clearance 0.1)
		)
		(min_thickness 0.25)
		(filled_areas_thickness no)
		(fill yes
			(thermal_gap 0.5)
			(thermal_bridge_width 0.5)
		)
		(polygon
			(pts
				(xy 83.5 67.9) (xy 84.8 67.9) (xy 84.8 66.4) (xy 87 66.4) (xy 87 68.4) (xy 86 68.4) (xy 86 72) (xy 87 73)
				(xy 89 73) (xy 89 79) (xy 86.5 79) (xy 83.5 76)
			)
		)
	)
	(zone
		(net 9)
		(net_name "/CSI/CSIB_5V")
		(layer "B.Cu")
		(hatch edge 0.5)
		(priority 39)
		(connect_pads yes
			(clearance 0.1)
		)
		(min_thickness 0.25)
		(filled_areas_thickness no)
		(fill yes
			(thermal_gap 0.5)
			(thermal_bridge_width 0.5)
		)
		(polygon
			(pts
				(xy 217.5 59.09) (xy 218.5 59.09) (xy 218.5 61) (xy 218 61.5) (xy 215 61.5) (xy 213.930532 62.569468)
				(xy 213.930532 65.5) (xy 211.298 65.5) (xy 211.201 65.403) (xy 211.201 64) (xy 212.5 64) (xy 212.5 62)
				(xy 214.65 59.85) (xy 217.5 59.85)
			)
		)
	)
	(zone
		(net 14)
		(net_name "/M.2/3V3_M2")
		(layer "B.Cu")
		(hatch edge 0.5)
		(priority 40)
		(connect_pads yes
			(clearance 0.1)
		)
		(min_thickness 0.15)
		(filled_areas_thickness no)
		(fill yes
			(thermal_gap 0.1)
			(thermal_bridge_width 0.15)
		)
		(polygon
			(pts
				(xy 124.5 99.7) (xy 120.25 99.7) (xy 120.25 112.2) (xy 122.6 112.2) (xy 123.5 111.3) (xy 124.5 111.3)
				(xy 124.5 114.2) (xy 117.8 114.2) (xy 117.8 97.75) (xy 120.25 97.75) (xy 122.1 97.75) (xy 122.1 96.3)
				(xy 120.3 96.3) (xy 120.3 94.8) (xy 124.5 94.8)
			)
		)
	)
	(zone
		(net 5)
		(net_name "+5V")
		(layer "B.Cu")
		(hatch edge 0.5)
		(priority 5)
		(connect_pads yes
			(clearance 0.1)
		)
		(min_thickness 0.25)
		(filled_areas_thickness no)
		(fill yes
			(thermal_gap 0.5)
			(thermal_bridge_width 0.5)
		)
		(polygon
			(pts
				(xy 235.95 83.45) (xy 235.95 82.3) (xy 234.3 82.3) (xy 234.3 83.4) (xy 234.6 83.7) (xy 234.6 84.7)
				(xy 237.2 84.7) (xy 237.2 83.45)
			)
		)
	)
	(zone
		(net 5)
		(net_name "+5V")
		(layer "B.Cu")
		(hatch edge 0.5)
		(priority 2)
		(connect_pads yes
			(clearance 0.1)
		)
		(min_thickness 0.1)
		(filled_areas_thickness no)
		(fill yes
			(thermal_gap 0.5)
			(thermal_bridge_width 0.5)
		)
		(polygon
			(pts
				(xy 233.1 95.7) (xy 234.7 95.7) (xy 235.019 96.019) (xy 235.019 96.03) (xy 235.609 96.03) (xy 235.609 97.7)
				(xy 233.1 97.7)
			)
		)
	)
	(zone
		(net 525)
		(net_name "/Power/USBPD2_HV")
		(layer "B.Cu")
		(hatch edge 0.5)
		(priority 27)
		(connect_pads yes
			(clearance 0.125)
		)
		(min_thickness 0.15)
		(filled_areas_thickness no)
		(fill yes
			(thermal_gap 0.5)
			(thermal_bridge_width 0.5)
		)
		(polygon
			(pts
				(xy 179.286 76.046) (xy 197.5 76.046) (xy 199.5 74) (xy 209 74) (xy 210.5 75.5) (xy 210.5 77.25)
				(xy 209.25 78.5) (xy 204.5 78.5) (xy 202.75 80.25) (xy 180.5 80.25) (xy 179.25 79) (xy 179.25 76.082)
			)
		)
	)
	(zone
		(net 295)
		(net_name "/Expansion connector/+V_{ADJ}")
		(layer "B.Cu")
		(hatch edge 0.5)
		(priority 65)
		(connect_pads
			(clearance 0.1)
		)
		(min_thickness 0.25)
		(filled_areas_thickness no)
		(fill yes
			(thermal_gap 0.5)
			(thermal_bridge_width 0.5)
		)
		(polygon
			(pts
				(xy 73.75 126) (xy 73.75 133) (xy 79 133) (xy 79 126)
			)
		)
	)
	(zone
		(net 2)
		(net_name "+3V3")
		(layer "B.Cu")
		(hatch edge 0.5)
		(priority 60)
		(connect_pads yes
			(clearance 0.1)
		)
		(min_thickness 0.1)
		(filled_areas_thickness no)
		(fill yes
			(thermal_gap 0.5)
			(thermal_bridge_width 0.5)
		)
		(polygon
			(pts
				(xy 207.1 62.4) (xy 211.1 62.4) (xy 211.1 60.5) (xy 207.1 60.5)
			)
		)
	)
	(zone
		(net 522)
		(net_name "/Power/USBPD1_HV")
		(layer "B.Cu")
		(hatch edge 0.5)
		(priority 31)
		(connect_pads yes
			(clearance 0.125)
		)
		(min_thickness 0.15)
		(filled_areas_thickness no)
		(fill yes
			(thermal_gap 0.5)
			(thermal_bridge_width 0.5)
		)
		(polygon
			(pts
				(xy 205.4 86) (xy 205.4 80.3) (xy 205.35 80.25) (xy 186.75 80.25) (xy 186.75 82.75) (xy 184.5 82.75)
				(xy 184.5 84.9) (xy 182.4 84.9) (xy 182.4 86.3) (xy 179.75 86.3) (xy 179.75 89.4) (xy 182.1 89.4)
				(xy 182.5 89) (xy 187.6 89) (xy 189.9 86.7) (xy 189.9 84.6) (xy 191.2 83.3) (xy 195.8 83.3) (xy 198.5 86)
			)
		)
	)
	(zone
		(net 156)
		(net_name "/Expansion connector/+VCC_FMC")
		(layer "B.Cu")
		(hatch edge 0.5)
		(priority 53)
		(connect_pads yes
			(clearance 0.1)
		)
		(min_thickness 0.25)
		(filled_areas_thickness no)
		(fill yes
			(thermal_gap 0.5)
			(thermal_bridge_width 0.5)
		)
		(polygon
			(pts
				(xy 91.978829 135.978829) (xy 97.978829 135.978829) (xy 98.478829 136.478829) (xy 99.478829 136.478829)
				(xy 99.478829 135.478829) (xy 99.978829 134.978829) (xy 99.978829 133.478829) (xy 99.478829 132.978829)
				(xy 97.478829 132.978829) (xy 96.478829 131.978829) (xy 91.978829 131.978829)
			)
		)
	)
	(zone
		(net 5)
		(net_name "+5V")
		(layer "B.Cu")
		(hatch edge 0.5)
		(priority 17)
		(connect_pads yes
			(clearance 0.1)
		)
		(min_thickness 0.25)
		(filled_areas_thickness no)
		(fill yes
			(thermal_gap 0.5)
			(thermal_bridge_width 0.5)
		)
		(polygon
			(pts
				(xy 235.75 122.6) (xy 233 122.6) (xy 233 124.6) (xy 237.25 124.6) (xy 237.25 123.5) (xy 235.75 123.5)
			)
		)
	)
	(zone
		(net 7)
		(net_name "/CSI/CSIA_5V")
		(layer "B.Cu")
		(hatch edge 0.5)
		(priority 37)
		(connect_pads yes
			(clearance 0.1)
		)
		(min_thickness 0.15)
		(filled_areas_thickness no)
		(fill yes
			(thermal_gap 0.1)
			(thermal_bridge_width 0.15)
		)
		(polygon
			(pts
				(xy 65.3 92.2) (xy 67.4 92.2) (xy 67.4 91) (xy 65.3 91)
			)
		)
	)
	(zone
		(net 1)
		(net_name "GND")
		(layer "B.Cu")
		(hatch edge 0.5)
		(priority 57)
		(connect_pads yes
			(clearance 0.1)
		)
		(min_thickness 0.25)
		(filled_areas_thickness no)
		(fill yes
			(thermal_gap 0.5)
			(thermal_bridge_width 0.5)
		)
		(polygon
			(pts
				(xy 92 136) (xy 98 136) (xy 98.5 136.5) (xy 99.85 136.5) (xy 99.85 148) (xy 92 148)
			)
		)
	)
	(zone
		(net 289)
		(net_name "/Expansion connector/+12V_FMC")
		(layer "B.Cu")
		(hatch edge 0.5)
		(priority 69)
		(connect_pads
			(clearance 0.1)
		)
		(min_thickness 0.1)
		(filled_areas_thickness no)
		(fill yes
			(thermal_gap 0.5)
			(thermal_bridge_width 0.5)
		)
		(polygon
			(pts
				(xy 70 122.5) (xy 73.555532 122.5) (xy 73.555532 135.20601) (xy 76.194366 138) (xy 77.5 138) (xy 80 135.5)
				(xy 80 121.5) (xy 83 121.5) (xy 83 139.5) (xy 81 141.5) (xy 72 141.5) (xy 70 139.5)
			)
		)
	)
	(zone
		(net 5)
		(net_name "+5V")
		(layer "B.Cu")
		(hatch edge 0.5)
		(priority 59)
		(connect_pads yes
			(clearance 0.1)
		)
		(min_thickness 0.1)
		(filled_areas_thickness no)
		(fill yes
			(thermal_gap 0.5)
			(thermal_bridge_width 0.5)
		)
		(polygon
			(pts
				(xy 100.2 130) (xy 105.4 130) (xy 105.4 134) (xy 102.8 134) (xy 102 133.2) (xy 102 132) (xy 100.2 132)
			)
		)
	)
	(zone
		(net 13)
		(net_name "VCC")
		(layer "B.Cu")
		(hatch edge 0.5)
		(priority 26)
		(connect_pads yes
			(clearance 0.125)
		)
		(min_thickness 0.2)
		(filled_areas_thickness no)
		(fill yes
			(thermal_gap 0.5)
			(thermal_bridge_width 0.5)
		)
		(polygon
			(pts
				(xy 182.5 89) (xy 182.5 91.65) (xy 187.6 91.65) (xy 187.6 89)
			)
		)
	)
	(zone
		(net 2)
		(net_name "+3V3")
		(layer "B.Cu")
		(hatch edge 0.5)
		(priority 58)
		(connect_pads yes
			(clearance 0.1)
		)
		(min_thickness 0.1)
		(filled_areas_thickness no)
		(fill yes
			(thermal_gap 0.5)
			(thermal_bridge_width 0.5)
		)
		(polygon
			(pts
				(xy 100.2 129.8) (xy 104 129.8) (xy 104 128.4) (xy 101.6 126) (xy 100.2 126)
			)
		)
	)
	(zone
		(net 8)
		(net_name "/CSI/CSIB_3V3")
		(layer "B.Cu")
		(hatch edge 0.5)
		(priority 43)
		(connect_pads yes
			(clearance 0.1)
		)
		(min_thickness 0.25)
		(filled_areas_thickness no)
		(fill yes
			(thermal_gap 0.5)
			(thermal_bridge_width 0.5)
		)
		(polygon
			(pts
				(xy 211.201 61.903) (xy 212.5 61.903) (xy 214.65 59.75) (xy 217.4 59.75) (xy 217.4 59.1) (xy 216.4 59.1)
				(xy 216.4 59) (xy 212 59) (xy 212 60.4) (xy 211.2 61.2) (xy 211.2 61.902)
			)
		)
	)
	(zone
		(net 2)
		(net_name "+3V3")
		(layer "B.Cu")
		(hatch edge 0.5)
		(priority 41)
		(connect_pads yes
			(clearance 0.1)
		)
		(min_thickness 0.15)
		(filled_areas_thickness no)
		(fill yes
			(thermal_gap 0.1)
			(thermal_bridge_width 0.15)
		)
		(polygon
			(pts
				(xy 124.6 96.2) (xy 126 96.2) (xy 126 92.4) (xy 122.2 92.4) (xy 122.2 94.6) (xy 124.6 94.6)
			)
		)
	)
	(zone
		(net 2)
		(net_name "+3V3")
		(layer "B.Cu")
		(hatch edge 0.5)
		(priority 42)
		(connect_pads yes
			(clearance 0.1)
		)
		(min_thickness 0.15)
		(filled_areas_thickness no)
		(fill yes
			(thermal_gap 0.1)
			(thermal_bridge_width 0.15)
		)
		(polygon
			(pts
				(xy 120.25 138.822568) (xy 122.5 138.822568) (xy 123.5 139.822568) (xy 124.5 139.822568) (xy 124.5 136.822568)
				(xy 123.5 136.822568) (xy 122.5 137.822568) (xy 120.25 137.822568)
			)
		)
	)
	(zone
		(net 904)
		(net_name "+20V")
		(layer "B.Cu")
		(hatch edge 0.5)
		(priority 23)
		(connect_pads yes
			(clearance 0.125)
		)
		(min_thickness 0.2)
		(filled_areas_thickness no)
		(fill yes
			(thermal_gap 0.5)
			(thermal_bridge_width 0.5)
		)
		(polygon
			(pts
				(xy 179 86) (xy 179 72.25) (xy 159.25 72.25) (xy 157 74.5) (xy 157 78) (xy 163.75 84.75) (xy 180.25 84.75)
			)
		)
	)
	(zone
		(net 297)
		(net_name "/Expansion connector/+3V3_FMC")
		(layer "B.Cu")
		(hatch edge 0.5)
		(priority 55)
		(connect_pads yes
			(clearance 0.1)
		)
		(min_thickness 0.25)
		(filled_areas_thickness no)
		(fill yes
			(thermal_gap 0.5)
			(thermal_bridge_width 0.5)
		)
		(polygon
			(pts
				(xy 92 130) (xy 100 130) (xy 100 128.5) (xy 99.5 128) (xy 99.5 127) (xy 92 127)
			)
		)
	)
	(zone
		(net 5)
		(net_name "+5V")
		(layer "B.Cu")
		(hatch edge 0.5)
		(priority 2)
		(connect_pads yes
			(clearance 0.1)
		)
		(min_thickness 0.1)
		(filled_areas_thickness no)
		(fill yes
			(thermal_gap 0.5)
			(thermal_bridge_width 0.5)
		)
		(polygon
			(pts
				(xy 233 109.2) (xy 234.6 109.2) (xy 234.919 109.519) (xy 234.919 109.53) (xy 235.7 109.53) (xy 235.7 110.35)
				(xy 237.209 110.35) (xy 237.209 111.2) (xy 233 111.2)
			)
		)
	)
	(zone
		(net 307)
		(net_name "/Expansion connector/+5V_FMC")
		(layer "B.Cu")
		(hatch edge 0.5)
		(priority 54)
		(connect_pads yes
			(clearance 0.1)
		)
		(min_thickness 0.25)
		(filled_areas_thickness no)
		(fill yes
			(thermal_gap 0.5)
			(thermal_bridge_width 0.5)
		)
		(polygon
			(pts
				(xy 92 132) (xy 96.5 132) (xy 97.5 133) (xy 99.5 133) (xy 99.5 132) (xy 100 131.5) (xy 100 130)
				(xy 92 130)
			)
		)
	)
	(zone
		(net 115)
		(net_name "/USB Hub/USBC4_VBUS")
		(layer "B.Cu")
		(hatch edge 0.5)
		(priority 15)
		(connect_pads yes
			(clearance 0.1)
		)
		(min_thickness 0.25)
		(filled_areas_thickness no)
		(fill yes
			(thermal_gap 0.5)
			(thermal_bridge_width 0.5)
		)
		(polygon
			(pts
				(xy 228.5 134.2) (xy 230.1 134.2) (xy 230.4 134.5) (xy 231.8 134.5) (xy 231.8 132.4) (xy 230.1 130.7)
				(xy 230.1 124.85) (xy 234.65 124.85) (xy 234.65 126.1) (xy 234.65 131.7) (xy 233.4 132.4) (xy 233.099 132.4)
				(xy 232.9 132.599) (xy 232.9 135.5) (xy 232.8 135.6) (xy 228.5 135.6)
			)
		)
	)
	(zone
		(net 376)
		(net_name "/USB DP Alt mode/USBC1_VBUS")
		(layer "B.Cu")
		(hatch edge 0.5)
		(priority 3)
		(connect_pads yes
			(clearance 0.1)
		)
		(min_thickness 0.25)
		(filled_areas_thickness no)
		(fill yes
			(thermal_gap 0.5)
			(thermal_bridge_width 0.5)
		)
		(polygon
			(pts
				(xy 231.8 95.6) (xy 228.2 95.6) (xy 228.2 97) (xy 233 97) (xy 233 92) (xy 234.45 92) (xy 234.45 86.6)
				(xy 232.3 86.6) (xy 232.3 86.9) (xy 230.2 86.9) (xy 230.2 92.2) (xy 231.8 93.8)
			)
		)
	)
	(zone
		(net 287)
		(net_name "/Recovery USB/USBC2_VBUS")
		(layer "B.Cu")
		(hatch edge 0.5)
		(priority 1)
		(connect_pads yes
			(clearance 0.1)
		)
		(min_thickness 0.1)
		(filled_areas_thickness no)
		(fill yes
			(thermal_gap 0.5)
			(thermal_bridge_width 0.5)
		)
		(polygon
			(pts
				(xy 230 99.4) (xy 234.3 99.4) (xy 234.3 106.6) (xy 233 106.8) (xy 233 110) (xy 228.2 109.999999)
				(xy 228.200001 108.799999) (xy 230 108.799999) (xy 230 109.2) (xy 230.051 109.251) (xy 231.8 109.251)
				(xy 231.8 107.45) (xy 230 105.65)
			)
		)
	)
	(zone
		(net 6)
		(net_name "/CSI/CSIA_3V3")
		(layer "B.Cu")
		(hatch edge 0.5)
		(priority 36)
		(connect_pads yes
			(clearance 0.1)
		)
		(min_thickness 0.15)
		(filled_areas_thickness no)
		(fill yes
			(thermal_gap 0.1)
			(thermal_bridge_width 0.15)
		)
		(polygon
			(pts
				(xy 62 93.6) (xy 63.3 93.6) (xy 63.3 93.2) (xy 63.9 93.2) (xy 63.9 92.2) (xy 63.3 92.2) (xy 63.3 91.1)
				(xy 62 91.1)
			)
		)
	)
	(zone
		(net 13)
		(net_name "VCC")
		(layer "B.Cu")
		(hatch edge 0.5)
		(priority 62)
		(connect_pads yes
			(clearance 0.1)
		)
		(min_thickness 0.25)
		(filled_areas_thickness no)
		(fill yes
			(thermal_gap 0.5)
			(thermal_bridge_width 0.5)
		)
		(polygon
			(pts
				(xy 107.4 134) (xy 102.8 134) (xy 102 133.2) (xy 99.978829 133.2) (xy 99.978829 135.103829) (xy 100.6 135.725)
				(xy 100.6 147.6) (xy 101 148) (xy 108 148) (xy 108 134.6)
			)
		)
	)
	(zone
		(net 2)
		(net_name "+3V3")
		(layer "B.Cu")
		(hatch edge 0.5)
		(priority 42)
		(connect_pads yes
			(clearance 0.1)
		)
		(min_thickness 0.15)
		(filled_areas_thickness no)
		(fill yes
			(thermal_gap 0.1)
			(thermal_bridge_width 0.15)
		)
		(polygon
			(pts
				(xy 120.25 121.25) (xy 122.5 121.25) (xy 123.5 122.25) (xy 124.5 122.25) (xy 124.5 119.25) (xy 123.5 119.25)
				(xy 122.5 120.25) (xy 120.25 120.25)
			)
		)
	)
	(zone
		(net 71)
		(net_name "/USB Hub/USBC3_VBUS")
		(layer "B.Cu")
		(hatch edge 0.5)
		(priority 13)
		(connect_pads yes
			(clearance 0.1)
		)
		(min_thickness 0.25)
		(filled_areas_thickness no)
		(fill yes
			(thermal_gap 0.5)
			(thermal_bridge_width 0.5)
		)
		(polygon
			(pts
				(xy 228.4 122) (xy 230.2 122) (xy 230.6 122.4) (xy 231.8 122.4) (xy 231.8 120.6) (xy 230.2 119)
				(xy 230.2 112.6) (xy 234.4 112.6) (xy 234.4 118) (xy 233 119.4) (xy 233 123.4) (xy 228.4 123.4)
			)
		)
	)
	(zone
		(net 1383)
		(net_name "VCC_NO_OVP")
		(layer "B.Cu")
		(hatch edge 0.5)
		(priority 72)
		(connect_pads
			(clearance 0.125)
		)
		(min_thickness 0.25)
		(filled_areas_thickness no)
		(fill yes
			(thermal_gap 0.5)
			(thermal_bridge_width 0.5)
		)
		(polygon
			(pts
				(xy 211.801 65.5) (xy 211.801 68.7) (xy 216.1 68.7) (xy 216.1 67.6) (xy 215.8 67.3) (xy 213.5 67.3)
				(xy 213.5 65.5)
			)
		)
	)
	(zone
		(net 0)
		(net_name "")
		(layers "In1.Cu" "In2.Cu")
		(hatch edge 0.5)
		(connect_pads yes
			(clearance 0)
		)
		(min_thickness 0.25)
		(filled_areas_thickness no)
		(keepout
			(tracks not_allowed)
			(vias allowed)
			(pads allowed)
			(copperpour not_allowed)
			(footprints allowed)
		)
		(placement
			(enabled no)
			(sheetname "")
		)
		(fill
			(thermal_gap 0.5)
			(thermal_bridge_width 0.5)
		)
		(polygon
			(pts
				(xy 196.743697 147.645) (xy 196.743697 148.16) (xy 198.743697 148.16) (xy 198.743697 147.645)
			)
		)
	)
	(zone
		(net 0)
		(net_name "")
		(layers "In1.Cu" "In2.Cu")
		(hatch edge 0.5)
		(connect_pads yes
			(clearance 0)
		)
		(min_thickness 0.25)
		(filled_areas_thickness no)
		(keepout
			(tracks not_allowed)
			(vias allowed)
			(pads allowed)
			(copperpour not_allowed)
			(footprints allowed)
		)
		(placement
			(enabled no)
			(sheetname "")
		)
		(fill
			(thermal_gap 0.5)
			(thermal_bridge_width 0.5)
		)
		(polygon
			(pts
				(xy 192.357939 141.95) (xy 192.357939 142.59) (xy 193.907939 142.59) (xy 193.907939 141.95)
			)
		)
	)
	(zone
		(net 0)
		(net_name "")
		(layers "In1.Cu" "In2.Cu")
		(hatch edge 0.5)
		(connect_pads yes
			(clearance 0)
		)
		(min_thickness 0.25)
		(filled_areas_thickness no)
		(keepout
			(tracks not_allowed)
			(vias allowed)
			(pads allowed)
			(copperpour not_allowed)
			(footprints allowed)
		)
		(placement
			(enabled no)
			(sheetname "")
		)
		(fill
			(thermal_gap 0.5)
			(thermal_bridge_width 0.5)
		)
		(polygon
			(pts
				(xy 196.743697 142.845) (xy 196.743697 143.36) (xy 198.743697 143.36) (xy 198.743697 142.845)
			)
		)
	)
	(zone
		(net 0)
		(net_name "")
		(layers "In1.Cu" "In2.Cu")
		(hatch edge 0.5)
		(connect_pads yes
			(clearance 0)
		)
		(min_thickness 0.25)
		(filled_areas_thickness no)
		(keepout
			(tracks not_allowed)
			(vias allowed)
			(pads allowed)
			(copperpour not_allowed)
			(footprints allowed)
		)
		(placement
			(enabled no)
			(sheetname "")
		)
		(fill
			(thermal_gap 0.5)
			(thermal_bridge_width 0.5)
		)
		(polygon
			(pts
				(xy 192.353573 146.775) (xy 192.353573 147.415) (xy 193.903573 147.415) (xy 193.903573 146.775)
			)
		)
	)
	(zone
		(net 0)
		(net_name "")
		(layers "In1.Cu" "In2.Cu")
		(hatch edge 0.5)
		(connect_pads yes
			(clearance 0)
		)
		(min_thickness 0.25)
		(filled_areas_thickness no)
		(keepout
			(tracks not_allowed)
			(vias allowed)
			(pads allowed)
			(copperpour not_allowed)
			(footprints allowed)
		)
		(placement
			(enabled no)
			(sheetname "")
		)
		(fill
			(thermal_gap 0.5)
			(thermal_bridge_width 0.5)
		)
		(polygon
			(pts
				(xy 205.975 89.15) (xy 205.975 89.79) (xy 207.525 89.79) (xy 207.525 89.15)
			)
		)
	)
	(zone
		(net 0)
		(net_name "")
		(layers "In1.Cu" "In2.Cu")
		(hatch edge 0.5)
		(connect_pads yes
			(clearance 0)
		)
		(min_thickness 0.25)
		(filled_areas_thickness no)
		(keepout
			(tracks not_allowed)
			(vias allowed)
			(pads allowed)
			(copperpour not_allowed)
			(footprints allowed)
		)
		(placement
			(enabled no)
			(sheetname "")
		)
		(fill
			(thermal_gap 0.5)
			(thermal_bridge_width 0.5)
		)
		(polygon
			(pts
				(xy 196.743697 146.86) (xy 196.743697 147.375) (xy 198.743697 147.375) (xy 198.743697 146.86)
			)
		)
	)
	(zone
		(net 0)
		(net_name "")
		(layers "In1.Cu" "In2.Cu")
		(hatch edge 0.5)
		(connect_pads yes
			(clearance 0)
		)
		(min_thickness 0.25)
		(filled_areas_thickness no)
		(keepout
			(tracks not_allowed)
			(vias allowed)
			(pads allowed)
			(copperpour not_allowed)
			(footprints allowed)
		)
		(placement
			(enabled no)
			(sheetname "")
		)
		(fill
			(thermal_gap 0.5)
			(thermal_bridge_width 0.5)
		)
		(polygon
			(pts
				(xy 109.025 129.184144) (xy 109.025 129.824144) (xy 110.575 129.824144) (xy 110.575 129.184144)
			)
		)
	)
	(zone
		(net 0)
		(net_name "")
		(layers "In1.Cu" "In2.Cu")
		(hatch edge 0.5)
		(connect_pads yes
			(clearance 0)
		)
		(min_thickness 0.25)
		(filled_areas_thickness no)
		(keepout
			(tracks not_allowed)
			(vias allowed)
			(pads allowed)
			(copperpour not_allowed)
			(footprints allowed)
		)
		(placement
			(enabled no)
			(sheetname "")
		)
		(fill
			(thermal_gap 0.5)
			(thermal_bridge_width 0.5)
		)
		(polygon
			(pts
				(xy 196.743697 142.06) (xy 196.743697 142.575) (xy 198.743697 142.575) (xy 198.743697 142.06)
			)
		)
	)
	(zone
		(net 0)
		(net_name "")
		(layers "In1.Cu" "In2.Cu")
		(hatch edge 0.5)
		(connect_pads yes
			(clearance 0)
		)
		(min_thickness 0.25)
		(filled_areas_thickness no)
		(keepout
			(tracks not_allowed)
			(vias allowed)
			(pads allowed)
			(copperpour not_allowed)
			(footprints allowed)
		)
		(placement
			(enabled no)
			(sheetname "")
		)
		(fill
			(thermal_gap 0.5)
			(thermal_bridge_width 0.5)
		)
		(polygon
			(pts
				(xy 109.025 128.175) (xy 109.025 128.815) (xy 110.575 128.815) (xy 110.575 128.175)
			)
		)
	)
	(zone
		(net 0)
		(net_name "")
		(layers "In1.Cu" "In2.Cu")
		(hatch edge 0.5)
		(connect_pads yes
			(clearance 0)
		)
		(min_thickness 0.25)
		(filled_areas_thickness no)
		(keepout
			(tracks not_allowed)
			(vias allowed)
			(pads allowed)
			(copperpour not_allowed)
			(footprints allowed)
		)
		(placement
			(enabled no)
			(sheetname "")
		)
		(fill
			(thermal_gap 0.5)
			(thermal_bridge_width 0.5)
		)
		(polygon
			(pts
				(xy 205.975 88.140856) (xy 205.975 88.780856) (xy 207.525 88.780856) (xy 207.525 88.140856)
			)
		)
	)
	(zone
		(net 0)
		(net_name "")
		(layers "In1.Cu" "In2.Cu")
		(hatch edge 0.5)
		(connect_pads yes
			(clearance 0)
		)
		(min_thickness 0.25)
		(filled_areas_thickness no)
		(keepout
			(tracks not_allowed)
			(vias allowed)
			(pads allowed)
			(copperpour not_allowed)
			(footprints allowed)
		)
		(placement
			(enabled no)
			(sheetname "")
		)
		(fill
			(thermal_gap 0.5)
			(thermal_bridge_width 0.5)
		)
		(polygon
			(pts
				(xy 203.975 89.640856) (xy 203.975 90.280856) (xy 205.525 90.280856) (xy 205.525 89.640856)
			)
		)
	)
	(zone
		(net 0)
		(net_name "")
		(layers "In1.Cu" "In2.Cu")
		(hatch edge 0.5)
		(connect_pads yes
			(clearance 0)
		)
		(min_thickness 0.25)
		(filled_areas_thickness no)
		(keepout
			(tracks not_allowed)
			(vias allowed)
			(pads allowed)
			(copperpour not_allowed)
			(footprints allowed)
		)
		(placement
			(enabled no)
			(sheetname "")
		)
		(fill
			(thermal_gap 0.5)
			(thermal_bridge_width 0.5)
		)
		(polygon
			(pts
				(xy 205.975 92.15) (xy 205.975 92.79) (xy 207.525 92.79) (xy 207.525 92.15)
			)
		)
	)
	(zone
		(net 0)
		(net_name "")
		(layers "In1.Cu" "In2.Cu")
		(hatch edge 0.5)
		(connect_pads yes
			(clearance 0)
		)
		(min_thickness 0.25)
		(filled_areas_thickness no)
		(keepout
			(tracks not_allowed)
			(vias allowed)
			(pads allowed)
			(copperpour not_allowed)
			(footprints allowed)
		)
		(placement
			(enabled no)
			(sheetname "")
		)
		(fill
			(thermal_gap 0.5)
			(thermal_bridge_width 0.5)
		)
		(polygon
			(pts
				(xy 192.347887 142.95) (xy 192.347887 143.59) (xy 193.897887 143.59) (xy 193.897887 142.95)
			)
		)
	)
	(zone
		(net 0)
		(net_name "")
		(layers "In1.Cu" "In2.Cu")
		(hatch edge 0.5)
		(connect_pads yes
			(clearance 0)
		)
		(min_thickness 0.25)
		(filled_areas_thickness no)
		(keepout
			(tracks not_allowed)
			(vias allowed)
			(pads allowed)
			(copperpour not_allowed)
			(footprints allowed)
		)
		(placement
			(enabled no)
			(sheetname "")
		)
		(fill
			(thermal_gap 0.5)
			(thermal_bridge_width 0.5)
		)
		(polygon
			(pts
				(xy 192.362495 147.775) (xy 192.362495 148.415) (xy 193.912495 148.415) (xy 193.912495 147.775)
			)
		)
	)
	(zone
		(net 0)
		(net_name "")
		(layers "In1.Cu" "In2.Cu")
		(hatch edge 0.5)
		(connect_pads yes
			(clearance 0)
		)
		(min_thickness 0.25)
		(filled_areas_thickness no)
		(keepout
			(tracks not_allowed)
			(vias allowed)
			(pads allowed)
			(copperpour not_allowed)
			(footprints allowed)
		)
		(placement
			(enabled no)
			(sheetname "")
		)
		(fill
			(thermal_gap 0.5)
			(thermal_bridge_width 0.5)
		)
		(polygon
			(pts
				(xy 205.975 91.140856) (xy 205.975 91.780856) (xy 207.525 91.780856) (xy 207.525 91.140856)
			)
		)
	)
	(zone
		(net 0)
		(net_name "")
		(layers "In1.Cu" "In2.Cu")
		(hatch edge 0.5)
		(connect_pads yes
			(clearance 0)
		)
		(min_thickness 0.25)
		(filled_areas_thickness no)
		(keepout
			(tracks not_allowed)
			(vias allowed)
			(pads allowed)
			(copperpour not_allowed)
			(footprints allowed)
		)
		(placement
			(enabled no)
			(sheetname "")
		)
		(fill
			(thermal_gap 0.5)
			(thermal_bridge_width 0.5)
		)
		(polygon
			(pts
				(xy 203.975 87.66) (xy 203.975 88.3) (xy 205.525 88.3) (xy 205.525 87.66)
			)
		)
	)
	(zone
		(net 0)
		(net_name "")
		(layers "In1.Cu" "In2.Cu")
		(hatch edge 0.5)
		(connect_pads yes
			(clearance 0)
		)
		(min_thickness 0.25)
		(filled_areas_thickness no)
		(keepout
			(tracks not_allowed)
			(vias allowed)
			(pads allowed)
			(copperpour not_allowed)
			(footprints allowed)
		)
		(placement
			(enabled no)
			(sheetname "")
		)
		(fill
			(thermal_gap 0.5)
			(thermal_bridge_width 0.5)
		)
		(polygon
			(pts
				(xy 203.975 86.650856) (xy 203.975 87.290856) (xy 205.525 87.290856) (xy 205.525 86.650856)
			)
		)
	)
	(zone
		(net 0)
		(net_name "")
		(layers "In1.Cu" "In2.Cu")
		(hatch edge 0.5)
		(connect_pads yes
			(clearance 0)
		)
		(min_thickness 0.25)
		(filled_areas_thickness no)
		(keepout
			(tracks not_allowed)
			(vias allowed)
			(pads allowed)
			(copperpour not_allowed)
			(footprints allowed)
		)
		(placement
			(enabled no)
			(sheetname "")
		)
		(fill
			(thermal_gap 0.5)
			(thermal_bridge_width 0.5)
		)
		(polygon
			(pts
				(xy 203.975 90.65) (xy 203.975 91.29) (xy 205.525 91.29) (xy 205.525 90.65)
			)
		)
	)
	(zone
		(net 1)
		(net_name "GND")
		(layers "In1.Cu" "In3.Cu" "In6.Cu" "In8.Cu")
		(hatch edge 0.5)
		(connect_pads yes
			(clearance 0.1)
		)
		(min_thickness 0.1)
		(filled_areas_thickness no)
		(fill yes
			(thermal_gap 0.5)
			(thermal_bridge_width 0.5)
		)
		(polygon
			(pts
				(xy 55 50) (xy 245 50) (xy 245 160) (xy 55 160)
			)
		)
	)
	(zone
		(net 297)
		(net_name "/Expansion connector/+3V3_FMC")
		(layer "In2.Cu")
		(hatch edge 0.5)
		(priority 56)
		(connect_pads yes
			(clearance 0.1)
		)
		(min_thickness 0.25)
		(filled_areas_thickness no)
		(fill yes
			(thermal_gap 0.5)
			(thermal_bridge_width 0.5)
		)
		(polygon
			(pts
				(xy 79 123) (xy 80.5 123) (xy 84.5 127) (xy 98.5 127) (xy 98.5 129.5) (xy 79 129.5)
			)
		)
	)
	(zone
		(net 2)
		(net_name "+3V3")
		(layer "In2.Cu")
		(hatch edge 0.5)
		(connect_pads yes
			(clearance 0.1)
		)
		(min_thickness 0.3)
		(filled_areas_thickness no)
		(fill yes
			(thermal_gap 0.5)
			(thermal_bridge_width 0.5)
		)
		(polygon
			(pts
				(xy 56 49.513938) (xy 243.5 49.513938) (xy 243.5 156.013938) (xy 242.5 157.013938) (xy 57 157.013938)
				(xy 54.5 154.513938) (xy 54.5 51.013938)
			)
		)
	)
	(zone
		(net 376)
		(net_name "/USB DP Alt mode/USBC1_VBUS")
		(layer "In4.Cu")
		(hatch edge 0.5)
		(priority 10)
		(connect_pads yes
			(clearance 0.125)
		)
		(min_thickness 0.2)
		(filled_areas_thickness no)
		(fill yes
			(thermal_gap 0.5)
			(thermal_bridge_width 0.5)
		)
		(polygon
			(pts
				(xy 225 92.513938) (xy 229.5 92.513938) (xy 233 92.513938) (xy 234.35 91.563938) (xy 234.35 88.563938)
				(xy 229 83.513938) (xy 229 80.513938) (xy 208 80.513938) (xy 207.2 79.513938) (xy 203.5 79.513938)
				(xy 203.5 83.513938) (xy 207 87.013938) (xy 219.5 87.013938)
			)
		)
	)
	(zone
		(net 12)
		(net_name "SYS_VIN_HV")
		(layer "In4.Cu")
		(hatch edge 0.5)
		(priority 21)
		(connect_pads yes
			(clearance 0.125)
		)
		(min_thickness 0.2)
		(filled_areas_thickness no)
		(fill yes
			(thermal_gap 0.5)
			(thermal_bridge_width 0.5)
		)
		(polygon
			(pts
				(xy 165 108.513938) (xy 150.913795 108.513938) (xy 130.035735 87.963695) (xy 130 69.5) (xy 111.291667 69.513938)
				(xy 102.68 69.513938) (xy 86.199579 85.399563) (xy 83 85.4) (xy 83 64.5) (xy 78.5 64.5) (xy 78.5 52.5)
				(xy 155 52.513938) (xy 156 53.513938) (xy 156 80.013938) (xy 165 89.013938) (xy 165 90.513938)
			)
		)
	)
	(zone
		(net 1)
		(net_name "GND")
		(layer "In4.Cu")
		(hatch edge 0.5)
		(priority 30)
		(connect_pads yes
			(clearance 0.125)
		)
		(min_thickness 0.2)
		(filled_areas_thickness no)
		(fill yes
			(thermal_gap 0.5)
			(thermal_bridge_width 0.5)
		)
		(polygon
			(pts
				(xy 86.199579 85.399563) (xy 102 69.513938) (xy 111 69.513938) (xy 130 69.5) (xy 130.4 88.4) (xy 138.6 96.6)
				(xy 120.5 96.6) (xy 120.5 101.013938) (xy 116.5 105.013938) (xy 99 105.013938) (xy 93.5 110.513938)
				(xy 93.5 113.513938) (xy 92.5 114.513938) (xy 85 114.513938) (xy 83 112.513938) (xy 83 85.4)
			)
		)
	)
	(zone
		(net 176)
		(net_name "/USB Debug, PD/USBC0_VBUS")
		(layer "In4.Cu")
		(hatch edge 0.5)
		(priority 9)
		(connect_pads yes
			(clearance 0.125)
		)
		(min_thickness 0.2)
		(filled_areas_thickness no)
		(fill yes
			(thermal_gap 0.5)
			(thermal_bridge_width 0.5)
		)
		(polygon
			(pts
				(xy 234.5 80.513938) (xy 234.5 73.013938) (xy 203.5 73.013938) (xy 203.5 80.513938)
			)
		)
	)
	(zone
		(net 5)
		(net_name "+5V")
		(layer "In4.Cu")
		(hatch edge 0.5)
		(priority 4)
		(connect_pads yes
			(clearance 0.125)
		)
		(min_thickness 0.2)
		(filled_areas_thickness no)
		(fill yes
			(thermal_gap 0.5)
			(thermal_bridge_width 0.5)
		)
		(polygon
			(pts
				(xy 59.517964 79.113938) (xy 69 79.113938) (xy 69 135.013938) (xy 88.5 135.013938) (xy 97.383469 125.745713)
				(xy 149.2 125.6) (xy 157.2 117.6) (xy 157.2 108.6) (xy 165 108.6) (xy 165 88.98616) (xy 156 80.013938)
				(xy 156 52.013938) (xy 202.2 52.013938) (xy 242 52.013938) (xy 242 153.513938) (xy 239 156.513938)
				(xy 59.491751 156.513938)
			)
		)
	)
	(zone
		(net 3)
		(net_name "VCC_IN")
		(layer "In4.Cu")
		(hatch edge 0.5)
		(priority 20)
		(connect_pads yes
			(clearance 0.125)
		)
		(min_thickness 0.2)
		(filled_areas_thickness no)
		(fill yes
			(thermal_gap 0.5)
			(thermal_bridge_width 0.5)
		)
		(polygon
			(pts
				(xy 215.8 67.3) (xy 216.1 67.6) (xy 216.1 73.013938) (xy 231 73.013938) (xy 231 53.5) (xy 213.3 53.5)
				(xy 213.3 64.4) (xy 213.3 67.1) (xy 213.5 67.3)
			)
		)
	)
	(zone
		(net 11)
		(net_name "+1V8")
		(layer "In4.Cu")
		(hatch edge 0.5)
		(priority 2)
		(connect_pads yes
			(clearance 0.125)
		)
		(min_thickness 0.2)
		(filled_areas_thickness no)
		(fill yes
			(thermal_gap 0.5)
			(thermal_bridge_width 0.5)
		)
		(polygon
			(pts
				(xy 56 49.513938) (xy 167 49.513938) (xy 167 153.513938) (xy 163 157.513938) (xy 58.5 157.513938)
				(xy 56 155.013938)
			)
		)
	)
	(zone
		(net 282)
		(net_name "+1V15")
		(layer "In4.Cu")
		(hatch edge 0.5)
		(priority 14)
		(connect_pads yes
			(clearance 0.125)
		)
		(min_thickness 0.2)
		(filled_areas_thickness no)
		(fill yes
			(thermal_gap 0.5)
			(thermal_bridge_width 0.5)
		)
		(polygon
			(pts
				(xy 194 122.013938) (xy 199.5 122.013938) (xy 203.5 118.013938) (xy 210.5 118.013938) (xy 213.5 121.013938)
				(xy 213.5 127.513938) (xy 213.4 136.6) (xy 203 136.6) (xy 197 130.6) (xy 197 125.513938) (xy 196 124.513938)
				(xy 194 124.513938)
			)
		)
	)
	(zone
		(net 379)
		(net_name "/SFP/SH")
		(layer "In4.Cu")
		(hatch edge 0.5)
		(priority 18)
		(connect_pads yes
			(clearance 0.125)
		)
		(min_thickness 0.2)
		(filled_areas_thickness no)
		(fill yes
			(thermal_gap 0.5)
			(thermal_bridge_width 0.5)
		)
		(polygon
			(pts
				(xy 191.75 136.783938) (xy 234 136.783938) (xy 234 154.013938) (xy 191.75 154.013938)
			)
		)
	)
	(zone
		(net 13)
		(net_name "VCC")
		(layer "In5.Cu")
		(hatch edge 0.5)
		(priority 61)
		(connect_pads
			(clearance 0.1)
		)
		(min_thickness 0.1)
		(filled_areas_thickness no)
		(fill yes
			(thermal_gap 0.5)
			(thermal_bridge_width 0.5)
		)
		(polygon
			(pts
				(xy 97 136) (xy 97 154) (xy 166 154) (xy 166 134.4) (xy 169.814451 134.4) (xy 169.75 123.25) (xy 173 120)
				(xy 182 120) (xy 191 111) (xy 191 80.4) (xy 161.978 80.4) (xy 158 84.378) (xy 158 110) (xy 137 131)
				(xy 125 131) (xy 120 136)
			)
		)
	)
	(zone
		(net 11)
		(net_name "+1V8")
		(layer "In5.Cu")
		(hatch edge 0.5)
		(priority 63)
		(connect_pads
			(clearance 0.1)
		)
		(min_thickness 0.25)
		(filled_areas_thickness no)
		(fill yes
			(thermal_gap 0.5)
			(thermal_bridge_width 0.5)
		)
		(polygon
			(pts
				(xy 150.5 110.5) (xy 155 110.5) (xy 157.5 108) (xy 157.5 94) (xy 150 94) (xy 150 110)
			)
		)
	)
	(zone
		(net 0)
		(net_name "")
		(layers "In7.Cu" "In8.Cu")
		(hatch edge 0.5)
		(connect_pads yes
			(clearance 0)
		)
		(min_thickness 0.25)
		(filled_areas_thickness no)
		(keepout
			(tracks not_allowed)
			(vias allowed)
			(pads allowed)
			(copperpour not_allowed)
			(footprints allowed)
		)
		(placement
			(enabled no)
			(sheetname "")
		)
		(fill
			(thermal_gap 0.5)
			(thermal_bridge_width 0.5)
		)
		(polygon
			(pts
				(xy 109.45 104.809144) (xy 109.45 104.169144) (xy 111 104.169144) (xy 111 104.809144)
			)
		)
	)
	(zone
		(net 0)
		(net_name "")
		(layers "In7.Cu" "In8.Cu")
		(hatch edge 0.5)
		(connect_pads yes
			(clearance 0)
		)
		(min_thickness 0.25)
		(filled_areas_thickness no)
		(keepout
			(tracks not_allowed)
			(vias allowed)
			(pads allowed)
			(copperpour not_allowed)
			(footprints allowed)
		)
		(placement
			(enabled no)
			(sheetname "")
		)
		(fill
			(thermal_gap 0.5)
			(thermal_bridge_width 0.5)
		)
		(polygon
			(pts
				(xy 109.45 101.834144) (xy 109.45 101.194144) (xy 111 101.194144) (xy 111 101.834144)
			)
		)
	)
	(zone
		(net 0)
		(net_name "")
		(layers "In7.Cu" "In8.Cu")
		(hatch edge 0.5)
		(connect_pads yes
			(clearance 0)
		)
		(min_thickness 0.25)
		(filled_areas_thickness no)
		(keepout
			(tracks not_allowed)
			(vias allowed)
			(pads allowed)
			(copperpour not_allowed)
			(footprints allowed)
		)
		(placement
			(enabled no)
			(sheetname "")
		)
		(fill
			(thermal_gap 0.5)
			(thermal_bridge_width 0.5)
		)
		(polygon
			(pts
				(xy 109.45 106.825) (xy 109.45 106.185) (xy 111 106.185) (xy 111 106.825)
			)
		)
	)
	(zone
		(net 0)
		(net_name "")
		(layers "In7.Cu" "In8.Cu")
		(hatch edge 0.5)
		(connect_pads yes
			(clearance 0)
		)
		(min_thickness 0.25)
		(filled_areas_thickness no)
		(keepout
			(tracks not_allowed)
			(vias allowed)
			(pads allowed)
			(copperpour not_allowed)
			(footprints allowed)
		)
		(placement
			(enabled no)
			(sheetname "")
		)
		(fill
			(thermal_gap 0.5)
			(thermal_bridge_width 0.5)
		)
		(polygon
			(pts
				(xy 109.45 98.834144) (xy 109.45 98.194144) (xy 111 98.194144) (xy 111 98.834144)
			)
		)
	)
	(zone
		(net 0)
		(net_name "")
		(layers "In7.Cu" "In8.Cu")
		(hatch edge 0.5)
		(connect_pads yes
			(clearance 0)
		)
		(min_thickness 0.25)
		(filled_areas_thickness no)
		(keepout
			(tracks not_allowed)
			(vias allowed)
			(pads allowed)
			(copperpour not_allowed)
			(footprints allowed)
		)
		(placement
			(enabled no)
			(sheetname "")
		)
		(fill
			(thermal_gap 0.5)
			(thermal_bridge_width 0.5)
		)
		(polygon
			(pts
				(xy 109.45 103.8) (xy 109.45 103.16) (xy 111 103.16) (xy 111 103.8)
			)
		)
	)
	(zone
		(net 0)
		(net_name "")
		(layers "In7.Cu" "In8.Cu")
		(hatch edge 0.5)
		(connect_pads yes
			(clearance 0)
		)
		(min_thickness 0.25)
		(filled_areas_thickness no)
		(keepout
			(tracks not_allowed)
			(vias allowed)
			(pads allowed)
			(copperpour not_allowed)
			(footprints allowed)
		)
		(placement
			(enabled no)
			(sheetname "")
		)
		(fill
			(thermal_gap 0.5)
			(thermal_bridge_width 0.5)
		)
		(polygon
			(pts
				(xy 109.45 107.834144) (xy 109.45 107.194144) (xy 111 107.194144) (xy 111 107.834144)
			)
		)
	)
	(zone
		(net 0)
		(net_name "")
		(layers "In7.Cu" "In8.Cu")
		(hatch edge 0.5)
		(connect_pads yes
			(clearance 0)
		)
		(min_thickness 0.25)
		(filled_areas_thickness no)
		(keepout
			(tracks not_allowed)
			(vias allowed)
			(pads allowed)
			(copperpour not_allowed)
			(footprints allowed)
		)
		(placement
			(enabled no)
			(sheetname "")
		)
		(fill
			(thermal_gap 0.5)
			(thermal_bridge_width 0.5)
		)
		(polygon
			(pts
				(xy 109.45 97.825) (xy 109.45 97.185) (xy 111 97.185) (xy 111 97.825)
			)
		)
	)
	(zone
		(net 0)
		(net_name "")
		(layers "In7.Cu" "In8.Cu")
		(hatch edge 0.5)
		(connect_pads yes
			(clearance 0)
		)
		(min_thickness 0.25)
		(filled_areas_thickness no)
		(keepout
			(tracks not_allowed)
			(vias allowed)
			(pads allowed)
			(copperpour not_allowed)
			(footprints allowed)
		)
		(placement
			(enabled no)
			(sheetname "")
		)
		(fill
			(thermal_gap 0.5)
			(thermal_bridge_width 0.5)
		)
		(polygon
			(pts
				(xy 109.45 100.825) (xy 109.45 100.185) (xy 111 100.185) (xy 111 100.825)
			)
		)
	)
)
